(lib_symbols
	(symbol "BAT54-02V-G3-08_1"
			(pin_numbers
				(hide yes)
			)
			(pin_names
				(hide yes)
			)
			(exclude_from_sim no)
			(in_bom yes)
			(on_board yes)
			(property "Reference" "D"
				(at 21.59 -5.08 0)
				(effects
					(font
						(size 1.27 1.27)
						(thickness 0.15)
					)
					(justify left bottom)
				)
			)
			(property "Value" "BAT54-02V-G3-08"
				(at 21.59 -15.24 0)
				(effects
					(font
						(size 1.27 1.27)
						(thickness 0.15)
					)
					(justify left bottom)
					(hide yes)
				)
			)
			(property "Footprint" "antmicro-footprints:SOD-523"
				(at 21.59 -10.16 0)
				(effects
					(font
						(size 1.27 1.27)
						(thickness 0.15)
					)
					(justify left bottom)
					(hide yes)
				)
			)
			(property "Datasheet" "https://www.vishay.com/docs/85633/bat5402v.pdf"
				(at 21.59 -12.7 0)
				(effects
					(font
						(size 1.27 1.27)
						(thickness 0.15)
					)
					(justify left bottom)
					(hide yes)
				)
			)
			(property "Description" "Small Signal Schottky Diode, Single, 30 V, 200 mA, 800 mV, 600 mA, 125 °C"
				(at 0 0 0)
				(effects
					(font
						(size 1.27 1.27)
					)
					(hide yes)
				)
			)
			(property "MPN" "BAT54-02V-G3-08"
				(at 21.59 -7.62 0)
				(effects
					(font
						(size 1.27 1.27)
						(thickness 0.15)
					)
					(justify left bottom)
				)
			)
			(property "Manufacturer" "Vishay"
				(at 21.59 -17.78 0)
				(effects
					(font
						(size 1.27 1.27)
						(thickness 0.15)
					)
					(justify left bottom)
					(hide yes)
				)
			)
			(property "Author" "Antmicro"
				(at 21.59 -20.32 0)
				(effects
					(font
						(size 1.27 1.27)
						(thickness 0.15)
					)
					(justify left bottom)
					(hide yes)
				)
			)
			(property "License" "Apache-2.0"
				(at 21.59 -22.86 0)
				(effects
					(font
						(size 1.27 1.27)
						(thickness 0.15)
					)
					(justify left bottom)
					(hide yes)
				)
			)
			(property "ki_keywords" "SMT, SEMICONDUCTOR, DIODE, SCHOTTKY"
				(at 0 0 0)
				(effects
					(font
						(size 1.27 1.27)
					)
					(hide yes)
				)
			)
			(symbol "BAT54-02V-G3-08_1_0_1"
				(polyline
					(pts
						(xy 1.905 0) (xy 0.635 0)
					)
					(stroke
						(width 0)
						(type default)
					)
					(fill
						(type none)
					)
				)
				(polyline
					(pts
						(xy 4.445 0) (xy 3.175 0)
					)
					(stroke
						(width 0)
						(type default)
					)
					(fill
						(type none)
					)
				)
			)
			(symbol "BAT54-02V-G3-08_1_1_1"
				(polyline
					(pts
						(xy 1.778 1.016) (xy 1.778 -1.016)
					)
					(stroke
						(width 0.254)
						(type default)
					)
					(fill
						(type none)
					)
				)
				(polyline
					(pts
						(xy 1.778 1.016) (xy 1.397 1.016) (xy 1.397 0.762)
					)
					(stroke
						(width 0.254)
						(type default)
					)
					(fill
						(type none)
					)
				)
				(polyline
					(pts
						(xy 1.778 -1.016) (xy 2.159 -1.016) (xy 2.159 -0.762)
					)
					(stroke
						(width 0.254)
						(type default)
					)
					(fill
						(type none)
					)
				)
				(polyline
					(pts
						(xy 3.302 1.016) (xy 3.302 -1.016) (xy 1.778 0) (xy 3.302 1.016)
					)
					(stroke
						(width 0.254)
						(type default)
					)
					(fill
						(type outline)
					)
				)
				(pin passive line
					(at 0 0 0)
					(length 0.635)
					(name "C"
						(effects
							(font
								(size 1.27 1.27)
							)
						)
					)
					(number "1"
						(effects
							(font
								(size 1.27 1.27)
							)
						)
					)
				)
				(pin passive line
					(at 5.08 0 180)
					(length 0.635)
					(name "A"
						(effects
							(font
								(size 1.27 1.27)
							)
						)
					)
					(number "2"
						(effects
							(font
								(size 1.27 1.27)
							)
						)
					)
				)
			)
		)
	(symbol "ESDA25P35-1U1M_1"
			(pin_numbers
				(hide yes)
			)
			(pin_names
				(hide yes)
			)
			(exclude_from_sim no)
			(in_bom yes)
			(on_board yes)
			(property "Reference" "D"
				(at 24.13 -5.08 0)
				(effects
					(font
						(size 1.27 1.27)
						(thickness 0.15)
					)
					(justify left bottom)
				)
			)
			(property "Value" "ESDA25P35-1U1M"
				(at 24.13 -15.24 0)
				(effects
					(font
						(size 1.27 1.27)
						(thickness 0.15)
					)
					(justify left bottom)
					(hide yes)
				)
			)
			(property "Footprint" "antmicro-footprints:QFN-2L_1.6x1x0.55mm"
				(at 24.13 -10.16 0)
				(effects
					(font
						(size 1.27 1.27)
						(thickness 0.15)
					)
					(justify left bottom)
					(hide yes)
				)
			)
			(property "Datasheet" "https://www.st.com/resource/en/datasheet/esda25p35-1u1m.pdf"
				(at 24.13 -12.7 0)
				(effects
					(font
						(size 1.27 1.27)
						(thickness 0.15)
					)
					(justify left bottom)
					(hide yes)
				)
			)
			(property "Description" "Unidirectional TVS, 30 kV, QFN-2L, 22 V, 195 pF"
				(at 0 0 0)
				(effects
					(font
						(size 1.27 1.27)
					)
					(hide yes)
				)
			)
			(property "MPN" "ESDA25P35-1U1M"
				(at 24.13 -7.62 0)
				(effects
					(font
						(size 1.27 1.27)
						(thickness 0.15)
					)
					(justify left bottom)
				)
			)
			(property "Manufacturer" "STMicroelectronics"
				(at 24.13 -17.78 0)
				(effects
					(font
						(size 1.27 1.27)
						(thickness 0.15)
					)
					(justify left bottom)
					(hide yes)
				)
			)
			(property "Author" "Antmicro"
				(at 24.13 -20.32 0)
				(effects
					(font
						(size 1.27 1.27)
						(thickness 0.15)
					)
					(justify left bottom)
					(hide yes)
				)
			)
			(property "License" "Apache-2.0"
				(at 24.13 -22.86 0)
				(effects
					(font
						(size 1.27 1.27)
						(thickness 0.15)
					)
					(justify left bottom)
					(hide yes)
				)
			)
			(property "ki_keywords" "DIODE, SEMICONDUCTOR, TVS, ESD"
				(at 0 0 0)
				(effects
					(font
						(size 1.27 1.27)
					)
					(hide yes)
				)
			)
			(symbol "ESDA25P35-1U1M_1_0_1"
				(polyline
					(pts
						(xy 1.905 0) (xy 0.635 0)
					)
					(stroke
						(width 0)
						(type default)
					)
					(fill
						(type none)
					)
				)
				(polyline
					(pts
						(xy 4.445 0) (xy 3.175 0)
					)
					(stroke
						(width 0)
						(type default)
					)
					(fill
						(type none)
					)
				)
			)
			(symbol "ESDA25P35-1U1M_1_1_1"
				(polyline
					(pts
						(xy 1.778 1.016) (xy 1.397 1.016)
					)
					(stroke
						(width 0.254)
						(type default)
					)
					(fill
						(type none)
					)
				)
				(polyline
					(pts
						(xy 1.778 1.016) (xy 1.778 -1.016)
					)
					(stroke
						(width 0.254)
						(type default)
					)
					(fill
						(type none)
					)
				)
				(polyline
					(pts
						(xy 2.159 -1.016) (xy 1.778 -1.016)
					)
					(stroke
						(width 0.254)
						(type default)
					)
					(fill
						(type none)
					)
				)
				(polyline
					(pts
						(xy 3.302 1.016) (xy 3.302 -1.016) (xy 1.778 0) (xy 3.302 1.016)
					)
					(stroke
						(width 0.254)
						(type default)
					)
					(fill
						(type outline)
					)
				)
				(pin passive line
					(at 0 0 0)
					(length 0.635)
					(name "C"
						(effects
							(font
								(size 1.27 1.27)
							)
						)
					)
					(number "1"
						(effects
							(font
								(size 1.27 1.27)
							)
						)
					)
				)
				(pin passive line
					(at 5.08 0 180)
					(length 0.635)
					(name "A"
						(effects
							(font
								(size 1.27 1.27)
							)
						)
					)
					(number "2"
						(effects
							(font
								(size 1.27 1.27)
							)
						)
					)
				)
			)
		)
	(symbol "LED_RGY_0606_APTF1616SURKCGKSYKC_1"
			(exclude_from_sim no)
			(in_bom yes)
			(on_board yes)
			(property "Reference" "D"
				(at 30.48 -2.54 0)
				(effects
					(font
						(size 1.27 1.27)
						(thickness 0.15)
					)
					(justify left bottom)
				)
			)
			(property "Value" "LED_RGY_0606_APTF1616SURKCGKSYKC"
				(at 30.48 -7.62 0)
				(effects
					(font
						(size 1.27 1.27)
						(thickness 0.15)
					)
					(justify left bottom)
					(hide yes)
				)
			)
			(property "Footprint" "antmicro-footprints:LED_RGY_1.6x1.6mm_APTF1616"
				(at 30.48 -10.16 0)
				(effects
					(font
						(size 1.27 1.27)
						(thickness 0.15)
					)
					(justify left bottom)
					(hide yes)
				)
			)
			(property "Datasheet" "https://www.kingbrightusa.com/images/catalog/SPEC/APTF1616SURKCGKSYKC.pdf"
				(at 30.48 -12.7 0)
				(effects
					(font
						(size 1.27 1.27)
						(thickness 0.15)
					)
					(justify left bottom)
					(hide yes)
				)
			)
			(property "Description" "LED, RGY, SMD, 0606, R 30 mA, G 30 mA, Y 30 mA, R 1.95 V, G 2.1 V, Y 2 V, Common Anode"
				(at 0 0 0)
				(effects
					(font
						(size 1.27 1.27)
					)
					(hide yes)
				)
			)
			(property "MPN" "APTF1616SURKCGKSYKC"
				(at 30.48 -15.24 0)
				(effects
					(font
						(size 1.27 1.27)
						(thickness 0.15)
					)
					(justify left bottom)
					(hide yes)
				)
			)
			(property "Manufacturer" "Kingbright"
				(at 30.48 -17.78 0)
				(effects
					(font
						(size 1.27 1.27)
						(thickness 0.15)
					)
					(justify left bottom)
					(hide yes)
				)
			)
			(property "Color" "R, G, Y"
				(at 30.48 -5.08 0)
				(effects
					(font
						(size 1.27 1.27)
					)
					(justify left bottom)
				)
			)
			(property "Author" "Antmicro"
				(at 30.48 -20.32 0)
				(effects
					(font
						(size 1.27 1.27)
						(thickness 0.15)
					)
					(justify left bottom)
					(hide yes)
				)
			)
			(property "License" "Apache-2.0"
				(at 30.48 -22.86 0)
				(effects
					(font
						(size 1.27 1.27)
						(thickness 0.15)
					)
					(justify left bottom)
					(hide yes)
				)
			)
			(property "ki_keywords" "SMT, DIODE, SEMICONDUCTOR, LED"
				(at 0 0 0)
				(effects
					(font
						(size 1.27 1.27)
					)
					(hide yes)
				)
			)
			(symbol "LED_RGY_0606_APTF1616SURKCGKSYKC_1_1_1"
				(rectangle
					(start 2.54 7.62)
					(end 16.51 -7.62)
					(stroke
						(width 0.254)
						(type default)
					)
					(fill
						(type background)
					)
				)
				(polyline
					(pts
						(xy 6.35 0) (xy 5.08 0)
					)
					(stroke
						(width 0.254)
						(type default)
					)
					(fill
						(type none)
					)
				)
				(polyline
					(pts
						(xy 6.35 0) (xy 6.35 -3.81) (xy 8.89 -3.81)
					)
					(stroke
						(width 0.254)
						(type default)
					)
					(fill
						(type none)
					)
				)
				(polyline
					(pts
						(xy 8.763 4.826) (xy 8.763 2.794) (xy 10.287 3.81) (xy 8.763 4.826)
					)
					(stroke
						(width 0.254)
						(type default)
					)
					(fill
						(type outline)
					)
				)
				(polyline
					(pts
						(xy 8.763 1.016) (xy 8.763 -1.016) (xy 10.287 0) (xy 8.763 1.016)
					)
					(stroke
						(width 0.254)
						(type default)
					)
					(fill
						(type outline)
					)
				)
				(polyline
					(pts
						(xy 8.763 -2.794) (xy 8.763 -4.826) (xy 10.287 -3.81) (xy 8.763 -2.794)
					)
					(stroke
						(width 0.254)
						(type default)
					)
					(fill
						(type outline)
					)
				)
				(polyline
					(pts
						(xy 8.89 0) (xy 6.35 0) (xy 6.35 3.81) (xy 8.89 3.81)
					)
					(stroke
						(width 0.254)
						(type default)
					)
					(fill
						(type none)
					)
				)
				(polyline
					(pts
						(xy 9.906 6.35) (xy 9.906 5.842) (xy 9.906 6.35) (xy 9.398 6.35) (xy 9.906 6.35) (xy 9.017 5.461)
					)
					(stroke
						(width 0.254)
						(type default)
					)
					(fill
						(type none)
					)
				)
				(polyline
					(pts
						(xy 9.906 2.54) (xy 9.906 2.032) (xy 9.906 2.54) (xy 9.398 2.54) (xy 9.906 2.54) (xy 9.017 1.651)
					)
					(stroke
						(width 0.254)
						(type default)
					)
					(fill
						(type none)
					)
				)
				(polyline
					(pts
						(xy 9.906 -1.27) (xy 9.906 -1.778) (xy 9.906 -1.27) (xy 9.398 -1.27) (xy 9.906 -1.27) (xy 9.017 -2.159)
					)
					(stroke
						(width 0.254)
						(type default)
					)
					(fill
						(type none)
					)
				)
				(polyline
					(pts
						(xy 10.287 4.826) (xy 10.287 2.794)
					)
					(stroke
						(width 0.254)
						(type default)
					)
					(fill
						(type none)
					)
				)
				(polyline
					(pts
						(xy 10.287 1.016) (xy 10.287 -1.016)
					)
					(stroke
						(width 0.254)
						(type default)
					)
					(fill
						(type none)
					)
				)
				(polyline
					(pts
						(xy 10.287 -2.794) (xy 10.287 -4.826)
					)
					(stroke
						(width 0.254)
						(type default)
					)
					(fill
						(type none)
					)
				)
				(polyline
					(pts
						(xy 10.922 6.096) (xy 10.922 5.588) (xy 10.922 6.096) (xy 10.414 6.096) (xy 10.922 6.096) (xy 9.906 5.08)
					)
					(stroke
						(width 0.254)
						(type default)
					)
					(fill
						(type none)
					)
				)
				(polyline
					(pts
						(xy 10.922 2.286) (xy 10.922 1.778) (xy 10.922 2.286) (xy 10.414 2.286) (xy 10.922 2.286) (xy 9.906 1.27)
					)
					(stroke
						(width 0.254)
						(type default)
					)
					(fill
						(type none)
					)
				)
				(polyline
					(pts
						(xy 10.922 -1.524) (xy 10.922 -2.032) (xy 10.922 -1.524) (xy 10.414 -1.524) (xy 10.922 -1.524)
						(xy 9.906 -2.54)
					)
					(stroke
						(width 0.254)
						(type default)
					)
					(fill
						(type none)
					)
				)
				(polyline
					(pts
						(xy 12.7 3.81) (xy 10.16 3.81)
					)
					(stroke
						(width 0.254)
						(type default)
					)
					(fill
						(type none)
					)
				)
				(polyline
					(pts
						(xy 12.7 0) (xy 10.16 0)
					)
					(stroke
						(width 0.254)
						(type default)
					)
					(fill
						(type none)
					)
				)
				(polyline
					(pts
						(xy 12.7 -3.81) (xy 10.16 -3.81)
					)
					(stroke
						(width 0.254)
						(type default)
					)
					(fill
						(type none)
					)
				)
				(pin passive line
					(at 0 0 0)
					(length 2.54)
					(name "A"
						(effects
							(font
								(size 1.27 1.27)
							)
						)
					)
					(number "1"
						(effects
							(font
								(size 1.27 1.27)
							)
						)
					)
				)
				(pin passive line
					(at 19.05 3.81 180)
					(length 2.54)
					(name "C_{R}"
						(effects
							(font
								(size 1.27 1.27)
							)
						)
					)
					(number "2"
						(effects
							(font
								(size 1.27 1.27)
							)
						)
					)
				)
				(pin passive line
					(at 19.05 0 180)
					(length 2.54)
					(name "C_{G}"
						(effects
							(font
								(size 1.27 1.27)
							)
						)
					)
					(number "3"
						(effects
							(font
								(size 1.27 1.27)
							)
						)
					)
				)
				(pin passive line
					(at 19.05 -3.81 180)
					(length 2.54)
					(name "C_{Y}"
						(effects
							(font
								(size 1.27 1.27)
							)
						)
					)
					(number "4"
						(effects
							(font
								(size 1.27 1.27)
							)
						)
					)
				)
			)
		)
	(symbol "MAX16150A_SOT_1"
			(exclude_from_sim no)
			(in_bom yes)
			(on_board yes)
			(property "Reference" "U"
				(at 31.75 -3.81 0)
				(effects
					(font
						(size 1.27 1.27)
						(thickness 0.15)
					)
					(justify left bottom)
				)
			)
			(property "Value" "MAX16150A_SOT"
				(at 31.75 -6.35 0)
				(effects
					(font
						(size 1.27 1.27)
						(thickness 0.15)
					)
					(justify left bottom)
					(hide yes)
				)
			)
			(property "Footprint" "antmicro-footprints:SOT-23-6"
				(at 31.75 -8.89 0)
				(effects
					(font
						(size 1.27 1.27)
						(thickness 0.15)
					)
					(justify left bottom)
					(hide yes)
				)
			)
			(property "Datasheet" "https://datasheets.maximintegrated.com/en/ds/MAX16150.pdf"
				(at 31.75 -11.43 0)
				(effects
					(font
						(size 1.27 1.27)
						(thickness 0.15)
					)
					(justify left bottom)
					(hide yes)
				)
			)
			(property "Description" "Pushbutton On/Off Controller, Latched Output, 1.3 to 5.5 V Supply, 50 ms Debounce Time, SOT-23-6"
				(at 0 0 0)
				(effects
					(font
						(size 1.27 1.27)
					)
					(hide yes)
				)
			)
			(property "Manufacturer" "Maxim Integrated Products"
				(at 31.75 -13.97 0)
				(effects
					(font
						(size 1.27 1.27)
						(thickness 0.15)
					)
					(justify left bottom)
					(hide yes)
				)
			)
			(property "MPN" "MAX16150AUT+T"
				(at 31.75 -16.51 0)
				(effects
					(font
						(size 1.27 1.27)
						(thickness 0.15)
					)
					(justify left bottom)
				)
			)
			(property "License" "Apache-2.0"
				(at 31.75 -19.05 0)
				(effects
					(font
						(size 1.27 1.27)
						(thickness 0.15)
					)
					(justify left bottom)
					(hide yes)
				)
			)
			(property "Author" "Antmicro"
				(at 31.75 -21.59 0)
				(effects
					(font
						(size 1.27 1.27)
						(thickness 0.15)
					)
					(justify left bottom)
					(hide yes)
				)
			)
			(property "ki_keywords" "SMT, PMIC, IC, CONTROLLER, ESD"
				(at 0 0 0)
				(effects
					(font
						(size 1.27 1.27)
					)
					(hide yes)
				)
			)
			(symbol "MAX16150A_SOT_1_0_0"
				(text "CTRL"
					(at 8.89 -0.254 0)
					(effects
						(font
							(size 0.635 0.635)
						)
					)
				)
			)
			(symbol "MAX16150A_SOT_1_1_1"
				(rectangle
					(start 2.54 2.54)
					(end 15.24 -7.62)
					(stroke
						(width 0.254)
						(type default)
					)
					(fill
						(type background)
					)
				)
				(polyline
					(pts
						(xy 6.35 -3.429) (xy 7.112 -3.429)
					)
					(stroke
						(width 0.254)
						(type default)
					)
					(fill
						(type background)
					)
				)
				(polyline
					(pts
						(xy 7.112 -2.54) (xy 10.668 -2.54)
					)
					(stroke
						(width 0.254)
						(type default)
					)
					(fill
						(type background)
					)
				)
				(circle
					(center 7.366 -3.429)
					(radius 0.254)
					(stroke
						(width 0.254)
						(type default)
					)
					(fill
						(type outline)
					)
				)
				(polyline
					(pts
						(xy 7.874 -1.016) (xy 9.906 -1.016)
					)
					(stroke
						(width 0.254)
						(type default)
					)
					(fill
						(type background)
					)
				)
				(polyline
					(pts
						(xy 8.89 -2.54) (xy 8.89 -1.016)
					)
					(stroke
						(width 0.254)
						(type default)
					)
					(fill
						(type background)
					)
				)
				(circle
					(center 10.414 -3.429)
					(radius 0.254)
					(stroke
						(width 0.254)
						(type default)
					)
					(fill
						(type outline)
					)
				)
				(polyline
					(pts
						(xy 11.43 -3.429) (xy 10.668 -3.429)
					)
					(stroke
						(width 0.254)
						(type default)
					)
					(fill
						(type background)
					)
				)
				(pin power_in line
					(at 0 0 0)
					(length 2.54)
					(name "VCC"
						(effects
							(font
								(size 1.27 1.27)
							)
						)
					)
					(number "3"
						(effects
							(font
								(size 1.27 1.27)
							)
						)
					)
				)
				(pin input line
					(at 0 -2.54 0)
					(length 2.54)
					(name "~{CLR}"
						(effects
							(font
								(size 1.27 1.27)
							)
						)
					)
					(number "6"
						(effects
							(font
								(size 1.27 1.27)
							)
						)
					)
				)
				(pin input line
					(at 0 -5.08 0)
					(length 2.54)
					(name "~{PB_IN}"
						(effects
							(font
								(size 1.27 1.27)
							)
						)
					)
					(number "1"
						(effects
							(font
								(size 1.27 1.27)
							)
						)
					)
				)
				(pin output line
					(at 17.78 0 180)
					(length 2.54)
					(name "OUT"
						(effects
							(font
								(size 1.27 1.27)
							)
						)
					)
					(number "4"
						(effects
							(font
								(size 1.27 1.27)
							)
						)
					)
				)
				(pin output line
					(at 17.78 -2.54 180)
					(length 2.54)
					(name "~{INT}"
						(effects
							(font
								(size 1.27 1.27)
							)
						)
					)
					(number "5"
						(effects
							(font
								(size 1.27 1.27)
							)
						)
					)
				)
				(pin power_in line
					(at 17.78 -5.08 180)
					(length 2.54)
					(name "GND"
						(effects
							(font
								(size 1.27 1.27)
							)
						)
					)
					(number "2"
						(effects
							(font
								(size 1.27 1.27)
							)
						)
					)
				)
			)
		)
	(symbol "PWR_FLAG_1"
			(power)
			(pin_numbers
				(hide yes)
			)
			(pin_names
				(offset 0)
				(hide yes)
			)
			(exclude_from_sim no)
			(in_bom yes)
			(on_board yes)
			(property "Reference" "#FLG"
				(at 0 1.905 0)
				(effects
					(font
						(size 1.27 1.27)
					)
					(hide yes)
				)
			)
			(property "Value" "PWR_FLAG"
				(at 0 3.81 0)
				(effects
					(font
						(size 1.27 1.27)
					)
				)
			)
			(property "Footprint" ""
				(at 0 0 0)
				(effects
					(font
						(size 1.27 1.27)
					)
					(hide yes)
				)
			)
			(property "Datasheet" ""
				(at 0 0 0)
				(effects
					(font
						(size 1.27 1.27)
					)
					(hide yes)
				)
			)
			(property "Description" ""
				(at 0 -2.54 0)
				(effects
					(font
						(size 1.27 1.27)
					)
					(justify left bottom)
					(hide yes)
				)
			)
			(symbol "PWR_FLAG_1_0_0"
				(pin power_out line
					(at 0 0 90)
					(length 0)
					(name "pwr"
						(effects
							(font
								(size 1.27 1.27)
							)
						)
					)
					(number "1"
						(effects
							(font
								(size 1.27 1.27)
							)
						)
					)
				)
			)
			(symbol "PWR_FLAG_1_0_1"
				(polyline
					(pts
						(xy 0 0) (xy 0 1.27) (xy -1.016 1.905) (xy 0 2.54) (xy 1.016 1.905) (xy 0 1.27)
					)
					(stroke
						(width 0)
						(type default)
					)
					(fill
						(type none)
					)
				)
			)
		)
	(symbol "REF3012AIDBZT_1"
			(exclude_from_sim no)
			(in_bom yes)
			(on_board yes)
			(property "Reference" "U"
				(at 33.02 -6.35 0)
				(effects
					(font
						(size 1.27 1.27)
						(thickness 0.15)
					)
					(justify left bottom)
				)
			)
			(property "Value" "REF3012AIDBZT"
				(at 33.02 -15.24 0)
				(effects
					(font
						(size 1.27 1.27)
						(thickness 0.15)
					)
					(justify left bottom)
					(hide yes)
				)
			)
			(property "Footprint" "antmicro-footprints:SOT-23-3"
				(at 33.02 -10.16 0)
				(effects
					(font
						(size 1.27 1.27)
						(thickness 0.15)
					)
					(justify left bottom)
					(hide yes)
				)
			)
			(property "Datasheet" "https://www.ti.com/lit/gpn/REF3012"
				(at 33.02 -12.7 0)
				(effects
					(font
						(size 1.27 1.27)
						(thickness 0.15)
					)
					(justify left bottom)
					(hide yes)
				)
			)
			(property "Description" "Voltage Reference, Low Power, Low Dropout, Series"
				(at 0 0 0)
				(effects
					(font
						(size 1.27 1.27)
					)
					(hide yes)
				)
			)
			(property "MPN" "REF3012AIDBZT"
				(at 33.02 -8.255 0)
				(effects
					(font
						(size 1.27 1.27)
						(thickness 0.15)
					)
					(justify left bottom)
				)
			)
			(property "Manufacturer" "Texas Instruments"
				(at 33.02 -17.78 0)
				(effects
					(font
						(size 1.27 1.27)
						(thickness 0.15)
					)
					(justify left bottom)
					(hide yes)
				)
			)
			(property "Author" "Antmicro"
				(at 33.02 -20.32 0)
				(effects
					(font
						(size 1.27 1.27)
						(thickness 0.15)
					)
					(justify left bottom)
					(hide yes)
				)
			)
			(property "License" "Apache-2.0"
				(at 33.02 -22.86 0)
				(effects
					(font
						(size 1.27 1.27)
						(thickness 0.15)
					)
					(justify left bottom)
					(hide yes)
				)
			)
			(property "ki_keywords" "SMT, PMIC, IC, POWER, SWITCH, DRIVER"
				(at 0 0 0)
				(effects
					(font
						(size 1.27 1.27)
					)
					(hide yes)
				)
			)
			(symbol "REF3012AIDBZT_1_1_1"
				(rectangle
					(start 2.54 1.27)
					(end 15.24 -5.08)
					(stroke
						(width 0.254)
						(type default)
					)
					(fill
						(type background)
					)
				)
				(pin power_in line
					(at 0 0 0)
					(length 2.54)
					(name "IN"
						(effects
							(font
								(size 1.27 1.27)
							)
						)
					)
					(number "1"
						(effects
							(font
								(size 1.27 1.27)
							)
						)
					)
				)
				(pin passive line
					(at 0 -3.81 0)
					(length 2.54)
					(name "GND"
						(effects
							(font
								(size 1.27 1.27)
							)
						)
					)
					(number "3"
						(effects
							(font
								(size 1.27 1.27)
							)
						)
					)
				)
				(pin output line
					(at 17.78 0 180)
					(length 2.54)
					(name "OUT"
						(effects
							(font
								(size 1.27 1.27)
							)
						)
					)
					(number "2"
						(effects
							(font
								(size 1.27 1.27)
							)
						)
					)
				)
			)
		)
	(symbol "SN74HC595B_1"
			(exclude_from_sim no)
			(in_bom yes)
			(on_board yes)
			(property "Reference" "U"
				(at 35.56 -5.08 0)
				(effects
					(font
						(size 1.27 1.27)
						(thickness 0.15)
					)
					(justify left bottom)
				)
			)
			(property "Value" "SN74HC595B"
				(at 35.56 -17.78 0)
				(effects
					(font
						(size 1.27 1.27)
						(thickness 0.15)
					)
					(justify left bottom)
					(hide yes)
				)
			)
			(property "Footprint" "antmicro-footprints:X1QFN-16-1EP_2.5x2.5mm"
				(at 35.56 -10.16 0)
				(effects
					(font
						(size 1.27 1.27)
						(thickness 0.15)
					)
					(justify left bottom)
					(hide yes)
				)
			)
			(property "Datasheet" "https://www.ti.com/general/docs/suppproductinfo.tsp?distId=26&gotoUrl=https://www.ti.com/lit/gpn/sn74hc595b"
				(at 35.56 -12.7 0)
				(effects
					(font
						(size 1.27 1.27)
						(thickness 0.15)
					)
					(justify left bottom)
					(hide yes)
				)
			)
			(property "Description" "Shift Register, 74HC595, Serial to Parallel, 1 Element, 8 bit, X1QFN, 16 Pins"
				(at 0 0 0)
				(effects
					(font
						(size 1.27 1.27)
					)
					(hide yes)
				)
			)
			(property "MPN" "SN74HC595BRWNR"
				(at 35.56 -7.62 0)
				(effects
					(font
						(size 1.27 1.27)
						(thickness 0.15)
					)
					(justify left bottom)
				)
			)
			(property "Manufacturer" "Texas Instruments"
				(at 35.56 -15.24 0)
				(effects
					(font
						(size 1.27 1.27)
						(thickness 0.15)
					)
					(justify left bottom)
					(hide yes)
				)
			)
			(property "Author" "Antmicro"
				(at 35.56 -20.32 0)
				(effects
					(font
						(size 1.27 1.27)
						(thickness 0.15)
					)
					(justify left bottom)
					(hide yes)
				)
			)
			(property "License" "Apache-2.0"
				(at 35.56 -22.86 0)
				(effects
					(font
						(size 1.27 1.27)
						(thickness 0.15)
					)
					(justify left bottom)
					(hide yes)
				)
			)
			(property "ki_keywords" "SMT, LOGIC, IC, LEVEL-SHIFTER, VOLTAGE"
				(at 0 0 0)
				(effects
					(font
						(size 1.27 1.27)
					)
					(hide yes)
				)
			)
			(symbol "SN74HC595B_1_1_1"
				(rectangle
					(start 2.54 2.54)
					(end 17.78 -22.86)
					(stroke
						(width 0.254)
						(type default)
					)
					(fill
						(type background)
					)
				)
				(pin power_in line
					(at 0 0 0)
					(length 2.54)
					(name "VCC"
						(effects
							(font
								(size 1.27 1.27)
							)
						)
					)
					(number "16"
						(effects
							(font
								(size 1.27 1.27)
							)
						)
					)
				)
				(pin input line
					(at 0 -5.08 0)
					(length 2.54)
					(name "~{OE}"
						(effects
							(font
								(size 1.27 1.27)
							)
						)
					)
					(number "13"
						(effects
							(font
								(size 1.27 1.27)
							)
						)
					)
				)
				(pin input line
					(at 0 -7.62 0)
					(length 2.54)
					(name "~{SRCLR}"
						(effects
							(font
								(size 1.27 1.27)
							)
						)
					)
					(number "10"
						(effects
							(font
								(size 1.27 1.27)
							)
						)
					)
				)
				(pin input line
					(at 0 -10.16 0)
					(length 2.54)
					(name "SRCLK"
						(effects
							(font
								(size 1.27 1.27)
							)
						)
					)
					(number "11"
						(effects
							(font
								(size 1.27 1.27)
							)
						)
					)
				)
				(pin input line
					(at 0 -12.7 0)
					(length 2.54)
					(name "RCLK"
						(effects
							(font
								(size 1.27 1.27)
							)
						)
					)
					(number "12"
						(effects
							(font
								(size 1.27 1.27)
							)
						)
					)
				)
				(pin input line
					(at 0 -15.24 0)
					(length 2.54)
					(name "SER"
						(effects
							(font
								(size 1.27 1.27)
							)
						)
					)
					(number "14"
						(effects
							(font
								(size 1.27 1.27)
							)
						)
					)
				)
				(pin power_in line
					(at 0 -20.32 0)
					(length 2.54)
					(name "GND"
						(effects
							(font
								(size 1.27 1.27)
							)
						)
					)
					(number "8"
						(effects
							(font
								(size 1.27 1.27)
							)
						)
					)
				)
				(pin no_connect line
					(at 2.54 -17.78 0)
					(length 2.54)
					(hide yes)
					(name "EP"
						(effects
							(font
								(size 1.27 1.27)
							)
						)
					)
					(number "17"
						(effects
							(font
								(size 1.27 1.27)
							)
						)
					)
				)
				(pin output line
					(at 20.32 0 180)
					(length 2.54)
					(name "QA"
						(effects
							(font
								(size 1.27 1.27)
							)
						)
					)
					(number "15"
						(effects
							(font
								(size 1.27 1.27)
							)
						)
					)
				)
				(pin output line
					(at 20.32 -2.54 180)
					(length 2.54)
					(name "QB"
						(effects
							(font
								(size 1.27 1.27)
							)
						)
					)
					(number "1"
						(effects
							(font
								(size 1.27 1.27)
							)
						)
					)
				)
				(pin output line
					(at 20.32 -5.08 180)
					(length 2.54)
					(name "QC"
						(effects
							(font
								(size 1.27 1.27)
							)
						)
					)
					(number "2"
						(effects
							(font
								(size 1.27 1.27)
							)
						)
					)
				)
				(pin output line
					(at 20.32 -7.62 180)
					(length 2.54)
					(name "QD"
						(effects
							(font
								(size 1.27 1.27)
							)
						)
					)
					(number "3"
						(effects
							(font
								(size 1.27 1.27)
							)
						)
					)
				)
				(pin output line
					(at 20.32 -10.16 180)
					(length 2.54)
					(name "QE"
						(effects
							(font
								(size 1.27 1.27)
							)
						)
					)
					(number "4"
						(effects
							(font
								(size 1.27 1.27)
							)
						)
					)
				)
				(pin output line
					(at 20.32 -12.7 180)
					(length 2.54)
					(name "QF"
						(effects
							(font
								(size 1.27 1.27)
							)
						)
					)
					(number "5"
						(effects
							(font
								(size 1.27 1.27)
							)
						)
					)
				)
				(pin output line
					(at 20.32 -15.24 180)
					(length 2.54)
					(name "QG"
						(effects
							(font
								(size 1.27 1.27)
							)
						)
					)
					(number "6"
						(effects
							(font
								(size 1.27 1.27)
							)
						)
					)
				)
				(pin output line
					(at 20.32 -17.78 180)
					(length 2.54)
					(name "QH"
						(effects
							(font
								(size 1.27 1.27)
							)
						)
					)
					(number "7"
						(effects
							(font
								(size 1.27 1.27)
							)
						)
					)
				)
				(pin output line
					(at 20.32 -20.32 180)
					(length 2.54)
					(name "QH'"
						(effects
							(font
								(size 1.27 1.27)
							)
						)
					)
					(number "9"
						(effects
							(font
								(size 1.27 1.27)
							)
						)
					)
				)
			)
		)
	(symbol "XCAU25P-2FFVB676I_1"
			(exclude_from_sim no)
			(in_bom yes)
			(on_board yes)
			(property "Reference" "U"
				(at 63.5 0 0)
				(effects
					(font
						(size 1.27 1.27)
						(thickness 0.15)
					)
					(justify left bottom)
				)
			)
			(property "Value" "XCAU25P-2FFVB676I"
				(at 63.5 -5.08 0)
				(effects
					(font
						(size 1.27 1.27)
						(thickness 0.15)
					)
					(justify left bottom)
					(hide yes)
				)
			)
			(property "Footprint" "antmicro-footprints:BGA-676_27x27mm_Layout26x26_P1x1mm_FFVB676"
				(at 63.5 -7.62 0)
				(effects
					(font
						(size 1.27 1.27)
						(thickness 0.15)
					)
					(justify left bottom)
					(hide yes)
				)
			)
			(property "Datasheet" "https://docs.xilinx.com/viewer/book-attachment/2PXOpPtpaABIt0fkzeBLnw/hvbsEUaOT0OxFhln7VEVyA"
				(at 63.5 -10.16 0)
				(effects
					(font
						(size 1.27 1.27)
						(thickness 0.15)
					)
					(justify left bottom)
					(hide yes)
				)
			)
			(property "Description" "Artix UltraScale+ Field Programmable Gate Array"
				(at 0 0 0)
				(effects
					(font
						(size 1.27 1.27)
					)
					(hide yes)
				)
			)
			(property "MPN" "XCAU25P-2FFVB676I"
				(at 63.5 -2.54 0)
				(effects
					(font
						(size 1.27 1.27)
						(thickness 0.15)
					)
					(justify left bottom)
				)
			)
			(property "Manufacturer" "AMD-Xilinx"
				(at 63.5 -12.7 0)
				(effects
					(font
						(size 1.27 1.27)
						(thickness 0.15)
					)
					(justify left bottom)
					(hide yes)
				)
			)
			(property "Author" "Antmicro"
				(at 63.5 -15.24 0)
				(effects
					(font
						(size 1.27 1.27)
						(thickness 0.15)
					)
					(justify left bottom)
					(hide yes)
				)
			)
			(property "License" "Apache-2.0"
				(at 63.5 -17.78 0)
				(effects
					(font
						(size 1.27 1.27)
						(thickness 0.15)
					)
					(justify left bottom)
					(hide yes)
				)
			)
			(property "ki_locked" ""
				(at 0 0 0)
				(effects
					(font
						(size 1.27 1.27)
					)
				)
			)
			(property "ki_keywords" "FPGA, LVDS, MIPI, CMOS, BGA, ETHERNET, VIDEO, DSP, BRIDGE"
				(at 0 0 0)
				(effects
					(font
						(size 1.27 1.27)
					)
					(hide yes)
				)
			)
			(symbol "XCAU25P-2FFVB676I_1_1_1"
				(rectangle
					(start 5.08 2.54)
					(end 25.4 -87.63)
					(stroke
						(width 0.254)
						(type default)
					)
					(fill
						(type background)
					)
				)
				(polyline
					(pts
						(xy 15.24 -3.81) (xy 22.86 -3.81) (xy 22.86 -83.82) (xy 15.24 -83.82)
					)
					(stroke
						(width 0.254)
						(type default)
					)
					(fill
						(type background)
					)
				)
				(text "CFG"
					(at 15.24 -3.81 0)
					(effects
						(font
							(size 1.27 1.27)
							(thickness 0.15)
						)
						(justify left bottom)
					)
				)
				(text ""
					(at 50.8 -31.75 0)
					(effects
						(font
							(size 1.27 1.27)
							(thickness 0.15)
						)
						(justify left bottom)
					)
				)
				(text ""
					(at 50.8 -31.75 0)
					(effects
						(font
							(size 1.27 1.27)
							(thickness 0.15)
						)
						(justify left bottom)
					)
				)
				(pin power_in line
					(at 0 0 0)
					(length 5.08)
					(name "VCCO_0"
						(effects
							(font
								(size 1.27 1.27)
							)
						)
					)
					(number "AA11"
						(effects
							(font
								(size 1.27 1.27)
							)
						)
					)
				)
				(pin passive line
					(at 0 0 0)
					(length 5.08)
					(hide yes)
					(name "VCCO_0"
						(effects
							(font
								(size 1.27 1.27)
							)
						)
					)
					(number "AD12"
						(effects
							(font
								(size 1.27 1.27)
							)
						)
					)
				)
				(pin bidirectional line
					(at 0 -5.08 0)
					(length 5.08)
					(name "DONE_0"
						(effects
							(font
								(size 1.27 1.27)
							)
						)
					)
					(number "AB11"
						(effects
							(font
								(size 1.27 1.27)
							)
						)
					)
				)
				(pin bidirectional line
					(at 0 -7.62 0)
					(length 5.08)
					(name "INIT_B_0"
						(effects
							(font
								(size 1.27 1.27)
							)
						)
					)
					(number "W10"
						(effects
							(font
								(size 1.27 1.27)
							)
						)
					)
				)
				(pin input line
					(at 0 -10.16 0)
					(length 5.08)
					(name "PROGRAM_B_0"
						(effects
							(font
								(size 1.27 1.27)
							)
						)
					)
					(number "AB9"
						(effects
							(font
								(size 1.27 1.27)
							)
						)
					)
				)
				(pin bidirectional line
					(at 0 -12.7 0)
					(length 5.08)
					(name "RDWR_FCS_B_0"
						(effects
							(font
								(size 1.27 1.27)
							)
						)
					)
					(number "AA12"
						(effects
							(font
								(size 1.27 1.27)
							)
						)
					)
				)
				(pin bidirectional line
					(at 0 -17.78 0)
					(length 5.08)
					(name "CCLK_0"
						(effects
							(font
								(size 1.27 1.27)
							)
						)
					)
					(number "Y11"
						(effects
							(font
								(size 1.27 1.27)
							)
						)
					)
				)
				(pin input line
					(at 0 -20.32 0)
					(length 5.08)
					(name "M0_0"
						(effects
							(font
								(size 1.27 1.27)
							)
						)
					)
					(number "AA10"
						(effects
							(font
								(size 1.27 1.27)
							)
						)
					)
				)
				(pin input line
					(at 0 -22.86 0)
					(length 5.08)
					(name "M1_0"
						(effects
							(font
								(size 1.27 1.27)
							)
						)
					)
					(number "AA9"
						(effects
							(font
								(size 1.27 1.27)
							)
						)
					)
				)
				(pin input line
					(at 0 -25.4 0)
					(length 5.08)
					(name "M2_0"
						(effects
							(font
								(size 1.27 1.27)
							)
						)
					)
					(number "AF12"
						(effects
							(font
								(size 1.27 1.27)
							)
						)
					)
				)
				(pin input line
					(at 0 -30.48 0)
					(length 5.08)
					(name "TCK_0"
						(effects
							(font
								(size 1.27 1.27)
							)
						)
					)
					(number "AE12"
						(effects
							(font
								(size 1.27 1.27)
							)
						)
					)
				)
				(pin input line
					(at 0 -33.02 0)
					(length 5.08)
					(name "TDI_0"
						(effects
							(font
								(size 1.27 1.27)
							)
						)
					)
					(number "AB12"
						(effects
							(font
								(size 1.27 1.27)
							)
						)
					)
				)
				(pin output line
					(at 0 -35.56 0)
					(length 5.08)
					(name "TDO_0"
						(effects
							(font
								(size 1.27 1.27)
							)
						)
					)
					(number "Y10"
						(effects
							(font
								(size 1.27 1.27)
							)
						)
					)
				)
				(pin input line
					(at 0 -38.1 0)
					(length 5.08)
					(name "TMS_0"
						(effects
							(font
								(size 1.27 1.27)
							)
						)
					)
					(number "AB10"
						(effects
							(font
								(size 1.27 1.27)
							)
						)
					)
				)
				(pin bidirectional line
					(at 0 -43.18 0)
					(length 5.08)
					(name "D00_MOSI_0"
						(effects
							(font
								(size 1.27 1.27)
							)
						)
					)
					(number "AD11"
						(effects
							(font
								(size 1.27 1.27)
							)
						)
					)
				)
				(pin bidirectional line
					(at 0 -45.72 0)
					(length 5.08)
					(name "D01_DIN_0"
						(effects
							(font
								(size 1.27 1.27)
							)
						)
					)
					(number "AC12"
						(effects
							(font
								(size 1.27 1.27)
							)
						)
					)
				)
				(pin bidirectional line
					(at 0 -48.26 0)
					(length 5.08)
					(name "D02_0"
						(effects
							(font
								(size 1.27 1.27)
							)
						)
					)
					(number "AC11"
						(effects
							(font
								(size 1.27 1.27)
							)
						)
					)
				)
				(pin bidirectional line
					(at 0 -50.8 0)
					(length 5.08)
					(name "D03_0"
						(effects
							(font
								(size 1.27 1.27)
							)
						)
					)
					(number "AE11"
						(effects
							(font
								(size 1.27 1.27)
							)
						)
					)
				)
				(pin input line
					(at 0 -55.88 0)
					(length 5.08)
					(name "VP"
						(effects
							(font
								(size 1.27 1.27)
							)
						)
					)
					(number "P14"
						(effects
							(font
								(size 1.27 1.27)
							)
						)
					)
				)
				(pin input line
					(at 0 -58.42 0)
					(length 5.08)
					(name "VN"
						(effects
							(font
								(size 1.27 1.27)
							)
						)
					)
					(number "R13"
						(effects
							(font
								(size 1.27 1.27)
							)
						)
					)
				)
				(pin input line
					(at 0 -63.5 0)
					(length 5.08)
					(name "VREFP"
						(effects
							(font
								(size 1.27 1.27)
							)
						)
					)
					(number "R14"
						(effects
							(font
								(size 1.27 1.27)
							)
						)
					)
				)
				(pin input line
					(at 0 -66.04 0)
					(length 5.08)
					(name "VREFN"
						(effects
							(font
								(size 1.27 1.27)
							)
						)
					)
					(number "P13"
						(effects
							(font
								(size 1.27 1.27)
							)
						)
					)
				)
				(pin passive line
					(at 0 -71.12 0)
					(length 5.08)
					(name "DXP"
						(effects
							(font
								(size 1.27 1.27)
							)
						)
					)
					(number "T14"
						(effects
							(font
								(size 1.27 1.27)
							)
						)
					)
				)
				(pin passive line
					(at 0 -73.66 0)
					(length 5.08)
					(name "DXN"
						(effects
							(font
								(size 1.27 1.27)
							)
						)
					)
					(number "T13"
						(effects
							(font
								(size 1.27 1.27)
							)
						)
					)
				)
				(pin input line
					(at 0 -78.74 0)
					(length 5.08)
					(name "POR_OVERRIDE"
						(effects
							(font
								(size 1.27 1.27)
							)
						)
					)
					(number "Y12"
						(effects
							(font
								(size 1.27 1.27)
							)
						)
					)
				)
				(pin input line
					(at 0 -81.28 0)
					(length 5.08)
					(name "PUDC_B_0"
						(effects
							(font
								(size 1.27 1.27)
							)
						)
					)
					(number "W9"
						(effects
							(font
								(size 1.27 1.27)
							)
						)
					)
				)
			)
			(symbol "XCAU25P-2FFVB676I_1_2_1"
				(rectangle
					(start 5.08 2.54)
					(end 43.18 -142.24)
					(stroke
						(width 0.254)
						(type default)
					)
					(fill
						(type background)
					)
				)
				(polyline
					(pts
						(xy 30.48 -6.35) (xy 39.37 -6.35) (xy 39.37 -138.43) (xy 31.75 -138.43)
					)
					(stroke
						(width 0.254)
						(type default)
					)
					(fill
						(type background)
					)
				)
				(text "BANK 64"
					(at 30.48 -5.08 0)
					(effects
						(font
							(size 1.27 1.27)
							(thickness 0.15)
						)
						(justify left bottom)
					)
				)
				(text ""
					(at 50.8 -31.75 0)
					(effects
						(font
							(size 1.27 1.27)
							(thickness 0.15)
						)
						(justify left bottom)
					)
				)
				(text ""
					(at 50.8 -31.75 0)
					(effects
						(font
							(size 1.27 1.27)
							(thickness 0.15)
						)
						(justify left bottom)
					)
				)
				(pin power_in line
					(at 0 0 0)
					(length 5.08)
					(name "VCCO_64"
						(effects
							(font
								(size 1.27 1.27)
							)
						)
					)
					(number "AA21"
						(effects
							(font
								(size 1.27 1.27)
							)
						)
					)
				)
				(pin passive line
					(at 0 0 0)
					(length 5.08)
					(hide yes)
					(name "VCCO_64"
						(effects
							(font
								(size 1.27 1.27)
							)
						)
					)
					(number "AB18"
						(effects
							(font
								(size 1.27 1.27)
							)
						)
					)
				)
				(pin passive line
					(at 0 0 0)
					(length 5.08)
					(hide yes)
					(name "VCCO_64"
						(effects
							(font
								(size 1.27 1.27)
							)
						)
					)
					(number "AD22"
						(effects
							(font
								(size 1.27 1.27)
							)
						)
					)
				)
				(pin input line
					(at 0 -2.54 0)
					(length 5.08)
					(name "VREF_64"
						(effects
							(font
								(size 1.27 1.27)
							)
						)
					)
					(number "W18"
						(effects
							(font
								(size 1.27 1.27)
							)
						)
					)
				)
				(pin bidirectional line
					(at 0 -7.62 0)
					(length 5.08)
					(name "IO_L1P_T0L_N0_DBC_64"
						(effects
							(font
								(size 1.27 1.27)
							)
						)
					)
					(number "AE25"
						(effects
							(font
								(size 1.27 1.27)
							)
						)
					)
				)
				(pin bidirectional line
					(at 0 -10.16 0)
					(length 5.08)
					(name "IO_L1N_T0L_N1_DBC_64"
						(effects
							(font
								(size 1.27 1.27)
							)
						)
					)
					(number "AE26"
						(effects
							(font
								(size 1.27 1.27)
							)
						)
					)
				)
				(pin bidirectional line
					(at 0 -12.7 0)
					(length 5.08)
					(name "IO_L2P_T0L_N2_64"
						(effects
							(font
								(size 1.27 1.27)
							)
						)
					)
					(number "AB25"
						(effects
							(font
								(size 1.27 1.27)
							)
						)
					)
				)
				(pin bidirectional line
					(at 0 -15.24 0)
					(length 5.08)
					(name "IO_L2N_T0L_N3_64"
						(effects
							(font
								(size 1.27 1.27)
							)
						)
					)
					(number "AB26"
						(effects
							(font
								(size 1.27 1.27)
							)
						)
					)
				)
				(pin bidirectional line
					(at 0 -17.78 0)
					(length 5.08)
					(name "IO_L3P_T0L_N4_AD15P_64"
						(effects
							(font
								(size 1.27 1.27)
							)
						)
					)
					(number "AF24"
						(effects
							(font
								(size 1.27 1.27)
							)
						)
					)
				)
				(pin bidirectional line
					(at 0 -20.32 0)
					(length 5.08)
					(name "IO_L3N_T0L_N5_AD15N_64"
						(effects
							(font
								(size 1.27 1.27)
							)
						)
					)
					(number "AF25"
						(effects
							(font
								(size 1.27 1.27)
							)
						)
					)
				)
				(pin bidirectional line
					(at 0 -22.86 0)
					(length 5.08)
					(name "IO_L4P_T0U_N6_DBC_AD7P_64"
						(effects
							(font
								(size 1.27 1.27)
							)
						)
					)
					(number "AC26"
						(effects
							(font
								(size 1.27 1.27)
							)
						)
					)
				)
				(pin bidirectional line
					(at 0 -25.4 0)
					(length 5.08)
					(name "IO_L4N_T0U_N7_DBC_AD7N_64"
						(effects
							(font
								(size 1.27 1.27)
							)
						)
					)
					(number "AD26"
						(effects
							(font
								(size 1.27 1.27)
							)
						)
					)
				)
				(pin bidirectional line
					(at 0 -27.94 0)
					(length 5.08)
					(name "IO_L5P_T0U_N8_AD14P_64"
						(effects
							(font
								(size 1.27 1.27)
							)
						)
					)
					(number "AD24"
						(effects
							(font
								(size 1.27 1.27)
							)
						)
					)
				)
				(pin bidirectional line
					(at 0 -30.48 0)
					(length 5.08)
					(name "IO_L5N_T0U_N9_AD14N_64"
						(effects
							(font
								(size 1.27 1.27)
							)
						)
					)
					(number "AD25"
						(effects
							(font
								(size 1.27 1.27)
							)
						)
					)
				)
				(pin bidirectional line
					(at 0 -33.02 0)
					(length 5.08)
					(name "IO_L6P_T0U_N10_AD6P_64"
						(effects
							(font
								(size 1.27 1.27)
							)
						)
					)
					(number "AB24"
						(effects
							(font
								(size 1.27 1.27)
							)
						)
					)
				)
				(pin bidirectional line
					(at 0 -35.56 0)
					(length 5.08)
					(name "IO_L6N_T0U_N11_AD6N_64"
						(effects
							(font
								(size 1.27 1.27)
							)
						)
					)
					(number "AC24"
						(effects
							(font
								(size 1.27 1.27)
							)
						)
					)
				)
				(pin bidirectional line
					(at 0 -38.1 0)
					(length 5.08)
					(name "IO_T0U_N12_VRP_64"
						(effects
							(font
								(size 1.27 1.27)
							)
						)
					)
					(number "AF23"
						(effects
							(font
								(size 1.27 1.27)
							)
						)
					)
				)
				(pin bidirectional line
					(at 0 -40.64 0)
					(length 5.08)
					(name "IO_L7P_T1L_N0_QBC_AD13P_64"
						(effects
							(font
								(size 1.27 1.27)
							)
						)
					)
					(number "AE22"
						(effects
							(font
								(size 1.27 1.27)
							)
						)
					)
				)
				(pin bidirectional line
					(at 0 -43.18 0)
					(length 5.08)
					(name "IO_L7N_T1L_N1_QBC_AD13N_64"
						(effects
							(font
								(size 1.27 1.27)
							)
						)
					)
					(number "AF22"
						(effects
							(font
								(size 1.27 1.27)
							)
						)
					)
				)
				(pin bidirectional line
					(at 0 -45.72 0)
					(length 5.08)
					(name "IO_L8P_T1L_N2_AD5P_64"
						(effects
							(font
								(size 1.27 1.27)
							)
						)
					)
					(number "AD23"
						(effects
							(font
								(size 1.27 1.27)
							)
						)
					)
				)
				(pin bidirectional line
					(at 0 -48.26 0)
					(length 5.08)
					(name "IO_L8N_T1L_N3_AD5N_64"
						(effects
							(font
								(size 1.27 1.27)
							)
						)
					)
					(number "AE23"
						(effects
							(font
								(size 1.27 1.27)
							)
						)
					)
				)
				(pin bidirectional line
					(at 0 -50.8 0)
					(length 5.08)
					(name "IO_L9P_T1L_N4_AD12P_64"
						(effects
							(font
								(size 1.27 1.27)
							)
						)
					)
					(number "AC22"
						(effects
							(font
								(size 1.27 1.27)
							)
						)
					)
				)
				(pin bidirectional line
					(at 0 -53.34 0)
					(length 5.08)
					(name "IO_L9N_T1L_N5_AD12N_64"
						(effects
							(font
								(size 1.27 1.27)
							)
						)
					)
					(number "AC23"
						(effects
							(font
								(size 1.27 1.27)
							)
						)
					)
				)
				(pin bidirectional line
					(at 0 -55.88 0)
					(length 5.08)
					(name "IO_L10P_T1U_N6_QBC_AD4P_64"
						(effects
							(font
								(size 1.27 1.27)
							)
						)
					)
					(number "AA22"
						(effects
							(font
								(size 1.27 1.27)
							)
						)
					)
				)
				(pin bidirectional line
					(at 0 -58.42 0)
					(length 5.08)
					(name "IO_L10N_T1U_N7_QBC_AD4N_64"
						(effects
							(font
								(size 1.27 1.27)
							)
						)
					)
					(number "AB22"
						(effects
							(font
								(size 1.27 1.27)
							)
						)
					)
				)
				(pin bidirectional line
					(at 0 -60.96 0)
					(length 5.08)
					(name "IO_L11P_T1U_N8_GC_64"
						(effects
							(font
								(size 1.27 1.27)
							)
						)
					)
					(number "AD21"
						(effects
							(font
								(size 1.27 1.27)
							)
						)
					)
				)
				(pin bidirectional line
					(at 0 -63.5 0)
					(length 5.08)
					(name "IO_L11N_T1U_N9_GC_64"
						(effects
							(font
								(size 1.27 1.27)
							)
						)
					)
					(number "AE21"
						(effects
							(font
								(size 1.27 1.27)
							)
						)
					)
				)
				(pin bidirectional line
					(at 0 -66.04 0)
					(length 5.08)
					(name "IO_L12P_T1U_N10_GC_64"
						(effects
							(font
								(size 1.27 1.27)
							)
						)
					)
					(number "AB21"
						(effects
							(font
								(size 1.27 1.27)
							)
						)
					)
				)
				(pin bidirectional line
					(at 0 -68.58 0)
					(length 5.08)
					(name "IO_L12N_T1U_N11_GC_64"
						(effects
							(font
								(size 1.27 1.27)
							)
						)
					)
					(number "AC21"
						(effects
							(font
								(size 1.27 1.27)
							)
						)
					)
				)
				(pin bidirectional line
					(at 0 -71.12 0)
					(length 5.08)
					(name "IO_T1U_N12_64"
						(effects
							(font
								(size 1.27 1.27)
							)
						)
					)
					(number "AF20"
						(effects
							(font
								(size 1.27 1.27)
							)
						)
					)
				)
				(pin bidirectional line
					(at 0 -73.66 0)
					(length 5.08)
					(name "IO_L13P_T2L_N0_GC_QBC_64"
						(effects
							(font
								(size 1.27 1.27)
							)
						)
					)
					(number "AD20"
						(effects
							(font
								(size 1.27 1.27)
							)
						)
					)
				)
				(pin bidirectional line
					(at 0 -76.2 0)
					(length 5.08)
					(name "IO_L13N_T2L_N1_GC_QBC_64"
						(effects
							(font
								(size 1.27 1.27)
							)
						)
					)
					(number "AE20"
						(effects
							(font
								(size 1.27 1.27)
							)
						)
					)
				)
				(pin bidirectional line
					(at 0 -78.74 0)
					(length 5.08)
					(name "IO_L14P_T2L_N2_GC_64"
						(effects
							(font
								(size 1.27 1.27)
							)
						)
					)
					(number "AC19"
						(effects
							(font
								(size 1.27 1.27)
							)
						)
					)
				)
				(pin bidirectional line
					(at 0 -81.28 0)
					(length 5.08)
					(name "IO_L14N_T2L_N3_GC_64"
						(effects
							(font
								(size 1.27 1.27)
							)
						)
					)
					(number "AD19"
						(effects
							(font
								(size 1.27 1.27)
							)
						)
					)
				)
				(pin bidirectional line
					(at 0 -83.82 0)
					(length 5.08)
					(name "IO_L15P_T2L_N4_AD11P_64"
						(effects
							(font
								(size 1.27 1.27)
							)
						)
					)
					(number "AF18"
						(effects
							(font
								(size 1.27 1.27)
							)
						)
					)
				)
				(pin bidirectional line
					(at 0 -86.36 0)
					(length 5.08)
					(name "IO_L15N_T2L_N5_AD11N_64"
						(effects
							(font
								(size 1.27 1.27)
							)
						)
					)
					(number "AF19"
						(effects
							(font
								(size 1.27 1.27)
							)
						)
					)
				)
				(pin bidirectional line
					(at 0 -88.9 0)
					(length 5.08)
					(name "IO_L16P_T2U_N6_QBC_AD3P_64"
						(effects
							(font
								(size 1.27 1.27)
							)
						)
					)
					(number "AC18"
						(effects
							(font
								(size 1.27 1.27)
							)
						)
					)
				)
				(pin bidirectional line
					(at 0 -91.44 0)
					(length 5.08)
					(name "IO_L16N_T2U_N7_QBC_AD3N_64"
						(effects
							(font
								(size 1.27 1.27)
							)
						)
					)
					(number "AD18"
						(effects
							(font
								(size 1.27 1.27)
							)
						)
					)
				)
				(pin bidirectional line
					(at 0 -93.98 0)
					(length 5.08)
					(name "IO_L17P_T2U_N8_AD10P_64"
						(effects
							(font
								(size 1.27 1.27)
							)
						)
					)
					(number "AE17"
						(effects
							(font
								(size 1.27 1.27)
							)
						)
					)
				)
				(pin bidirectional line
					(at 0 -96.52 0)
					(length 5.08)
					(name "IO_L17N_T2U_N9_AD10N_64"
						(effects
							(font
								(size 1.27 1.27)
							)
						)
					)
					(number "AF17"
						(effects
							(font
								(size 1.27 1.27)
							)
						)
					)
				)
				(pin bidirectional line
					(at 0 -99.06 0)
					(length 5.08)
					(name "IO_L18P_T2U_N10_AD2P_64"
						(effects
							(font
								(size 1.27 1.27)
							)
						)
					)
					(number "AD16"
						(effects
							(font
								(size 1.27 1.27)
							)
						)
					)
				)
				(pin bidirectional line
					(at 0 -101.6 0)
					(length 5.08)
					(name "IO_L18N_T2U_N11_AD2N_64"
						(effects
							(font
								(size 1.27 1.27)
							)
						)
					)
					(number "AE16"
						(effects
							(font
								(size 1.27 1.27)
							)
						)
					)
				)
				(pin bidirectional line
					(at 0 -104.14 0)
					(length 5.08)
					(name "IO_T2U_N12_64"
						(effects
							(font
								(size 1.27 1.27)
							)
						)
					)
					(number "AE18"
						(effects
							(font
								(size 1.27 1.27)
							)
						)
					)
				)
				(pin bidirectional line
					(at 0 -106.68 0)
					(length 5.08)
					(name "IO_L19P_T3L_N0_DBC_AD9P_64"
						(effects
							(font
								(size 1.27 1.27)
							)
						)
					)
					(number "Y20"
						(effects
							(font
								(size 1.27 1.27)
							)
						)
					)
				)
				(pin bidirectional line
					(at 0 -109.22 0)
					(length 5.08)
					(name "IO_L19N_T3L_N1_DBC_AD9N_64"
						(effects
							(font
								(size 1.27 1.27)
							)
						)
					)
					(number "Y21"
						(effects
							(font
								(size 1.27 1.27)
							)
						)
					)
				)
				(pin bidirectional line
					(at 0 -111.76 0)
					(length 5.08)
					(name "IO_L20P_T3L_N2_AD1P_64"
						(effects
							(font
								(size 1.27 1.27)
							)
						)
					)
					(number "AA19"
						(effects
							(font
								(size 1.27 1.27)
							)
						)
					)
				)
				(pin bidirectional line
					(at 0 -114.3 0)
					(length 5.08)
					(name "IO_L20N_T3L_N3_AD1N_64"
						(effects
							(font
								(size 1.27 1.27)
							)
						)
					)
					(number "AB19"
						(effects
							(font
								(size 1.27 1.27)
							)
						)
					)
				)
				(pin bidirectional line
					(at 0 -116.84 0)
					(length 5.08)
					(name "IO_L21P_T3L_N4_AD8P_64"
						(effects
							(font
								(size 1.27 1.27)
							)
						)
					)
					(number "AA20"
						(effects
							(font
								(size 1.27 1.27)
							)
						)
					)
				)
				(pin bidirectional line
					(at 0 -119.38 0)
					(length 5.08)
					(name "IO_L21N_T3L_N5_AD8N_64"
						(effects
							(font
								(size 1.27 1.27)
							)
						)
					)
					(number "AB20"
						(effects
							(font
								(size 1.27 1.27)
							)
						)
					)
				)
				(pin bidirectional line
					(at 0 -121.92 0)
					(length 5.08)
					(name "IO_L22P_T3U_N6_DBC_AD0P_64"
						(effects
							(font
								(size 1.27 1.27)
							)
						)
					)
					(number "AB17"
						(effects
							(font
								(size 1.27 1.27)
							)
						)
					)
				)
				(pin bidirectional line
					(at 0 -124.46 0)
					(length 5.08)
					(name "IO_L22N_T3U_N7_DBC_AD0N_64"
						(effects
							(font
								(size 1.27 1.27)
							)
						)
					)
					(number "AC17"
						(effects
							(font
								(size 1.27 1.27)
							)
						)
					)
				)
				(pin bidirectional line
					(at 0 -127 0)
					(length 5.08)
					(name "IO_L23P_T3U_N8_64"
						(effects
							(font
								(size 1.27 1.27)
							)
						)
					)
					(number "Y17"
						(effects
							(font
								(size 1.27 1.27)
							)
						)
					)
				)
				(pin bidirectional line
					(at 0 -129.54 0)
					(length 5.08)
					(name "IO_L23N_T3U_N9_64"
						(effects
							(font
								(size 1.27 1.27)
							)
						)
					)
					(number "AA17"
						(effects
							(font
								(size 1.27 1.27)
							)
						)
					)
				)
				(pin bidirectional line
					(at 0 -132.08 0)
					(length 5.08)
					(name "IO_L24P_T3U_N10_64"
						(effects
							(font
								(size 1.27 1.27)
							)
						)
					)
					(number "Y18"
						(effects
							(font
								(size 1.27 1.27)
							)
						)
					)
				)
				(pin bidirectional line
					(at 0 -134.62 0)
					(length 5.08)
					(name "IO_L24N_T3U_N11_64"
						(effects
							(font
								(size 1.27 1.27)
							)
						)
					)
					(number "AA18"
						(effects
							(font
								(size 1.27 1.27)
							)
						)
					)
				)
				(pin bidirectional line
					(at 0 -137.16 0)
					(length 5.08)
					(name "IO_T3U_N12_64"
						(effects
							(font
								(size 1.27 1.27)
							)
						)
					)
					(number "AC16"
						(effects
							(font
								(size 1.27 1.27)
							)
						)
					)
				)
			)
			(symbol "XCAU25P-2FFVB676I_1_3_1"
				(rectangle
					(start 5.08 2.54)
					(end 50.8 -142.24)
					(stroke
						(width 0.254)
						(type default)
					)
					(fill
						(type background)
					)
				)
				(polyline
					(pts
						(xy 36.83 -5.08) (xy 44.45 -5.08) (xy 44.45 -138.43) (xy 36.83 -138.43)
					)
					(stroke
						(width 0.254)
						(type default)
					)
					(fill
						(type background)
					)
				)
				(text "BANK 65"
					(at 36.83 -3.81 0)
					(effects
						(font
							(size 1.27 1.27)
							(thickness 0.15)
						)
						(justify left bottom)
					)
				)
				(text ""
					(at 50.8 -31.75 0)
					(effects
						(font
							(size 1.27 1.27)
							(thickness 0.15)
						)
						(justify left bottom)
					)
				)
				(text ""
					(at 50.8 -31.75 0)
					(effects
						(font
							(size 1.27 1.27)
							(thickness 0.15)
						)
						(justify left bottom)
					)
				)
				(pin power_in line
					(at 0 0 0)
					(length 5.08)
					(name "VCCO_65"
						(effects
							(font
								(size 1.27 1.27)
							)
						)
					)
					(number "P22"
						(effects
							(font
								(size 1.27 1.27)
							)
						)
					)
				)
				(pin passive line
					(at 0 0 0)
					(length 5.08)
					(hide yes)
					(name "VCCO_65"
						(effects
							(font
								(size 1.27 1.27)
							)
						)
					)
					(number "U23"
						(effects
							(font
								(size 1.27 1.27)
							)
						)
					)
				)
				(pin passive line
					(at 0 0 0)
					(length 5.08)
					(hide yes)
					(name "VCCO_65"
						(effects
							(font
								(size 1.27 1.27)
							)
						)
					)
					(number "Y24"
						(effects
							(font
								(size 1.27 1.27)
							)
						)
					)
				)
				(pin input line
					(at 0 -2.54 0)
					(length 5.08)
					(name "VREF_65"
						(effects
							(font
								(size 1.27 1.27)
							)
						)
					)
					(number "V18"
						(effects
							(font
								(size 1.27 1.27)
							)
						)
					)
				)
				(pin bidirectional line
					(at 0 -7.62 0)
					(length 5.08)
					(name "IO_L1P_T0L_N0_DBC_RS0_65"
						(effects
							(font
								(size 1.27 1.27)
							)
						)
					)
					(number "U19"
						(effects
							(font
								(size 1.27 1.27)
							)
						)
					)
				)
				(pin bidirectional line
					(at 0 -10.16 0)
					(length 5.08)
					(name "IO_L1N_T0L_N1_DBC_RS1_65"
						(effects
							(font
								(size 1.27 1.27)
							)
						)
					)
					(number "V19"
						(effects
							(font
								(size 1.27 1.27)
							)
						)
					)
				)
				(pin bidirectional line
					(at 0 -12.7 0)
					(length 5.08)
					(name "IO_L2P_T0L_N2_FOE_B_65"
						(effects
							(font
								(size 1.27 1.27)
							)
						)
					)
					(number "U21"
						(effects
							(font
								(size 1.27 1.27)
							)
						)
					)
				)
				(pin bidirectional line
					(at 0 -15.24 0)
					(length 5.08)
					(name "IO_L2N_T0L_N3_FWE_FCS2_B_65"
						(effects
							(font
								(size 1.27 1.27)
							)
						)
					)
					(number "U22"
						(effects
							(font
								(size 1.27 1.27)
							)
						)
					)
				)
				(pin bidirectional line
					(at 0 -17.78 0)
					(length 5.08)
					(name "IO_L3P_T0L_N4_AD15P_A26_65"
						(effects
							(font
								(size 1.27 1.27)
							)
						)
					)
					(number "T20"
						(effects
							(font
								(size 1.27 1.27)
							)
						)
					)
				)
				(pin bidirectional line
					(at 0 -20.32 0)
					(length 5.08)
					(name "IO_L3N_T0L_N5_AD15N_A27_65"
						(effects
							(font
								(size 1.27 1.27)
							)
						)
					)
					(number "U20"
						(effects
							(font
								(size 1.27 1.27)
							)
						)
					)
				)
				(pin bidirectional line
					(at 0 -22.86 0)
					(length 5.08)
					(name "IO_L4P_T0U_N6_DBC_AD7P_A24_65"
						(effects
							(font
								(size 1.27 1.27)
							)
						)
					)
					(number "V21"
						(effects
							(font
								(size 1.27 1.27)
							)
						)
					)
				)
				(pin bidirectional line
					(at 0 -25.4 0)
					(length 5.08)
					(name "IO_L4N_T0U_N7_DBC_AD7N_A25_65"
						(effects
							(font
								(size 1.27 1.27)
							)
						)
					)
					(number "V22"
						(effects
							(font
								(size 1.27 1.27)
							)
						)
					)
				)
				(pin bidirectional line
					(at 0 -27.94 0)
					(length 5.08)
					(name "IO_L5P_T0U_N8_AD14P_A22_65"
						(effects
							(font
								(size 1.27 1.27)
							)
						)
					)
					(number "T22"
						(effects
							(font
								(size 1.27 1.27)
							)
						)
					)
				)
				(pin bidirectional line
					(at 0 -30.48 0)
					(length 5.08)
					(name "IO_L5N_T0U_N9_AD14N_A23_65"
						(effects
							(font
								(size 1.27 1.27)
							)
						)
					)
					(number "T23"
						(effects
							(font
								(size 1.27 1.27)
							)
						)
					)
				)
				(pin bidirectional line
					(at 0 -33.02 0)
					(length 5.08)
					(name "IO_L6P_T0U_N10_AD6P_A20_65"
						(effects
							(font
								(size 1.27 1.27)
							)
						)
					)
					(number "W19"
						(effects
							(font
								(size 1.27 1.27)
							)
						)
					)
				)
				(pin bidirectional line
					(at 0 -35.56 0)
					(length 5.08)
					(name "IO_L6N_T0U_N11_AD6N_A21_65"
						(effects
							(font
								(size 1.27 1.27)
							)
						)
					)
					(number "W20"
						(effects
							(font
								(size 1.27 1.27)
							)
						)
					)
				)
				(pin bidirectional line
					(at 0 -38.1 0)
					(length 5.08)
					(name "IO_T0U_N12_VRP_A28_65"
						(effects
							(font
								(size 1.27 1.27)
							)
						)
					)
					(number "W21"
						(effects
							(font
								(size 1.27 1.27)
							)
						)
					)
				)
				(pin bidirectional line
					(at 0 -40.64 0)
					(length 5.08)
					(name "IO_L7P_T1L_N0_QBC_AD13P_A18_65"
						(effects
							(font
								(size 1.27 1.27)
							)
						)
					)
					(number "Y22"
						(effects
							(font
								(size 1.27 1.27)
							)
						)
					)
				)
				(pin bidirectional line
					(at 0 -43.18 0)
					(length 5.08)
					(name "IO_L7N_T1L_N1_QBC_AD13N_A19_65"
						(effects
							(font
								(size 1.27 1.27)
							)
						)
					)
					(number "Y23"
						(effects
							(font
								(size 1.27 1.27)
							)
						)
					)
				)
				(pin bidirectional line
					(at 0 -45.72 0)
					(length 5.08)
					(name "IO_L8P_T1L_N2_AD5P_A16_65"
						(effects
							(font
								(size 1.27 1.27)
							)
						)
					)
					(number "Y25"
						(effects
							(font
								(size 1.27 1.27)
							)
						)
					)
				)
				(pin bidirectional line
					(at 0 -48.26 0)
					(length 5.08)
					(name "IO_L8N_T1L_N3_AD5N_A17_65"
						(effects
							(font
								(size 1.27 1.27)
							)
						)
					)
					(number "Y26"
						(effects
							(font
								(size 1.27 1.27)
							)
						)
					)
				)
				(pin bidirectional line
					(at 0 -50.8 0)
					(length 5.08)
					(name "IO_L9P_T1L_N4_AD12P_A14_D30_65"
						(effects
							(font
								(size 1.27 1.27)
							)
						)
					)
					(number "AA24"
						(effects
							(font
								(size 1.27 1.27)
							)
						)
					)
				)
				(pin bidirectional line
					(at 0 -53.34 0)
					(length 5.08)
					(name "IO_L9N_T1L_N5_AD12N_A15_D31_65"
						(effects
							(font
								(size 1.27 1.27)
							)
						)
					)
					(number "AA25"
						(effects
							(font
								(size 1.27 1.27)
							)
						)
					)
				)
				(pin bidirectional line
					(at 0 -55.88 0)
					(length 5.08)
					(name "IO_L10P_T1U_N6_QBC_AD4P_A12_D28_65"
						(effects
							(font
								(size 1.27 1.27)
							)
						)
					)
					(number "W25"
						(effects
							(font
								(size 1.27 1.27)
							)
						)
					)
				)
				(pin bidirectional line
					(at 0 -58.42 0)
					(length 5.08)
					(name "IO_L10N_T1U_N7_QBC_AD4N_A13_D29_65"
						(effects
							(font
								(size 1.27 1.27)
							)
						)
					)
					(number "W26"
						(effects
							(font
								(size 1.27 1.27)
							)
						)
					)
				)
				(pin bidirectional line
					(at 0 -60.96 0)
					(length 5.08)
					(name "IO_L11P_T1U_N8_GC_A10_D26_65"
						(effects
							(font
								(size 1.27 1.27)
							)
						)
					)
					(number "V23"
						(effects
							(font
								(size 1.27 1.27)
							)
						)
					)
				)
				(pin bidirectional line
					(at 0 -63.5 0)
					(length 5.08)
					(name "IO_L11N_T1U_N9_GC_A11_D27_65"
						(effects
							(font
								(size 1.27 1.27)
							)
						)
					)
					(number "W23"
						(effects
							(font
								(size 1.27 1.27)
							)
						)
					)
				)
				(pin bidirectional line
					(at 0 -66.04 0)
					(length 5.08)
					(name "IO_L12P_T1U_N10_GC_A08_D24_65"
						(effects
							(font
								(size 1.27 1.27)
							)
						)
					)
					(number "V24"
						(effects
							(font
								(size 1.27 1.27)
							)
						)
					)
				)
				(pin bidirectional line
					(at 0 -68.58 0)
					(length 5.08)
					(name "IO_L12N_T1U_N11_GC_A09_D25_65"
						(effects
							(font
								(size 1.27 1.27)
							)
						)
					)
					(number "W24"
						(effects
							(font
								(size 1.27 1.27)
							)
						)
					)
				)
				(pin bidirectional line
					(at 0 -71.12 0)
					(length 5.08)
					(name "IO_T1U_N12_SMBALERT_65"
						(effects
							(font
								(size 1.27 1.27)
							)
						)
					)
					(number "AA23"
						(effects
							(font
								(size 1.27 1.27)
							)
						)
					)
				)
				(pin bidirectional line
					(at 0 -73.66 0)
					(length 5.08)
					(name "IO_L13P_T2L_N0_GC_QBC_A06_D22_65"
						(effects
							(font
								(size 1.27 1.27)
							)
						)
					)
					(number "T24"
						(effects
							(font
								(size 1.27 1.27)
							)
						)
					)
				)
				(pin bidirectional line
					(at 0 -76.2 0)
					(length 5.08)
					(name "IO_L13N_T2L_N1_GC_QBC_A07_D23_65"
						(effects
							(font
								(size 1.27 1.27)
							)
						)
					)
					(number "U24"
						(effects
							(font
								(size 1.27 1.27)
							)
						)
					)
				)
				(pin bidirectional line
					(at 0 -78.74 0)
					(length 5.08)
					(name "IO_L14P_T2L_N2_GC_A04_D20_65"
						(effects
							(font
								(size 1.27 1.27)
							)
						)
					)
					(number "T25"
						(effects
							(font
								(size 1.27 1.27)
							)
						)
					)
				)
				(pin bidirectional line
					(at 0 -81.28 0)
					(length 5.08)
					(name "IO_L14N_T2L_N3_GC_A05_D21_65"
						(effects
							(font
								(size 1.27 1.27)
							)
						)
					)
					(number "U25"
						(effects
							(font
								(size 1.27 1.27)
							)
						)
					)
				)
				(pin bidirectional line
					(at 0 -83.82 0)
					(length 5.08)
					(name "IO_L15P_T2L_N4_AD11P_A02_D18_65"
						(effects
							(font
								(size 1.27 1.27)
							)
						)
					)
					(number "N24"
						(effects
							(font
								(size 1.27 1.27)
							)
						)
					)
				)
				(pin bidirectional line
					(at 0 -86.36 0)
					(length 5.08)
					(name "IO_L15N_T2L_N5_AD11N_A03_D19_65"
						(effects
							(font
								(size 1.27 1.27)
							)
						)
					)
					(number "P24"
						(effects
							(font
								(size 1.27 1.27)
							)
						)
					)
				)
				(pin bidirectional line
					(at 0 -88.9 0)
					(length 5.08)
					(name "IO_L16P_T2U_N6_QBC_AD3P_A00_D16_65"
						(effects
							(font
								(size 1.27 1.27)
							)
						)
					)
					(number "U26"
						(effects
							(font
								(size 1.27 1.27)
							)
						)
					)
				)
				(pin bidirectional line
					(at 0 -91.44 0)
					(length 5.08)
					(name "IO_L16N_T2U_N7_QBC_AD3N_A01_D17_65"
						(effects
							(font
								(size 1.27 1.27)
							)
						)
					)
					(number "V26"
						(effects
							(font
								(size 1.27 1.27)
							)
						)
					)
				)
				(pin bidirectional line
					(at 0 -93.98 0)
					(length 5.08)
					(name "IO_L17P_T2U_N8_AD10P_D14_65"
						(effects
							(font
								(size 1.27 1.27)
							)
						)
					)
					(number "P25"
						(effects
							(font
								(size 1.27 1.27)
							)
						)
					)
				)
				(pin bidirectional line
					(at 0 -96.52 0)
					(length 5.08)
					(name "IO_L17N_T2U_N9_AD10N_D15_65"
						(effects
							(font
								(size 1.27 1.27)
							)
						)
					)
					(number "P26"
						(effects
							(font
								(size 1.27 1.27)
							)
						)
					)
				)
				(pin bidirectional line
					(at 0 -99.06 0)
					(length 5.08)
					(name "IO_L18P_T2U_N10_AD2P_D12_65"
						(effects
							(font
								(size 1.27 1.27)
							)
						)
					)
					(number "R25"
						(effects
							(font
								(size 1.27 1.27)
							)
						)
					)
				)
				(pin bidirectional line
					(at 0 -101.6 0)
					(length 5.08)
					(name "IO_L18N_T2U_N11_AD2N_D13_65"
						(effects
							(font
								(size 1.27 1.27)
							)
						)
					)
					(number "R26"
						(effects
							(font
								(size 1.27 1.27)
							)
						)
					)
				)
				(pin bidirectional line
					(at 0 -104.14 0)
					(length 5.08)
					(name "IO_T2U_N12_CSI_ADV_B_65"
						(effects
							(font
								(size 1.27 1.27)
							)
						)
					)
					(number "N26"
						(effects
							(font
								(size 1.27 1.27)
							)
						)
					)
				)
				(pin bidirectional line
					(at 0 -106.68 0)
					(length 5.08)
					(name "IO_L19P_T3L_N0_DBC_AD9P_D10_65"
						(effects
							(font
								(size 1.27 1.27)
							)
						)
					)
					(number "R22"
						(effects
							(font
								(size 1.27 1.27)
							)
						)
					)
				)
				(pin bidirectional line
					(at 0 -109.22 0)
					(length 5.08)
					(name "IO_L19N_T3L_N1_DBC_AD9N_D11_65"
						(effects
							(font
								(size 1.27 1.27)
							)
						)
					)
					(number "R23"
						(effects
							(font
								(size 1.27 1.27)
							)
						)
					)
				)
				(pin bidirectional line
					(at 0 -111.76 0)
					(length 5.08)
					(name "IO_L20P_T3L_N2_AD1P_D08_65"
						(effects
							(font
								(size 1.27 1.27)
							)
						)
					)
					(number "P20"
						(effects
							(font
								(size 1.27 1.27)
							)
						)
					)
				)
				(pin bidirectional line
					(at 0 -114.3 0)
					(length 5.08)
					(name "IO_L20N_T3L_N3_AD1N_D09_65"
						(effects
							(font
								(size 1.27 1.27)
							)
						)
					)
					(number "P21"
						(effects
							(font
								(size 1.27 1.27)
							)
						)
					)
				)
				(pin bidirectional line
					(at 0 -116.84 0)
					(length 5.08)
					(name "IO_L21P_T3L_N4_AD8P_D06_65"
						(effects
							(font
								(size 1.27 1.27)
							)
						)
					)
					(number "R20"
						(effects
							(font
								(size 1.27 1.27)
							)
						)
					)
				)
				(pin bidirectional line
					(at 0 -119.38 0)
					(length 5.08)
					(name "IO_L21N_T3L_N5_AD8N_D07_65"
						(effects
							(font
								(size 1.27 1.27)
							)
						)
					)
					(number "R21"
						(effects
							(font
								(size 1.27 1.27)
							)
						)
					)
				)
				(pin bidirectional line
					(at 0 -121.92 0)
					(length 5.08)
					(name "IO_L22P_T3U_N6_DBC_AD0P_D04_65"
						(effects
							(font
								(size 1.27 1.27)
							)
						)
					)
					(number "N23"
						(effects
							(font
								(size 1.27 1.27)
							)
						)
					)
				)
				(pin bidirectional line
					(at 0 -124.46 0)
					(length 5.08)
					(name "IO_L22N_T3U_N7_DBC_AD0N_D05_65"
						(effects
							(font
								(size 1.27 1.27)
							)
						)
					)
					(number "P23"
						(effects
							(font
								(size 1.27 1.27)
							)
						)
					)
				)
				(pin bidirectional line
					(at 0 -127 0)
					(length 5.08)
					(name "IO_L23P_T3U_N8_I2C_SCLK_65"
						(effects
							(font
								(size 1.27 1.27)
							)
						)
					)
					(number "N19"
						(effects
							(font
								(size 1.27 1.27)
							)
						)
					)
				)
				(pin bidirectional line
					(at 0 -129.54 0)
					(length 5.08)
					(name "IO_L23N_T3U_N9_PERSTN1_I2C_SDA_65"
						(effects
							(font
								(size 1.27 1.27)
							)
						)
					)
					(number "P19"
						(effects
							(font
								(size 1.27 1.27)
							)
						)
					)
				)
				(pin bidirectional line
					(at 0 -132.08 0)
					(length 5.08)
					(name "IO_L24P_T3U_N10_EMCCLK_65"
						(effects
							(font
								(size 1.27 1.27)
							)
						)
					)
					(number "N21"
						(effects
							(font
								(size 1.27 1.27)
							)
						)
					)
				)
				(pin bidirectional line
					(at 0 -134.62 0)
					(length 5.08)
					(name "IO_L24N_T3U_N11_DOUT_CSO_B_65"
						(effects
							(font
								(size 1.27 1.27)
							)
						)
					)
					(number "N22"
						(effects
							(font
								(size 1.27 1.27)
							)
						)
					)
				)
				(pin bidirectional line
					(at 0 -137.16 0)
					(length 5.08)
					(name "IO_T3U_N12_PERSTN0_65"
						(effects
							(font
								(size 1.27 1.27)
							)
						)
					)
					(number "T19"
						(effects
							(font
								(size 1.27 1.27)
							)
						)
					)
				)
			)
			(symbol "XCAU25P-2FFVB676I_1_4_1"
				(rectangle
					(start 5.08 2.54)
					(end 43.18 -142.24)
					(stroke
						(width 0.254)
						(type default)
					)
					(fill
						(type background)
					)
				)
				(polyline
					(pts
						(xy 30.48 -6.35) (xy 39.37 -6.35) (xy 39.37 -138.43) (xy 31.75 -138.43)
					)
					(stroke
						(width 0.254)
						(type default)
					)
					(fill
						(type background)
					)
				)
				(text "BANK 66"
					(at 30.48 -5.08 0)
					(effects
						(font
							(size 1.27 1.27)
							(thickness 0.15)
						)
						(justify left bottom)
					)
				)
				(text ""
					(at 50.8 -31.75 0)
					(effects
						(font
							(size 1.27 1.27)
							(thickness 0.15)
						)
						(justify left bottom)
					)
				)
				(text ""
					(at 50.8 -31.75 0)
					(effects
						(font
							(size 1.27 1.27)
							(thickness 0.15)
						)
						(justify left bottom)
					)
				)
				(pin power_in line
					(at 0 0 0)
					(length 5.08)
					(name "VCCO_66"
						(effects
							(font
								(size 1.27 1.27)
							)
						)
					)
					(number "E24"
						(effects
							(font
								(size 1.27 1.27)
							)
						)
					)
				)
				(pin passive line
					(at 0 0 0)
					(length 5.08)
					(hide yes)
					(name "VCCO_66"
						(effects
							(font
								(size 1.27 1.27)
							)
						)
					)
					(number "H25"
						(effects
							(font
								(size 1.27 1.27)
							)
						)
					)
				)
				(pin passive line
					(at 0 0 0)
					(length 5.08)
					(hide yes)
					(name "VCCO_66"
						(effects
							(font
								(size 1.27 1.27)
							)
						)
					)
					(number "J22"
						(effects
							(font
								(size 1.27 1.27)
							)
						)
					)
				)
				(pin input line
					(at 0 -2.54 0)
					(length 5.08)
					(name "VREF_66"
						(effects
							(font
								(size 1.27 1.27)
							)
						)
					)
					(number "J18"
						(effects
							(font
								(size 1.27 1.27)
							)
						)
					)
				)
				(pin bidirectional line
					(at 0 -7.62 0)
					(length 5.08)
					(name "IO_L1P_T0L_N0_DBC_66"
						(effects
							(font
								(size 1.27 1.27)
							)
						)
					)
					(number "L18"
						(effects
							(font
								(size 1.27 1.27)
							)
						)
					)
				)
				(pin bidirectional line
					(at 0 -10.16 0)
					(length 5.08)
					(name "IO_L1N_T0L_N1_DBC_66"
						(effects
							(font
								(size 1.27 1.27)
							)
						)
					)
					(number "K18"
						(effects
							(font
								(size 1.27 1.27)
							)
						)
					)
				)
				(pin bidirectional line
					(at 0 -12.7 0)
					(length 5.08)
					(name "IO_L2P_T0L_N2_66"
						(effects
							(font
								(size 1.27 1.27)
							)
						)
					)
					(number "M20"
						(effects
							(font
								(size 1.27 1.27)
							)
						)
					)
				)
				(pin bidirectional line
					(at 0 -15.24 0)
					(length 5.08)
					(name "IO_L2N_T0L_N3_66"
						(effects
							(font
								(size 1.27 1.27)
							)
						)
					)
					(number "M21"
						(effects
							(font
								(size 1.27 1.27)
							)
						)
					)
				)
				(pin bidirectional line
					(at 0 -17.78 0)
					(length 5.08)
					(name "IO_L3P_T0L_N4_AD15P_66"
						(effects
							(font
								(size 1.27 1.27)
							)
						)
					)
					(number "J19"
						(effects
							(font
								(size 1.27 1.27)
							)
						)
					)
				)
				(pin bidirectional line
					(at 0 -20.32 0)
					(length 5.08)
					(name "IO_L3N_T0L_N5_AD15N_66"
						(effects
							(font
								(size 1.27 1.27)
							)
						)
					)
					(number "J20"
						(effects
							(font
								(size 1.27 1.27)
							)
						)
					)
				)
				(pin bidirectional line
					(at 0 -22.86 0)
					(length 5.08)
					(name "IO_L4P_T0U_N6_DBC_AD7P_66"
						(effects
							(font
								(size 1.27 1.27)
							)
						)
					)
					(number "M19"
						(effects
							(font
								(size 1.27 1.27)
							)
						)
					)
				)
				(pin bidirectional line
					(at 0 -25.4 0)
					(length 5.08)
					(name "IO_L4N_T0U_N7_DBC_AD7N_66"
						(effects
							(font
								(size 1.27 1.27)
							)
						)
					)
					(number "L19"
						(effects
							(font
								(size 1.27 1.27)
							)
						)
					)
				)
				(pin bidirectional line
					(at 0 -27.94 0)
					(length 5.08)
					(name "IO_L5P_T0U_N8_AD14P_66"
						(effects
							(font
								(size 1.27 1.27)
							)
						)
					)
					(number "K21"
						(effects
							(font
								(size 1.27 1.27)
							)
						)
					)
				)
				(pin bidirectional line
					(at 0 -30.48 0)
					(length 5.08)
					(name "IO_L5N_T0U_N9_AD14N_66"
						(effects
							(font
								(size 1.27 1.27)
							)
						)
					)
					(number "J21"
						(effects
							(font
								(size 1.27 1.27)
							)
						)
					)
				)
				(pin bidirectional line
					(at 0 -33.02 0)
					(length 5.08)
					(name "IO_L6P_T0U_N10_AD6P_66"
						(effects
							(font
								(size 1.27 1.27)
							)
						)
					)
					(number "L20"
						(effects
							(font
								(size 1.27 1.27)
							)
						)
					)
				)
				(pin bidirectional line
					(at 0 -35.56 0)
					(length 5.08)
					(name "IO_L6N_T0U_N11_AD6N_66"
						(effects
							(font
								(size 1.27 1.27)
							)
						)
					)
					(number "K20"
						(effects
							(font
								(size 1.27 1.27)
							)
						)
					)
				)
				(pin bidirectional line
					(at 0 -38.1 0)
					(length 5.08)
					(name "IO_T0U_N12_VRP_66"
						(effects
							(font
								(size 1.27 1.27)
							)
						)
					)
					(number "M22"
						(effects
							(font
								(size 1.27 1.27)
							)
						)
					)
				)
				(pin bidirectional line
					(at 0 -40.64 0)
					(length 5.08)
					(name "IO_L7P_T1L_N0_QBC_AD13P_66"
						(effects
							(font
								(size 1.27 1.27)
							)
						)
					)
					(number "L22"
						(effects
							(font
								(size 1.27 1.27)
							)
						)
					)
				)
				(pin bidirectional line
					(at 0 -43.18 0)
					(length 5.08)
					(name "IO_L7N_T1L_N1_QBC_AD13N_66"
						(effects
							(font
								(size 1.27 1.27)
							)
						)
					)
					(number "L23"
						(effects
							(font
								(size 1.27 1.27)
							)
						)
					)
				)
				(pin bidirectional line
					(at 0 -45.72 0)
					(length 5.08)
					(name "IO_L8P_T1L_N2_AD5P_66"
						(effects
							(font
								(size 1.27 1.27)
							)
						)
					)
					(number "M25"
						(effects
							(font
								(size 1.27 1.27)
							)
						)
					)
				)
				(pin bidirectional line
					(at 0 -48.26 0)
					(length 5.08)
					(name "IO_L8N_T1L_N3_AD5N_66"
						(effects
							(font
								(size 1.27 1.27)
							)
						)
					)
					(number "M26"
						(effects
							(font
								(size 1.27 1.27)
							)
						)
					)
				)
				(pin bidirectional line
					(at 0 -50.8 0)
					(length 5.08)
					(name "IO_L9P_T1L_N4_AD12P_66"
						(effects
							(font
								(size 1.27 1.27)
							)
						)
					)
					(number "K25"
						(effects
							(font
								(size 1.27 1.27)
							)
						)
					)
				)
				(pin bidirectional line
					(at 0 -53.34 0)
					(length 5.08)
					(name "IO_L9N_T1L_N5_AD12N_66"
						(effects
							(font
								(size 1.27 1.27)
							)
						)
					)
					(number "K26"
						(effects
							(font
								(size 1.27 1.27)
							)
						)
					)
				)
				(pin bidirectional line
					(at 0 -55.88 0)
					(length 5.08)
					(name "IO_L10P_T1U_N6_QBC_AD4P_66"
						(effects
							(font
								(size 1.27 1.27)
							)
						)
					)
					(number "L24"
						(effects
							(font
								(size 1.27 1.27)
							)
						)
					)
				)
				(pin bidirectional line
					(at 0 -58.42 0)
					(length 5.08)
					(name "IO_L10N_T1U_N7_QBC_AD4N_66"
						(effects
							(font
								(size 1.27 1.27)
							)
						)
					)
					(number "L25"
						(effects
							(font
								(size 1.27 1.27)
							)
						)
					)
				)
				(pin bidirectional line
					(at 0 -60.96 0)
					(length 5.08)
					(name "IO_L11P_T1U_N8_GC_66"
						(effects
							(font
								(size 1.27 1.27)
							)
						)
					)
					(number "K22"
						(effects
							(font
								(size 1.27 1.27)
							)
						)
					)
				)
				(pin bidirectional line
					(at 0 -63.5 0)
					(length 5.08)
					(name "IO_L11N_T1U_N9_GC_66"
						(effects
							(font
								(size 1.27 1.27)
							)
						)
					)
					(number "K23"
						(effects
							(font
								(size 1.27 1.27)
							)
						)
					)
				)
				(pin bidirectional line
					(at 0 -66.04 0)
					(length 5.08)
					(name "IO_L12P_T1U_N10_GC_66"
						(effects
							(font
								(size 1.27 1.27)
							)
						)
					)
					(number "J23"
						(effects
							(font
								(size 1.27 1.27)
							)
						)
					)
				)
				(pin bidirectional line
					(at 0 -68.58 0)
					(length 5.08)
					(name "IO_L12N_T1U_N11_GC_66"
						(effects
							(font
								(size 1.27 1.27)
							)
						)
					)
					(number "J24"
						(effects
							(font
								(size 1.27 1.27)
							)
						)
					)
				)
				(pin bidirectional line
					(at 0 -71.12 0)
					(length 5.08)
					(name "IO_T1U_N12_66"
						(effects
							(font
								(size 1.27 1.27)
							)
						)
					)
					(number "M24"
						(effects
							(font
								(size 1.27 1.27)
							)
						)
					)
				)
				(pin bidirectional line
					(at 0 -73.66 0)
					(length 5.08)
					(name "IO_L13P_T2L_N0_GC_QBC_66"
						(effects
							(font
								(size 1.27 1.27)
							)
						)
					)
					(number "G24"
						(effects
							(font
								(size 1.27 1.27)
							)
						)
					)
				)
				(pin bidirectional line
					(at 0 -76.2 0)
					(length 5.08)
					(name "IO_L13N_T2L_N1_GC_QBC_66"
						(effects
							(font
								(size 1.27 1.27)
							)
						)
					)
					(number "G25"
						(effects
							(font
								(size 1.27 1.27)
							)
						)
					)
				)
				(pin bidirectional line
					(at 0 -78.74 0)
					(length 5.08)
					(name "IO_L14P_T2L_N2_GC_66"
						(effects
							(font
								(size 1.27 1.27)
							)
						)
					)
					(number "H23"
						(effects
							(font
								(size 1.27 1.27)
							)
						)
					)
				)
				(pin bidirectional line
					(at 0 -81.28 0)
					(length 5.08)
					(name "IO_L14N_T2L_N3_GC_66"
						(effects
							(font
								(size 1.27 1.27)
							)
						)
					)
					(number "H24"
						(effects
							(font
								(size 1.27 1.27)
							)
						)
					)
				)
				(pin bidirectional line
					(at 0 -83.82 0)
					(length 5.08)
					(name "IO_L15P_T2L_N4_AD11P_66"
						(effects
							(font
								(size 1.27 1.27)
							)
						)
					)
					(number "J25"
						(effects
							(font
								(size 1.27 1.27)
							)
						)
					)
				)
				(pin bidirectional line
					(at 0 -86.36 0)
					(length 5.08)
					(name "IO_L15N_T2L_N5_AD11N_66"
						(effects
							(font
								(size 1.27 1.27)
							)
						)
					)
					(number "J26"
						(effects
							(font
								(size 1.27 1.27)
							)
						)
					)
				)
				(pin bidirectional line
					(at 0 -88.9 0)
					(length 5.08)
					(name "IO_L16P_T2U_N6_QBC_AD3P_66"
						(effects
							(font
								(size 1.27 1.27)
							)
						)
					)
					(number "F24"
						(effects
							(font
								(size 1.27 1.27)
							)
						)
					)
				)
				(pin bidirectional line
					(at 0 -91.44 0)
					(length 5.08)
					(name "IO_L16N_T2U_N7_QBC_AD3N_66"
						(effects
							(font
								(size 1.27 1.27)
							)
						)
					)
					(number "F25"
						(effects
							(font
								(size 1.27 1.27)
							)
						)
					)
				)
				(pin bidirectional line
					(at 0 -93.98 0)
					(length 5.08)
					(name "IO_L17P_T2U_N8_AD10P_66"
						(effects
							(font
								(size 1.27 1.27)
							)
						)
					)
					(number "H26"
						(effects
							(font
								(size 1.27 1.27)
							)
						)
					)
				)
				(pin bidirectional line
					(at 0 -96.52 0)
					(length 5.08)
					(name "IO_L17N_T2U_N9_AD10N_66"
						(effects
							(font
								(size 1.27 1.27)
							)
						)
					)
					(number "G26"
						(effects
							(font
								(size 1.27 1.27)
							)
						)
					)
				)
				(pin bidirectional line
					(at 0 -99.06 0)
					(length 5.08)
					(name "IO_L18P_T2U_N10_AD2P_66"
						(effects
							(font
								(size 1.27 1.27)
							)
						)
					)
					(number "H21"
						(effects
							(font
								(size 1.27 1.27)
							)
						)
					)
				)
				(pin bidirectional line
					(at 0 -101.6 0)
					(length 5.08)
					(name "IO_L18N_T2U_N11_AD2N_66"
						(effects
							(font
								(size 1.27 1.27)
							)
						)
					)
					(number "H22"
						(effects
							(font
								(size 1.27 1.27)
							)
						)
					)
				)
				(pin bidirectional line
					(at 0 -104.14 0)
					(length 5.08)
					(name "IO_T2U_N12_66"
						(effects
							(font
								(size 1.27 1.27)
							)
						)
					)
					(number "G22"
						(effects
							(font
								(size 1.27 1.27)
							)
						)
					)
				)
				(pin bidirectional line
					(at 0 -106.68 0)
					(length 5.08)
					(name "IO_L19P_T3L_N0_DBC_AD9P_66"
						(effects
							(font
								(size 1.27 1.27)
							)
						)
					)
					(number "E25"
						(effects
							(font
								(size 1.27 1.27)
							)
						)
					)
				)
				(pin bidirectional line
					(at 0 -109.22 0)
					(length 5.08)
					(name "IO_L19N_T3L_N1_DBC_AD9N_66"
						(effects
							(font
								(size 1.27 1.27)
							)
						)
					)
					(number "E26"
						(effects
							(font
								(size 1.27 1.27)
							)
						)
					)
				)
				(pin bidirectional line
					(at 0 -111.76 0)
					(length 5.08)
					(name "IO_L20P_T3L_N2_AD1P_66"
						(effects
							(font
								(size 1.27 1.27)
							)
						)
					)
					(number "F23"
						(effects
							(font
								(size 1.27 1.27)
							)
						)
					)
				)
				(pin bidirectional line
					(at 0 -114.3 0)
					(length 5.08)
					(name "IO_L20N_T3L_N3_AD1N_66"
						(effects
							(font
								(size 1.27 1.27)
							)
						)
					)
					(number "E23"
						(effects
							(font
								(size 1.27 1.27)
							)
						)
					)
				)
				(pin bidirectional line
					(at 0 -116.84 0)
					(length 5.08)
					(name "IO_L21P_T3L_N4_AD8P_66"
						(effects
							(font
								(size 1.27 1.27)
							)
						)
					)
					(number "D24"
						(effects
							(font
								(size 1.27 1.27)
							)
						)
					)
				)
				(pin bidirectional line
					(at 0 -119.38 0)
					(length 5.08)
					(name "IO_L21N_T3L_N5_AD8N_66"
						(effects
							(font
								(size 1.27 1.27)
							)
						)
					)
					(number "D25"
						(effects
							(font
								(size 1.27 1.27)
							)
						)
					)
				)
				(pin bidirectional line
					(at 0 -121.92 0)
					(length 5.08)
					(name "IO_L22P_T3U_N6_DBC_AD0P_66"
						(effects
							(font
								(size 1.27 1.27)
							)
						)
					)
					(number "D23"
						(effects
							(font
								(size 1.27 1.27)
							)
						)
					)
				)
				(pin bidirectional line
					(at 0 -124.46 0)
					(length 5.08)
					(name "IO_L22N_T3U_N7_DBC_AD0N_66"
						(effects
							(font
								(size 1.27 1.27)
							)
						)
					)
					(number "C24"
						(effects
							(font
								(size 1.27 1.27)
							)
						)
					)
				)
				(pin bidirectional line
					(at 0 -127 0)
					(length 5.08)
					(name "IO_L23P_T3U_N8_66"
						(effects
							(font
								(size 1.27 1.27)
							)
						)
					)
					(number "D26"
						(effects
							(font
								(size 1.27 1.27)
							)
						)
					)
				)
				(pin bidirectional line
					(at 0 -129.54 0)
					(length 5.08)
					(name "IO_L23N_T3U_N9_66"
						(effects
							(font
								(size 1.27 1.27)
							)
						)
					)
					(number "C26"
						(effects
							(font
								(size 1.27 1.27)
							)
						)
					)
				)
				(pin bidirectional line
					(at 0 -132.08 0)
					(length 5.08)
					(name "IO_L24P_T3U_N10_66"
						(effects
							(font
								(size 1.27 1.27)
							)
						)
					)
					(number "B25"
						(effects
							(font
								(size 1.27 1.27)
							)
						)
					)
				)
				(pin bidirectional line
					(at 0 -134.62 0)
					(length 5.08)
					(name "IO_L24N_T3U_N11_66"
						(effects
							(font
								(size 1.27 1.27)
							)
						)
					)
					(number "B26"
						(effects
							(font
								(size 1.27 1.27)
							)
						)
					)
				)
				(pin bidirectional line
					(at 0 -137.16 0)
					(length 5.08)
					(name "IO_T3U_N12_66"
						(effects
							(font
								(size 1.27 1.27)
							)
						)
					)
					(number "F22"
						(effects
							(font
								(size 1.27 1.27)
							)
						)
					)
				)
			)
			(symbol "XCAU25P-2FFVB676I_1_5_1"
				(rectangle
					(start 5.08 2.54)
					(end 43.18 -142.24)
					(stroke
						(width 0.254)
						(type default)
					)
					(fill
						(type background)
					)
				)
				(polyline
					(pts
						(xy 30.48 -6.35) (xy 39.37 -6.35) (xy 39.37 -138.43) (xy 31.75 -138.43)
					)
					(stroke
						(width 0.254)
						(type default)
					)
					(fill
						(type background)
					)
				)
				(text "BANK 67"
					(at 30.48 -5.08 0)
					(effects
						(font
							(size 1.27 1.27)
							(thickness 0.15)
						)
						(justify left bottom)
					)
				)
				(text ""
					(at 50.8 -31.75 0)
					(effects
						(font
							(size 1.27 1.27)
							(thickness 0.15)
						)
						(justify left bottom)
					)
				)
				(text ""
					(at 50.8 -31.75 0)
					(effects
						(font
							(size 1.27 1.27)
							(thickness 0.15)
						)
						(justify left bottom)
					)
				)
				(pin power_in line
					(at 0 0 0)
					(length 5.08)
					(name "VCCO_67"
						(effects
							(font
								(size 1.27 1.27)
							)
						)
					)
					(number "C20"
						(effects
							(font
								(size 1.27 1.27)
							)
						)
					)
				)
				(pin passive line
					(at 0 0 0)
					(length 5.08)
					(hide yes)
					(name "VCCO_67"
						(effects
							(font
								(size 1.27 1.27)
							)
						)
					)
					(number "D17"
						(effects
							(font
								(size 1.27 1.27)
							)
						)
					)
				)
				(pin passive line
					(at 0 0 0)
					(length 5.08)
					(hide yes)
					(name "VCCO_67"
						(effects
							(font
								(size 1.27 1.27)
							)
						)
					)
					(number "G18"
						(effects
							(font
								(size 1.27 1.27)
							)
						)
					)
				)
				(pin input line
					(at 0 -2.54 0)
					(length 5.08)
					(name "VREF_67"
						(effects
							(font
								(size 1.27 1.27)
							)
						)
					)
					(number "J16"
						(effects
							(font
								(size 1.27 1.27)
							)
						)
					)
				)
				(pin bidirectional line
					(at 0 -7.62 0)
					(length 5.08)
					(name "IO_L1P_T0L_N0_DBC_67"
						(effects
							(font
								(size 1.27 1.27)
							)
						)
					)
					(number "G15"
						(effects
							(font
								(size 1.27 1.27)
							)
						)
					)
				)
				(pin bidirectional line
					(at 0 -10.16 0)
					(length 5.08)
					(name "IO_L1N_T0L_N1_DBC_67"
						(effects
							(font
								(size 1.27 1.27)
							)
						)
					)
					(number "F15"
						(effects
							(font
								(size 1.27 1.27)
							)
						)
					)
				)
				(pin bidirectional line
					(at 0 -12.7 0)
					(length 5.08)
					(name "IO_L2P_T0L_N2_67"
						(effects
							(font
								(size 1.27 1.27)
							)
						)
					)
					(number "H17"
						(effects
							(font
								(size 1.27 1.27)
							)
						)
					)
				)
				(pin bidirectional line
					(at 0 -15.24 0)
					(length 5.08)
					(name "IO_L2N_T0L_N3_67"
						(effects
							(font
								(size 1.27 1.27)
							)
						)
					)
					(number "G17"
						(effects
							(font
								(size 1.27 1.27)
							)
						)
					)
				)
				(pin bidirectional line
					(at 0 -17.78 0)
					(length 5.08)
					(name "IO_L3P_T0L_N4_AD15P_67"
						(effects
							(font
								(size 1.27 1.27)
							)
						)
					)
					(number "E15"
						(effects
							(font
								(size 1.27 1.27)
							)
						)
					)
				)
				(pin bidirectional line
					(at 0 -20.32 0)
					(length 5.08)
					(name "IO_L3N_T0L_N5_AD15N_67"
						(effects
							(font
								(size 1.27 1.27)
							)
						)
					)
					(number "D15"
						(effects
							(font
								(size 1.27 1.27)
							)
						)
					)
				)
				(pin bidirectional line
					(at 0 -22.86 0)
					(length 5.08)
					(name "IO_L4P_T0U_N6_DBC_AD7P_67"
						(effects
							(font
								(size 1.27 1.27)
							)
						)
					)
					(number "E16"
						(effects
							(font
								(size 1.27 1.27)
							)
						)
					)
				)
				(pin bidirectional line
					(at 0 -25.4 0)
					(length 5.08)
					(name "IO_L4N_T0U_N7_DBC_AD7N_67"
						(effects
							(font
								(size 1.27 1.27)
							)
						)
					)
					(number "E17"
						(effects
							(font
								(size 1.27 1.27)
							)
						)
					)
				)
				(pin bidirectional line
					(at 0 -27.94 0)
					(length 5.08)
					(name "IO_L5P_T0U_N8_AD14P_67"
						(effects
							(font
								(size 1.27 1.27)
							)
						)
					)
					(number "H16"
						(effects
							(font
								(size 1.27 1.27)
							)
						)
					)
				)
				(pin bidirectional line
					(at 0 -30.48 0)
					(length 5.08)
					(name "IO_L5N_T0U_N9_AD14N_67"
						(effects
							(font
								(size 1.27 1.27)
							)
						)
					)
					(number "G16"
						(effects
							(font
								(size 1.27 1.27)
							)
						)
					)
				)
				(pin bidirectional line
					(at 0 -33.02 0)
					(length 5.08)
					(name "IO_L6P_T0U_N10_AD6P_67"
						(effects
							(font
								(size 1.27 1.27)
							)
						)
					)
					(number "D16"
						(effects
							(font
								(size 1.27 1.27)
							)
						)
					)
				)
				(pin bidirectional line
					(at 0 -35.56 0)
					(length 5.08)
					(name "IO_L6N_T0U_N11_AD6N_67"
						(effects
							(font
								(size 1.27 1.27)
							)
						)
					)
					(number "C16"
						(effects
							(font
								(size 1.27 1.27)
							)
						)
					)
				)
				(pin bidirectional line
					(at 0 -38.1 0)
					(length 5.08)
					(name "IO_T0U_N12_VRP_67"
						(effects
							(font
								(size 1.27 1.27)
							)
						)
					)
					(number "F17"
						(effects
							(font
								(size 1.27 1.27)
							)
						)
					)
				)
				(pin bidirectional line
					(at 0 -40.64 0)
					(length 5.08)
					(name "IO_L7P_T1L_N0_QBC_AD13P_67"
						(effects
							(font
								(size 1.27 1.27)
							)
						)
					)
					(number "H18"
						(effects
							(font
								(size 1.27 1.27)
							)
						)
					)
				)
				(pin bidirectional line
					(at 0 -43.18 0)
					(length 5.08)
					(name "IO_L7N_T1L_N1_QBC_AD13N_67"
						(effects
							(font
								(size 1.27 1.27)
							)
						)
					)
					(number "H19"
						(effects
							(font
								(size 1.27 1.27)
							)
						)
					)
				)
				(pin bidirectional line
					(at 0 -45.72 0)
					(length 5.08)
					(name "IO_L8P_T1L_N2_AD5P_67"
						(effects
							(font
								(size 1.27 1.27)
							)
						)
					)
					(number "F18"
						(effects
							(font
								(size 1.27 1.27)
							)
						)
					)
				)
				(pin bidirectional line
					(at 0 -48.26 0)
					(length 5.08)
					(name "IO_L8N_T1L_N3_AD5N_67"
						(effects
							(font
								(size 1.27 1.27)
							)
						)
					)
					(number "F19"
						(effects
							(font
								(size 1.27 1.27)
							)
						)
					)
				)
				(pin bidirectional line
					(at 0 -50.8 0)
					(length 5.08)
					(name "IO_L9P_T1L_N4_AD12P_67"
						(effects
							(font
								(size 1.27 1.27)
							)
						)
					)
					(number "G20"
						(effects
							(font
								(size 1.27 1.27)
							)
						)
					)
				)
				(pin bidirectional line
					(at 0 -53.34 0)
					(length 5.08)
					(name "IO_L9N_T1L_N5_AD12N_67"
						(effects
							(font
								(size 1.27 1.27)
							)
						)
					)
					(number "G21"
						(effects
							(font
								(size 1.27 1.27)
							)
						)
					)
				)
				(pin bidirectional line
					(at 0 -55.88 0)
					(length 5.08)
					(name "IO_L10P_T1U_N6_QBC_AD4P_67"
						(effects
							(font
								(size 1.27 1.27)
							)
						)
					)
					(number "F20"
						(effects
							(font
								(size 1.27 1.27)
							)
						)
					)
				)
				(pin bidirectional line
					(at 0 -58.42 0)
					(length 5.08)
					(name "IO_L10N_T1U_N7_QBC_AD4N_67"
						(effects
							(font
								(size 1.27 1.27)
							)
						)
					)
					(number "E20"
						(effects
							(font
								(size 1.27 1.27)
							)
						)
					)
				)
				(pin bidirectional line
					(at 0 -60.96 0)
					(length 5.08)
					(name "IO_L11P_T1U_N8_GC_67"
						(effects
							(font
								(size 1.27 1.27)
							)
						)
					)
					(number "E18"
						(effects
							(font
								(size 1.27 1.27)
							)
						)
					)
				)
				(pin bidirectional line
					(at 0 -63.5 0)
					(length 5.08)
					(name "IO_L11N_T1U_N9_GC_67"
						(effects
							(font
								(size 1.27 1.27)
							)
						)
					)
					(number "D18"
						(effects
							(font
								(size 1.27 1.27)
							)
						)
					)
				)
				(pin bidirectional line
					(at 0 -66.04 0)
					(length 5.08)
					(name "IO_L12P_T1U_N10_GC_67"
						(effects
							(font
								(size 1.27 1.27)
							)
						)
					)
					(number "D19"
						(effects
							(font
								(size 1.27 1.27)
							)
						)
					)
				)
				(pin bidirectional line
					(at 0 -68.58 0)
					(length 5.08)
					(name "IO_L12N_T1U_N11_GC_67"
						(effects
							(font
								(size 1.27 1.27)
							)
						)
					)
					(number "D20"
						(effects
							(font
								(size 1.27 1.27)
							)
						)
					)
				)
				(pin bidirectional line
					(at 0 -71.12 0)
					(length 5.08)
					(name "IO_T1U_N12_67"
						(effects
							(font
								(size 1.27 1.27)
							)
						)
					)
					(number "G19"
						(effects
							(font
								(size 1.27 1.27)
							)
						)
					)
				)
				(pin bidirectional line
					(at 0 -73.66 0)
					(length 5.08)
					(name "IO_L13P_T2L_N0_GC_QBC_67"
						(effects
							(font
								(size 1.27 1.27)
							)
						)
					)
					(number "C18"
						(effects
							(font
								(size 1.27 1.27)
							)
						)
					)
				)
				(pin bidirectional line
					(at 0 -76.2 0)
					(length 5.08)
					(name "IO_L13N_T2L_N1_GC_QBC_67"
						(effects
							(font
								(size 1.27 1.27)
							)
						)
					)
					(number "C19"
						(effects
							(font
								(size 1.27 1.27)
							)
						)
					)
				)
				(pin bidirectional line
					(at 0 -78.74 0)
					(length 5.08)
					(name "IO_L14P_T2L_N2_GC_67"
						(effects
							(font
								(size 1.27 1.27)
							)
						)
					)
					(number "B19"
						(effects
							(font
								(size 1.27 1.27)
							)
						)
					)
				)
				(pin bidirectional line
					(at 0 -81.28 0)
					(length 5.08)
					(name "IO_L14N_T2L_N3_GC_67"
						(effects
							(font
								(size 1.27 1.27)
							)
						)
					)
					(number "B20"
						(effects
							(font
								(size 1.27 1.27)
							)
						)
					)
				)
				(pin bidirectional line
					(at 0 -83.82 0)
					(length 5.08)
					(name "IO_L15P_T2L_N4_AD11P_67"
						(effects
							(font
								(size 1.27 1.27)
							)
						)
					)
					(number "C17"
						(effects
							(font
								(size 1.27 1.27)
							)
						)
					)
				)
				(pin bidirectional line
					(at 0 -86.36 0)
					(length 5.08)
					(name "IO_L15N_T2L_N5_AD11N_67"
						(effects
							(font
								(size 1.27 1.27)
							)
						)
					)
					(number "B17"
						(effects
							(font
								(size 1.27 1.27)
							)
						)
					)
				)
				(pin bidirectional line
					(at 0 -88.9 0)
					(length 5.08)
					(name "IO_L16P_T2U_N6_QBC_AD3P_67"
						(effects
							(font
								(size 1.27 1.27)
							)
						)
					)
					(number "A17"
						(effects
							(font
								(size 1.27 1.27)
							)
						)
					)
				)
				(pin bidirectional line
					(at 0 -91.44 0)
					(length 5.08)
					(name "IO_L16N_T2U_N7_QBC_AD3N_67"
						(effects
							(font
								(size 1.27 1.27)
							)
						)
					)
					(number "A18"
						(effects
							(font
								(size 1.27 1.27)
							)
						)
					)
				)
				(pin bidirectional line
					(at 0 -93.98 0)
					(length 5.08)
					(name "IO_L17P_T2U_N8_AD10P_67"
						(effects
							(font
								(size 1.27 1.27)
							)
						)
					)
					(number "B15"
						(effects
							(font
								(size 1.27 1.27)
							)
						)
					)
				)
				(pin bidirectional line
					(at 0 -96.52 0)
					(length 5.08)
					(name "IO_L17N_T2U_N9_AD10N_67"
						(effects
							(font
								(size 1.27 1.27)
							)
						)
					)
					(number "A15"
						(effects
							(font
								(size 1.27 1.27)
							)
						)
					)
				)
				(pin bidirectional line
					(at 0 -99.06 0)
					(length 5.08)
					(name "IO_L18P_T2U_N10_AD2P_67"
						(effects
							(font
								(size 1.27 1.27)
							)
						)
					)
					(number "A19"
						(effects
							(font
								(size 1.27 1.27)
							)
						)
					)
				)
				(pin bidirectional line
					(at 0 -101.6 0)
					(length 5.08)
					(name "IO_L18N_T2U_N11_AD2N_67"
						(effects
							(font
								(size 1.27 1.27)
							)
						)
					)
					(number "A20"
						(effects
							(font
								(size 1.27 1.27)
							)
						)
					)
				)
				(pin bidirectional line
					(at 0 -104.14 0)
					(length 5.08)
					(name "IO_T2U_N12_67"
						(effects
							(font
								(size 1.27 1.27)
							)
						)
					)
					(number "B16"
						(effects
							(font
								(size 1.27 1.27)
							)
						)
					)
				)
				(pin bidirectional line
					(at 0 -106.68 0)
					(length 5.08)
					(name "IO_L19P_T3L_N0_DBC_AD9P_67"
						(effects
							(font
								(size 1.27 1.27)
							)
						)
					)
					(number "A22"
						(effects
							(font
								(size 1.27 1.27)
							)
						)
					)
				)
				(pin bidirectional line
					(at 0 -109.22 0)
					(length 5.08)
					(name "IO_L19N_T3L_N1_DBC_AD9N_67"
						(effects
							(font
								(size 1.27 1.27)
							)
						)
					)
					(number "A23"
						(effects
							(font
								(size 1.27 1.27)
							)
						)
					)
				)
				(pin bidirectional line
					(at 0 -111.76 0)
					(length 5.08)
					(name "IO_L20P_T3L_N2_AD1P_67"
						(effects
							(font
								(size 1.27 1.27)
							)
						)
					)
					(number "E21"
						(effects
							(font
								(size 1.27 1.27)
							)
						)
					)
				)
				(pin bidirectional line
					(at 0 -114.3 0)
					(length 5.08)
					(name "IO_L20N_T3L_N3_AD1N_67"
						(effects
							(font
								(size 1.27 1.27)
							)
						)
					)
					(number "D21"
						(effects
							(font
								(size 1.27 1.27)
							)
						)
					)
				)
				(pin bidirectional line
					(at 0 -116.84 0)
					(length 5.08)
					(name "IO_L21P_T3L_N4_AD8P_67"
						(effects
							(font
								(size 1.27 1.27)
							)
						)
					)
					(number "C23"
						(effects
							(font
								(size 1.27 1.27)
							)
						)
					)
				)
				(pin bidirectional line
					(at 0 -119.38 0)
					(length 5.08)
					(name "IO_L21N_T3L_N5_AD8N_67"
						(effects
							(font
								(size 1.27 1.27)
							)
						)
					)
					(number "B24"
						(effects
							(font
								(size 1.27 1.27)
							)
						)
					)
				)
				(pin bidirectional line
					(at 0 -121.92 0)
					(length 5.08)
					(name "IO_L22P_T3U_N6_DBC_AD0P_67"
						(effects
							(font
								(size 1.27 1.27)
							)
						)
					)
					(number "C21"
						(effects
							(font
								(size 1.27 1.27)
							)
						)
					)
				)
				(pin bidirectional line
					(at 0 -124.46 0)
					(length 5.08)
					(name "IO_L22N_T3U_N7_DBC_AD0N_67"
						(effects
							(font
								(size 1.27 1.27)
							)
						)
					)
					(number "B21"
						(effects
							(font
								(size 1.27 1.27)
							)
						)
					)
				)
				(pin bidirectional line
					(at 0 -127 0)
					(length 5.08)
					(name "IO_L23P_T3U_N8_67"
						(effects
							(font
								(size 1.27 1.27)
							)
						)
					)
					(number "A24"
						(effects
							(font
								(size 1.27 1.27)
							)
						)
					)
				)
				(pin bidirectional line
					(at 0 -129.54 0)
					(length 5.08)
					(name "IO_L23N_T3U_N9_67"
						(effects
							(font
								(size 1.27 1.27)
							)
						)
					)
					(number "A25"
						(effects
							(font
								(size 1.27 1.27)
							)
						)
					)
				)
				(pin bidirectional line
					(at 0 -132.08 0)
					(length 5.08)
					(name "IO_L24P_T3U_N10_67"
						(effects
							(font
								(size 1.27 1.27)
							)
						)
					)
					(number "C22"
						(effects
							(font
								(size 1.27 1.27)
							)
						)
					)
				)
				(pin bidirectional line
					(at 0 -134.62 0)
					(length 5.08)
					(name "IO_L24N_T3U_N11_67"
						(effects
							(font
								(size 1.27 1.27)
							)
						)
					)
					(number "B22"
						(effects
							(font
								(size 1.27 1.27)
							)
						)
					)
				)
				(pin bidirectional line
					(at 0 -137.16 0)
					(length 5.08)
					(name "IO_T3U_N12_67"
						(effects
							(font
								(size 1.27 1.27)
							)
						)
					)
					(number "E22"
						(effects
							(font
								(size 1.27 1.27)
							)
						)
					)
				)
			)
			(symbol "XCAU25P-2FFVB676I_1_6_1"
				(rectangle
					(start 5.08 2.54)
					(end 33.02 -68.58)
					(stroke
						(width 0.254)
						(type default)
					)
					(fill
						(type background)
					)
				)
				(polyline
					(pts
						(xy 22.86 -3.81) (xy 30.48 -3.81) (xy 30.48 -64.77) (xy 22.86 -64.77)
					)
					(stroke
						(width 0.254)
						(type default)
					)
					(fill
						(type background)
					)
				)
				(text "BANK 84"
					(at 22.86 -2.54 0)
					(effects
						(font
							(size 1.27 1.27)
							(thickness 0.15)
						)
						(justify left bottom)
					)
				)
				(text ""
					(at 50.8 -31.75 0)
					(effects
						(font
							(size 1.27 1.27)
							(thickness 0.15)
						)
						(justify left bottom)
					)
				)
				(text ""
					(at 50.8 -31.75 0)
					(effects
						(font
							(size 1.27 1.27)
							(thickness 0.15)
						)
						(justify left bottom)
					)
				)
				(pin power_in line
					(at 0 0 0)
					(length 5.08)
					(name "VCCO_84"
						(effects
							(font
								(size 1.27 1.27)
							)
						)
					)
					(number "AC15"
						(effects
							(font
								(size 1.27 1.27)
							)
						)
					)
				)
				(pin passive line
					(at 0 0 0)
					(length 5.08)
					(hide yes)
					(name "VCCO_84"
						(effects
							(font
								(size 1.27 1.27)
							)
						)
					)
					(number "Y14"
						(effects
							(font
								(size 1.27 1.27)
							)
						)
					)
				)
				(pin bidirectional line
					(at 0 -5.08 0)
					(length 5.08)
					(name "IO_L1P_AD11P_84"
						(effects
							(font
								(size 1.27 1.27)
							)
						)
					)
					(number "AF14"
						(effects
							(font
								(size 1.27 1.27)
							)
						)
					)
				)
				(pin bidirectional line
					(at 0 -7.62 0)
					(length 5.08)
					(name "IO_L1N_AD11N_84"
						(effects
							(font
								(size 1.27 1.27)
							)
						)
					)
					(number "AF15"
						(effects
							(font
								(size 1.27 1.27)
							)
						)
					)
				)
				(pin bidirectional line
					(at 0 -10.16 0)
					(length 5.08)
					(name "IO_L2P_AD10P_84"
						(effects
							(font
								(size 1.27 1.27)
							)
						)
					)
					(number "AE13"
						(effects
							(font
								(size 1.27 1.27)
							)
						)
					)
				)
				(pin bidirectional line
					(at 0 -12.7 0)
					(length 5.08)
					(name "IO_L2N_AD10N_84"
						(effects
							(font
								(size 1.27 1.27)
							)
						)
					)
					(number "AF13"
						(effects
							(font
								(size 1.27 1.27)
							)
						)
					)
				)
				(pin bidirectional line
					(at 0 -15.24 0)
					(length 5.08)
					(name "IO_L3P_AD9P_84"
						(effects
							(font
								(size 1.27 1.27)
							)
						)
					)
					(number "AD15"
						(effects
							(font
								(size 1.27 1.27)
							)
						)
					)
				)
				(pin bidirectional line
					(at 0 -17.78 0)
					(length 5.08)
					(name "IO_L3N_AD9N_84"
						(effects
							(font
								(size 1.27 1.27)
							)
						)
					)
					(number "AE15"
						(effects
							(font
								(size 1.27 1.27)
							)
						)
					)
				)
				(pin bidirectional line
					(at 0 -20.32 0)
					(length 5.08)
					(name "IO_L4P_AD8P_84"
						(effects
							(font
								(size 1.27 1.27)
							)
						)
					)
					(number "AD13"
						(effects
							(font
								(size 1.27 1.27)
							)
						)
					)
				)
				(pin bidirectional line
					(at 0 -22.86 0)
					(length 5.08)
					(name "IO_L4N_AD8N_84"
						(effects
							(font
								(size 1.27 1.27)
							)
						)
					)
					(number "AD14"
						(effects
							(font
								(size 1.27 1.27)
							)
						)
					)
				)
				(pin bidirectional line
					(at 0 -25.4 0)
					(length 5.08)
					(name "IO_L5P_HDGC_AD7P_84"
						(effects
							(font
								(size 1.27 1.27)
							)
						)
					)
					(number "AC13"
						(effects
							(font
								(size 1.27 1.27)
							)
						)
					)
				)
				(pin bidirectional line
					(at 0 -27.94 0)
					(length 5.08)
					(name "IO_L5N_HDGC_AD7N_84"
						(effects
							(font
								(size 1.27 1.27)
							)
						)
					)
					(number "AC14"
						(effects
							(font
								(size 1.27 1.27)
							)
						)
					)
				)
				(pin bidirectional line
					(at 0 -30.48 0)
					(length 5.08)
					(name "IO_L6P_HDGC_AD6P_84"
						(effects
							(font
								(size 1.27 1.27)
							)
						)
					)
					(number "AB15"
						(effects
							(font
								(size 1.27 1.27)
							)
						)
					)
				)
				(pin bidirectional line
					(at 0 -33.02 0)
					(length 5.08)
					(name "IO_L6N_HDGC_AD6N_84"
						(effects
							(font
								(size 1.27 1.27)
							)
						)
					)
					(number "AB16"
						(effects
							(font
								(size 1.27 1.27)
							)
						)
					)
				)
				(pin bidirectional line
					(at 0 -35.56 0)
					(length 5.08)
					(name "IO_L7P_HDGC_AD5P_84"
						(effects
							(font
								(size 1.27 1.27)
							)
						)
					)
					(number "Y15"
						(effects
							(font
								(size 1.27 1.27)
							)
						)
					)
				)
				(pin bidirectional line
					(at 0 -38.1 0)
					(length 5.08)
					(name "IO_L7N_HDGC_AD5N_84"
						(effects
							(font
								(size 1.27 1.27)
							)
						)
					)
					(number "AA15"
						(effects
							(font
								(size 1.27 1.27)
							)
						)
					)
				)
				(pin bidirectional line
					(at 0 -40.64 0)
					(length 5.08)
					(name "IO_L8P_HDGC_AD4P_84"
						(effects
							(font
								(size 1.27 1.27)
							)
						)
					)
					(number "AA14"
						(effects
							(font
								(size 1.27 1.27)
							)
						)
					)
				)
				(pin bidirectional line
					(at 0 -43.18 0)
					(length 5.08)
					(name "IO_L8N_HDGC_AD4N_84"
						(effects
							(font
								(size 1.27 1.27)
							)
						)
					)
					(number "AB14"
						(effects
							(font
								(size 1.27 1.27)
							)
						)
					)
				)
				(pin bidirectional line
					(at 0 -45.72 0)
					(length 5.08)
					(name "IO_L9P_AD3P_84"
						(effects
							(font
								(size 1.27 1.27)
							)
						)
					)
					(number "W16"
						(effects
							(font
								(size 1.27 1.27)
							)
						)
					)
				)
				(pin bidirectional line
					(at 0 -48.26 0)
					(length 5.08)
					(name "IO_L9N_AD3N_84"
						(effects
							(font
								(size 1.27 1.27)
							)
						)
					)
					(number "Y16"
						(effects
							(font
								(size 1.27 1.27)
							)
						)
					)
				)
				(pin bidirectional line
					(at 0 -50.8 0)
					(length 5.08)
					(name "IO_L10P_AD2P_84"
						(effects
							(font
								(size 1.27 1.27)
							)
						)
					)
					(number "W14"
						(effects
							(font
								(size 1.27 1.27)
							)
						)
					)
				)
				(pin bidirectional line
					(at 0 -53.34 0)
					(length 5.08)
					(name "IO_L10N_AD2N_84"
						(effects
							(font
								(size 1.27 1.27)
							)
						)
					)
					(number "W15"
						(effects
							(font
								(size 1.27 1.27)
							)
						)
					)
				)
				(pin bidirectional line
					(at 0 -55.88 0)
					(length 5.08)
					(name "IO_L11P_AD1P_84"
						(effects
							(font
								(size 1.27 1.27)
							)
						)
					)
					(number "Y13"
						(effects
							(font
								(size 1.27 1.27)
							)
						)
					)
				)
				(pin bidirectional line
					(at 0 -58.42 0)
					(length 5.08)
					(name "IO_L11N_AD1N_84"
						(effects
							(font
								(size 1.27 1.27)
							)
						)
					)
					(number "AA13"
						(effects
							(font
								(size 1.27 1.27)
							)
						)
					)
				)
				(pin bidirectional line
					(at 0 -60.96 0)
					(length 5.08)
					(name "IO_L12P_AD0P_84"
						(effects
							(font
								(size 1.27 1.27)
							)
						)
					)
					(number "W12"
						(effects
							(font
								(size 1.27 1.27)
							)
						)
					)
				)
				(pin bidirectional line
					(at 0 -63.5 0)
					(length 5.08)
					(name "IO_L12N_AD0N_84"
						(effects
							(font
								(size 1.27 1.27)
							)
						)
					)
					(number "W13"
						(effects
							(font
								(size 1.27 1.27)
							)
						)
					)
				)
			)
			(symbol "XCAU25P-2FFVB676I_1_7_1"
				(rectangle
					(start 5.08 2.54)
					(end 33.02 -68.58)
					(stroke
						(width 0.254)
						(type default)
					)
					(fill
						(type background)
					)
				)
				(polyline
					(pts
						(xy 22.86 -3.81) (xy 30.48 -3.81) (xy 30.48 -64.77) (xy 22.86 -64.77)
					)
					(stroke
						(width 0.254)
						(type default)
					)
					(fill
						(type background)
					)
				)
				(text "BANK 86"
					(at 22.86 -2.54 0)
					(effects
						(font
							(size 1.27 1.27)
							(thickness 0.15)
						)
						(justify left bottom)
					)
				)
				(text ""
					(at 50.8 -31.75 0)
					(effects
						(font
							(size 1.27 1.27)
							(thickness 0.15)
						)
						(justify left bottom)
					)
				)
				(text ""
					(at 50.8 -31.75 0)
					(effects
						(font
							(size 1.27 1.27)
							(thickness 0.15)
						)
						(justify left bottom)
					)
				)
				(pin power_in line
					(at 0 0 0)
					(length 5.08)
					(name "VCCO_86"
						(effects
							(font
								(size 1.27 1.27)
							)
						)
					)
					(number "E9"
						(effects
							(font
								(size 1.27 1.27)
							)
						)
					)
				)
				(pin passive line
					(at 0 0 0)
					(length 5.08)
					(hide yes)
					(name "VCCO_86"
						(effects
							(font
								(size 1.27 1.27)
							)
						)
					)
					(number "H10"
						(effects
							(font
								(size 1.27 1.27)
							)
						)
					)
				)
				(pin bidirectional line
					(at 0 -5.08 0)
					(length 5.08)
					(name "IO_L1P_AD11P_86"
						(effects
							(font
								(size 1.27 1.27)
							)
						)
					)
					(number "K10"
						(effects
							(font
								(size 1.27 1.27)
							)
						)
					)
				)
				(pin bidirectional line
					(at 0 -7.62 0)
					(length 5.08)
					(name "IO_L1N_AD11N_86"
						(effects
							(font
								(size 1.27 1.27)
							)
						)
					)
					(number "K9"
						(effects
							(font
								(size 1.27 1.27)
							)
						)
					)
				)
				(pin bidirectional line
					(at 0 -10.16 0)
					(length 5.08)
					(name "IO_L2P_AD10P_86"
						(effects
							(font
								(size 1.27 1.27)
							)
						)
					)
					(number "J11"
						(effects
							(font
								(size 1.27 1.27)
							)
						)
					)
				)
				(pin bidirectional line
					(at 0 -12.7 0)
					(length 5.08)
					(name "IO_L2N_AD10N_86"
						(effects
							(font
								(size 1.27 1.27)
							)
						)
					)
					(number "J10"
						(effects
							(font
								(size 1.27 1.27)
							)
						)
					)
				)
				(pin bidirectional line
					(at 0 -15.24 0)
					(length 5.08)
					(name "IO_L3P_AD9P_86"
						(effects
							(font
								(size 1.27 1.27)
							)
						)
					)
					(number "J9"
						(effects
							(font
								(size 1.27 1.27)
							)
						)
					)
				)
				(pin bidirectional line
					(at 0 -17.78 0)
					(length 5.08)
					(name "IO_L3N_AD9N_86"
						(effects
							(font
								(size 1.27 1.27)
							)
						)
					)
					(number "H9"
						(effects
							(font
								(size 1.27 1.27)
							)
						)
					)
				)
				(pin bidirectional line
					(at 0 -20.32 0)
					(length 5.08)
					(name "IO_L4P_AD8P_86"
						(effects
							(font
								(size 1.27 1.27)
							)
						)
					)
					(number "H11"
						(effects
							(font
								(size 1.27 1.27)
							)
						)
					)
				)
				(pin bidirectional line
					(at 0 -22.86 0)
					(length 5.08)
					(name "IO_L4N_AD8N_86"
						(effects
							(font
								(size 1.27 1.27)
							)
						)
					)
					(number "G11"
						(effects
							(font
								(size 1.27 1.27)
							)
						)
					)
				)
				(pin bidirectional line
					(at 0 -25.4 0)
					(length 5.08)
					(name "IO_L5P_HDGC_AD7P_86"
						(effects
							(font
								(size 1.27 1.27)
							)
						)
					)
					(number "G10"
						(effects
							(font
								(size 1.27 1.27)
							)
						)
					)
				)
				(pin bidirectional line
					(at 0 -27.94 0)
					(length 5.08)
					(name "IO_L5N_HDGC_AD7N_86"
						(effects
							(font
								(size 1.27 1.27)
							)
						)
					)
					(number "G9"
						(effects
							(font
								(size 1.27 1.27)
							)
						)
					)
				)
				(pin bidirectional line
					(at 0 -30.48 0)
					(length 5.08)
					(name "IO_L6P_HDGC_AD6P_86"
						(effects
							(font
								(size 1.27 1.27)
							)
						)
					)
					(number "F10"
						(effects
							(font
								(size 1.27 1.27)
							)
						)
					)
				)
				(pin bidirectional line
					(at 0 -33.02 0)
					(length 5.08)
					(name "IO_L6N_HDGC_AD6N_86"
						(effects
							(font
								(size 1.27 1.27)
							)
						)
					)
					(number "F9"
						(effects
							(font
								(size 1.27 1.27)
							)
						)
					)
				)
				(pin bidirectional line
					(at 0 -35.56 0)
					(length 5.08)
					(name "IO_L7P_HDGC_AD5P_86"
						(effects
							(font
								(size 1.27 1.27)
							)
						)
					)
					(number "E11"
						(effects
							(font
								(size 1.27 1.27)
							)
						)
					)
				)
				(pin bidirectional line
					(at 0 -38.1 0)
					(length 5.08)
					(name "IO_L7N_HDGC_AD5N_86"
						(effects
							(font
								(size 1.27 1.27)
							)
						)
					)
					(number "E10"
						(effects
							(font
								(size 1.27 1.27)
							)
						)
					)
				)
				(pin bidirectional line
					(at 0 -40.64 0)
					(length 5.08)
					(name "IO_L8P_HDGC_AD4P_86"
						(effects
							(font
								(size 1.27 1.27)
							)
						)
					)
					(number "D11"
						(effects
							(font
								(size 1.27 1.27)
							)
						)
					)
				)
				(pin bidirectional line
					(at 0 -43.18 0)
					(length 5.08)
					(name "IO_L8N_HDGC_AD4N_86"
						(effects
							(font
								(size 1.27 1.27)
							)
						)
					)
					(number "D10"
						(effects
							(font
								(size 1.27 1.27)
							)
						)
					)
				)
				(pin bidirectional line
					(at 0 -45.72 0)
					(length 5.08)
					(name "IO_L9P_AD3P_86"
						(effects
							(font
								(size 1.27 1.27)
							)
						)
					)
					(number "D9"
						(effects
							(font
								(size 1.27 1.27)
							)
						)
					)
				)
				(pin bidirectional line
					(at 0 -48.26 0)
					(length 5.08)
					(name "IO_L9N_AD3N_86"
						(effects
							(font
								(size 1.27 1.27)
							)
						)
					)
					(number "C9"
						(effects
							(font
								(size 1.27 1.27)
							)
						)
					)
				)
				(pin bidirectional line
					(at 0 -50.8 0)
					(length 5.08)
					(name "IO_L10P_AD2P_86"
						(effects
							(font
								(size 1.27 1.27)
							)
						)
					)
					(number "B9"
						(effects
							(font
								(size 1.27 1.27)
							)
						)
					)
				)
				(pin bidirectional line
					(at 0 -53.34 0)
					(length 5.08)
					(name "IO_L10N_AD2N_86"
						(effects
							(font
								(size 1.27 1.27)
							)
						)
					)
					(number "A9"
						(effects
							(font
								(size 1.27 1.27)
							)
						)
					)
				)
				(pin bidirectional line
					(at 0 -55.88 0)
					(length 5.08)
					(name "IO_L11P_AD1P_86"
						(effects
							(font
								(size 1.27 1.27)
							)
						)
					)
					(number "B10"
						(effects
							(font
								(size 1.27 1.27)
							)
						)
					)
				)
				(pin bidirectional line
					(at 0 -58.42 0)
					(length 5.08)
					(name "IO_L11N_AD1N_86"
						(effects
							(font
								(size 1.27 1.27)
							)
						)
					)
					(number "A10"
						(effects
							(font
								(size 1.27 1.27)
							)
						)
					)
				)
				(pin bidirectional line
					(at 0 -60.96 0)
					(length 5.08)
					(name "IO_L12P_AD0P_86"
						(effects
							(font
								(size 1.27 1.27)
							)
						)
					)
					(number "C11"
						(effects
							(font
								(size 1.27 1.27)
							)
						)
					)
				)
				(pin bidirectional line
					(at 0 -63.5 0)
					(length 5.08)
					(name "IO_L12N_AD0N_86"
						(effects
							(font
								(size 1.27 1.27)
							)
						)
					)
					(number "B11"
						(effects
							(font
								(size 1.27 1.27)
							)
						)
					)
				)
			)
			(symbol "XCAU25P-2FFVB676I_1_8_1"
				(rectangle
					(start 5.08 2.54)
					(end 33.02 -67.31)
					(stroke
						(width 0.254)
						(type default)
					)
					(fill
						(type background)
					)
				)
				(polyline
					(pts
						(xy 22.86 -3.81) (xy 30.48 -3.81) (xy 30.48 -64.77) (xy 22.86 -64.77)
					)
					(stroke
						(width 0.254)
						(type default)
					)
					(fill
						(type background)
					)
				)
				(text "BANK 87"
					(at 22.86 -2.54 0)
					(effects
						(font
							(size 1.27 1.27)
							(thickness 0.15)
						)
						(justify left bottom)
					)
				)
				(text ""
					(at 50.8 -31.75 0)
					(effects
						(font
							(size 1.27 1.27)
							(thickness 0.15)
						)
						(justify left bottom)
					)
				)
				(text ""
					(at 50.8 -31.75 0)
					(effects
						(font
							(size 1.27 1.27)
							(thickness 0.15)
						)
						(justify left bottom)
					)
				)
				(pin power_in line
					(at 0 0 0)
					(length 5.08)
					(name "VCCO_87"
						(effects
							(font
								(size 1.27 1.27)
							)
						)
					)
					(number "E14"
						(effects
							(font
								(size 1.27 1.27)
							)
						)
					)
				)
				(pin passive line
					(at 0 0 0)
					(length 5.08)
					(hide yes)
					(name "VCCO_87"
						(effects
							(font
								(size 1.27 1.27)
							)
						)
					)
					(number "H15"
						(effects
							(font
								(size 1.27 1.27)
							)
						)
					)
				)
				(pin bidirectional line
					(at 0 -5.08 0)
					(length 5.08)
					(name "IO_L1P_AD15P_87"
						(effects
							(font
								(size 1.27 1.27)
							)
						)
					)
					(number "J12"
						(effects
							(font
								(size 1.27 1.27)
							)
						)
					)
				)
				(pin bidirectional line
					(at 0 -7.62 0)
					(length 5.08)
					(name "IO_L1N_AD15N_87"
						(effects
							(font
								(size 1.27 1.27)
							)
						)
					)
					(number "H12"
						(effects
							(font
								(size 1.27 1.27)
							)
						)
					)
				)
				(pin bidirectional line
					(at 0 -10.16 0)
					(length 5.08)
					(name "IO_L2P_AD14P_87"
						(effects
							(font
								(size 1.27 1.27)
							)
						)
					)
					(number "J13"
						(effects
							(font
								(size 1.27 1.27)
							)
						)
					)
				)
				(pin bidirectional line
					(at 0 -12.7 0)
					(length 5.08)
					(name "IO_L2N_AD14N_87"
						(effects
							(font
								(size 1.27 1.27)
							)
						)
					)
					(number "H13"
						(effects
							(font
								(size 1.27 1.27)
							)
						)
					)
				)
				(pin bidirectional line
					(at 0 -15.24 0)
					(length 5.08)
					(name "IO_L3P_AD13P_87"
						(effects
							(font
								(size 1.27 1.27)
							)
						)
					)
					(number "H14"
						(effects
							(font
								(size 1.27 1.27)
							)
						)
					)
				)
				(pin bidirectional line
					(at 0 -17.78 0)
					(length 5.08)
					(name "IO_L3N_AD13N_87"
						(effects
							(font
								(size 1.27 1.27)
							)
						)
					)
					(number "G14"
						(effects
							(font
								(size 1.27 1.27)
							)
						)
					)
				)
				(pin bidirectional line
					(at 0 -20.32 0)
					(length 5.08)
					(name "IO_L4P_AD12P_87"
						(effects
							(font
								(size 1.27 1.27)
							)
						)
					)
					(number "J15"
						(effects
							(font
								(size 1.27 1.27)
							)
						)
					)
				)
				(pin bidirectional line
					(at 0 -22.86 0)
					(length 5.08)
					(name "IO_L4N_AD12N_87"
						(effects
							(font
								(size 1.27 1.27)
							)
						)
					)
					(number "J14"
						(effects
							(font
								(size 1.27 1.27)
							)
						)
					)
				)
				(pin bidirectional line
					(at 0 -25.4 0)
					(length 5.08)
					(name "IO_L5P_HDGC_87"
						(effects
							(font
								(size 1.27 1.27)
							)
						)
					)
					(number "G12"
						(effects
							(font
								(size 1.27 1.27)
							)
						)
					)
				)
				(pin bidirectional line
					(at 0 -27.94 0)
					(length 5.08)
					(name "IO_L5N_HDGC_87"
						(effects
							(font
								(size 1.27 1.27)
							)
						)
					)
					(number "F12"
						(effects
							(font
								(size 1.27 1.27)
							)
						)
					)
				)
				(pin bidirectional line
					(at 0 -30.48 0)
					(length 5.08)
					(name "IO_L6P_HDGC_87"
						(effects
							(font
								(size 1.27 1.27)
							)
						)
					)
					(number "F14"
						(effects
							(font
								(size 1.27 1.27)
							)
						)
					)
				)
				(pin bidirectional line
					(at 0 -33.02 0)
					(length 5.08)
					(name "IO_L6N_HDGC_87"
						(effects
							(font
								(size 1.27 1.27)
							)
						)
					)
					(number "F13"
						(effects
							(font
								(size 1.27 1.27)
							)
						)
					)
				)
				(pin bidirectional line
					(at 0 -35.56 0)
					(length 5.08)
					(name "IO_L7P_HDGC_87"
						(effects
							(font
								(size 1.27 1.27)
							)
						)
					)
					(number "E13"
						(effects
							(font
								(size 1.27 1.27)
							)
						)
					)
				)
				(pin bidirectional line
					(at 0 -38.1 0)
					(length 5.08)
					(name "IO_L7N_HDGC_87"
						(effects
							(font
								(size 1.27 1.27)
							)
						)
					)
					(number "E12"
						(effects
							(font
								(size 1.27 1.27)
							)
						)
					)
				)
				(pin bidirectional line
					(at 0 -40.64 0)
					(length 5.08)
					(name "IO_L8P_HDGC_87"
						(effects
							(font
								(size 1.27 1.27)
							)
						)
					)
					(number "D14"
						(effects
							(font
								(size 1.27 1.27)
							)
						)
					)
				)
				(pin bidirectional line
					(at 0 -43.18 0)
					(length 5.08)
					(name "IO_L8N_HDGC_87"
						(effects
							(font
								(size 1.27 1.27)
							)
						)
					)
					(number "D13"
						(effects
							(font
								(size 1.27 1.27)
							)
						)
					)
				)
				(pin bidirectional line
					(at 0 -45.72 0)
					(length 5.08)
					(name "IO_L9P_AD11P_87"
						(effects
							(font
								(size 1.27 1.27)
							)
						)
					)
					(number "C14"
						(effects
							(font
								(size 1.27 1.27)
							)
						)
					)
				)
				(pin bidirectional line
					(at 0 -48.26 0)
					(length 5.08)
					(name "IO_L9N_AD11N_87"
						(effects
							(font
								(size 1.27 1.27)
							)
						)
					)
					(number "C13"
						(effects
							(font
								(size 1.27 1.27)
							)
						)
					)
				)
				(pin bidirectional line
					(at 0 -50.8 0)
					(length 5.08)
					(name "IO_L10P_AD10P_87"
						(effects
							(font
								(size 1.27 1.27)
							)
						)
					)
					(number "C12"
						(effects
							(font
								(size 1.27 1.27)
							)
						)
					)
				)
				(pin bidirectional line
					(at 0 -53.34 0)
					(length 5.08)
					(name "IO_L10N_AD10N_87"
						(effects
							(font
								(size 1.27 1.27)
							)
						)
					)
					(number "B12"
						(effects
							(font
								(size 1.27 1.27)
							)
						)
					)
				)
				(pin bidirectional line
					(at 0 -55.88 0)
					(length 5.08)
					(name "IO_L11P_AD9P_87"
						(effects
							(font
								(size 1.27 1.27)
							)
						)
					)
					(number "A13"
						(effects
							(font
								(size 1.27 1.27)
							)
						)
					)
				)
				(pin bidirectional line
					(at 0 -58.42 0)
					(length 5.08)
					(name "IO_L11N_AD9N_87"
						(effects
							(font
								(size 1.27 1.27)
							)
						)
					)
					(number "A12"
						(effects
							(font
								(size 1.27 1.27)
							)
						)
					)
				)
				(pin bidirectional line
					(at 0 -60.96 0)
					(length 5.08)
					(name "IO_L12P_AD8P_87"
						(effects
							(font
								(size 1.27 1.27)
							)
						)
					)
					(number "B14"
						(effects
							(font
								(size 1.27 1.27)
							)
						)
					)
				)
				(pin bidirectional line
					(at 0 -63.5 0)
					(length 5.08)
					(name "IO_L12N_AD8N_87"
						(effects
							(font
								(size 1.27 1.27)
							)
						)
					)
					(number "A14"
						(effects
							(font
								(size 1.27 1.27)
							)
						)
					)
				)
			)
			(symbol "XCAU25P-2FFVB676I_1_9_1"
				(rectangle
					(start 5.08 6.35)
					(end 27.94 -58.42)
					(stroke
						(width 0.254)
						(type default)
					)
					(fill
						(type background)
					)
				)
				(polyline
					(pts
						(xy 16.51 2.54) (xy 25.4 2.54) (xy 25.4 -55.88) (xy 16.51 -55.88)
					)
					(stroke
						(width 0.254)
						(type default)
					)
					(fill
						(type background)
					)
				)
				(text "GTX 224"
					(at 6.35 2.54 0)
					(effects
						(font
							(size 1.27 1.27)
							(thickness 0.15)
						)
						(justify left bottom)
					)
				)
				(text ""
					(at 50.8 -31.75 0)
					(effects
						(font
							(size 1.27 1.27)
							(thickness 0.15)
						)
						(justify left bottom)
					)
				)
				(text ""
					(at 50.8 -31.75 0)
					(effects
						(font
							(size 1.27 1.27)
							(thickness 0.15)
						)
						(justify left bottom)
					)
				)
				(pin output line
					(at 0 0 0)
					(length 5.08)
					(name "MGTYTXP0_224"
						(effects
							(font
								(size 1.27 1.27)
							)
						)
					)
					(number "AF7"
						(effects
							(font
								(size 1.27 1.27)
							)
						)
					)
				)
				(pin output line
					(at 0 -2.54 0)
					(length 5.08)
					(name "MGTYTXN0_224"
						(effects
							(font
								(size 1.27 1.27)
							)
						)
					)
					(number "AF6"
						(effects
							(font
								(size 1.27 1.27)
							)
						)
					)
				)
				(pin output line
					(at 0 -5.08 0)
					(length 5.08)
					(name "MGTYTXP1_224"
						(effects
							(font
								(size 1.27 1.27)
							)
						)
					)
					(number "AE9"
						(effects
							(font
								(size 1.27 1.27)
							)
						)
					)
				)
				(pin output line
					(at 0 -7.62 0)
					(length 5.08)
					(name "MGTYTXN1_224"
						(effects
							(font
								(size 1.27 1.27)
							)
						)
					)
					(number "AE8"
						(effects
							(font
								(size 1.27 1.27)
							)
						)
					)
				)
				(pin output line
					(at 0 -10.16 0)
					(length 5.08)
					(name "MGTYTXP2_224"
						(effects
							(font
								(size 1.27 1.27)
							)
						)
					)
					(number "AD7"
						(effects
							(font
								(size 1.27 1.27)
							)
						)
					)
				)
				(pin output line
					(at 0 -12.7 0)
					(length 5.08)
					(name "MGTYTXN2_224"
						(effects
							(font
								(size 1.27 1.27)
							)
						)
					)
					(number "AD6"
						(effects
							(font
								(size 1.27 1.27)
							)
						)
					)
				)
				(pin output line
					(at 0 -15.24 0)
					(length 5.08)
					(name "MGTYTXP3_224"
						(effects
							(font
								(size 1.27 1.27)
							)
						)
					)
					(number "AC5"
						(effects
							(font
								(size 1.27 1.27)
							)
						)
					)
				)
				(pin output line
					(at 0 -17.78 0)
					(length 5.08)
					(name "MGTYTXN3_224"
						(effects
							(font
								(size 1.27 1.27)
							)
						)
					)
					(number "AC4"
						(effects
							(font
								(size 1.27 1.27)
							)
						)
					)
				)
				(pin input line
					(at 0 -22.86 0)
					(length 5.08)
					(name "MGTYRXP0_224"
						(effects
							(font
								(size 1.27 1.27)
							)
						)
					)
					(number "AF2"
						(effects
							(font
								(size 1.27 1.27)
							)
						)
					)
				)
				(pin input line
					(at 0 -25.4 0)
					(length 5.08)
					(name "MGTYRXN0_224"
						(effects
							(font
								(size 1.27 1.27)
							)
						)
					)
					(number "AF1"
						(effects
							(font
								(size 1.27 1.27)
							)
						)
					)
				)
				(pin input line
					(at 0 -27.94 0)
					(length 5.08)
					(name "MGTYRXP1_224"
						(effects
							(font
								(size 1.27 1.27)
							)
						)
					)
					(number "AE4"
						(effects
							(font
								(size 1.27 1.27)
							)
						)
					)
				)
				(pin input line
					(at 0 -30.48 0)
					(length 5.08)
					(name "MGTYRXN1_224"
						(effects
							(font
								(size 1.27 1.27)
							)
						)
					)
					(number "AE3"
						(effects
							(font
								(size 1.27 1.27)
							)
						)
					)
				)
				(pin input line
					(at 0 -33.02 0)
					(length 5.08)
					(name "MGTYRXP2_224"
						(effects
							(font
								(size 1.27 1.27)
							)
						)
					)
					(number "AD2"
						(effects
							(font
								(size 1.27 1.27)
							)
						)
					)
				)
				(pin input line
					(at 0 -35.56 0)
					(length 5.08)
					(name "MGTYRXN2_224"
						(effects
							(font
								(size 1.27 1.27)
							)
						)
					)
					(number "AD1"
						(effects
							(font
								(size 1.27 1.27)
							)
						)
					)
				)
				(pin input line
					(at 0 -38.1 0)
					(length 5.08)
					(name "MGTYRXP3_224"
						(effects
							(font
								(size 1.27 1.27)
							)
						)
					)
					(number "AB2"
						(effects
							(font
								(size 1.27 1.27)
							)
						)
					)
				)
				(pin input line
					(at 0 -40.64 0)
					(length 5.08)
					(name "MGTYRXN3_224"
						(effects
							(font
								(size 1.27 1.27)
							)
						)
					)
					(number "AB1"
						(effects
							(font
								(size 1.27 1.27)
							)
						)
					)
				)
				(pin input line
					(at 0 -45.72 0)
					(length 5.08)
					(name "MGTREFCLK0P_224"
						(effects
							(font
								(size 1.27 1.27)
							)
						)
					)
					(number "AB7"
						(effects
							(font
								(size 1.27 1.27)
							)
						)
					)
				)
				(pin input line
					(at 0 -48.26 0)
					(length 5.08)
					(name "MGTREFCLK0N_224"
						(effects
							(font
								(size 1.27 1.27)
							)
						)
					)
					(number "AB6"
						(effects
							(font
								(size 1.27 1.27)
							)
						)
					)
				)
				(pin input line
					(at 0 -50.8 0)
					(length 5.08)
					(name "MGTREFCLK1P_224"
						(effects
							(font
								(size 1.27 1.27)
							)
						)
					)
					(number "Y7"
						(effects
							(font
								(size 1.27 1.27)
							)
						)
					)
				)
				(pin input line
					(at 0 -53.34 0)
					(length 5.08)
					(name "MGTREFCLK1N_224"
						(effects
							(font
								(size 1.27 1.27)
							)
						)
					)
					(number "Y6"
						(effects
							(font
								(size 1.27 1.27)
							)
						)
					)
				)
			)
			(symbol "XCAU25P-2FFVB676I_1_10_1"
				(rectangle
					(start 5.08 6.35)
					(end 27.94 -58.42)
					(stroke
						(width 0.254)
						(type default)
					)
					(fill
						(type background)
					)
				)
				(polyline
					(pts
						(xy 16.51 2.54) (xy 25.4 2.54) (xy 25.4 -55.88) (xy 16.51 -55.88)
					)
					(stroke
						(width 0.254)
						(type default)
					)
					(fill
						(type background)
					)
				)
				(text "GTX 225"
					(at 6.35 2.54 0)
					(effects
						(font
							(size 1.27 1.27)
							(thickness 0.15)
						)
						(justify left bottom)
					)
				)
				(text ""
					(at 50.8 -31.75 0)
					(effects
						(font
							(size 1.27 1.27)
							(thickness 0.15)
						)
						(justify left bottom)
					)
				)
				(text ""
					(at 50.8 -31.75 0)
					(effects
						(font
							(size 1.27 1.27)
							(thickness 0.15)
						)
						(justify left bottom)
					)
				)
				(pin output line
					(at 0 0 0)
					(length 5.08)
					(name "MGTYTXP0_225"
						(effects
							(font
								(size 1.27 1.27)
							)
						)
					)
					(number "AA5"
						(effects
							(font
								(size 1.27 1.27)
							)
						)
					)
				)
				(pin output line
					(at 0 -2.54 0)
					(length 5.08)
					(name "MGTYTXN0_225"
						(effects
							(font
								(size 1.27 1.27)
							)
						)
					)
					(number "AA4"
						(effects
							(font
								(size 1.27 1.27)
							)
						)
					)
				)
				(pin output line
					(at 0 -5.08 0)
					(length 5.08)
					(name "MGTYTXP1_225"
						(effects
							(font
								(size 1.27 1.27)
							)
						)
					)
					(number "W5"
						(effects
							(font
								(size 1.27 1.27)
							)
						)
					)
				)
				(pin output line
					(at 0 -7.62 0)
					(length 5.08)
					(name "MGTYTXN1_225"
						(effects
							(font
								(size 1.27 1.27)
							)
						)
					)
					(number "W4"
						(effects
							(font
								(size 1.27 1.27)
							)
						)
					)
				)
				(pin output line
					(at 0 -10.16 0)
					(length 5.08)
					(name "MGTYTXP2_225"
						(effects
							(font
								(size 1.27 1.27)
							)
						)
					)
					(number "U5"
						(effects
							(font
								(size 1.27 1.27)
							)
						)
					)
				)
				(pin output line
					(at 0 -12.7 0)
					(length 5.08)
					(name "MGTYTXN2_225"
						(effects
							(font
								(size 1.27 1.27)
							)
						)
					)
					(number "U4"
						(effects
							(font
								(size 1.27 1.27)
							)
						)
					)
				)
				(pin output line
					(at 0 -15.24 0)
					(length 5.08)
					(name "MGTYTXP3_225"
						(effects
							(font
								(size 1.27 1.27)
							)
						)
					)
					(number "R5"
						(effects
							(font
								(size 1.27 1.27)
							)
						)
					)
				)
				(pin output line
					(at 0 -17.78 0)
					(length 5.08)
					(name "MGTYTXN3_225"
						(effects
							(font
								(size 1.27 1.27)
							)
						)
					)
					(number "R4"
						(effects
							(font
								(size 1.27 1.27)
							)
						)
					)
				)
				(pin input line
					(at 0 -22.86 0)
					(length 5.08)
					(name "MGTYRXP0_225"
						(effects
							(font
								(size 1.27 1.27)
							)
						)
					)
					(number "Y2"
						(effects
							(font
								(size 1.27 1.27)
							)
						)
					)
				)
				(pin input line
					(at 0 -25.4 0)
					(length 5.08)
					(name "MGTYRXN0_225"
						(effects
							(font
								(size 1.27 1.27)
							)
						)
					)
					(number "Y1"
						(effects
							(font
								(size 1.27 1.27)
							)
						)
					)
				)
				(pin input line
					(at 0 -27.94 0)
					(length 5.08)
					(name "MGTYRXP1_225"
						(effects
							(font
								(size 1.27 1.27)
							)
						)
					)
					(number "V2"
						(effects
							(font
								(size 1.27 1.27)
							)
						)
					)
				)
				(pin input line
					(at 0 -30.48 0)
					(length 5.08)
					(name "MGTYRXN1_225"
						(effects
							(font
								(size 1.27 1.27)
							)
						)
					)
					(number "V1"
						(effects
							(font
								(size 1.27 1.27)
							)
						)
					)
				)
				(pin input line
					(at 0 -33.02 0)
					(length 5.08)
					(name "MGTYRXP2_225"
						(effects
							(font
								(size 1.27 1.27)
							)
						)
					)
					(number "T2"
						(effects
							(font
								(size 1.27 1.27)
							)
						)
					)
				)
				(pin input line
					(at 0 -35.56 0)
					(length 5.08)
					(name "MGTYRXN2_225"
						(effects
							(font
								(size 1.27 1.27)
							)
						)
					)
					(number "T1"
						(effects
							(font
								(size 1.27 1.27)
							)
						)
					)
				)
				(pin input line
					(at 0 -38.1 0)
					(length 5.08)
					(name "MGTYRXP3_225"
						(effects
							(font
								(size 1.27 1.27)
							)
						)
					)
					(number "P2"
						(effects
							(font
								(size 1.27 1.27)
							)
						)
					)
				)
				(pin input line
					(at 0 -40.64 0)
					(length 5.08)
					(name "MGTYRXN3_225"
						(effects
							(font
								(size 1.27 1.27)
							)
						)
					)
					(number "P1"
						(effects
							(font
								(size 1.27 1.27)
							)
						)
					)
				)
				(pin input line
					(at 0 -45.72 0)
					(length 5.08)
					(name "MGTREFCLK0P_225"
						(effects
							(font
								(size 1.27 1.27)
							)
						)
					)
					(number "V7"
						(effects
							(font
								(size 1.27 1.27)
							)
						)
					)
				)
				(pin input line
					(at 0 -48.26 0)
					(length 5.08)
					(name "MGTREFCLK0N_225"
						(effects
							(font
								(size 1.27 1.27)
							)
						)
					)
					(number "V6"
						(effects
							(font
								(size 1.27 1.27)
							)
						)
					)
				)
				(pin input line
					(at 0 -50.8 0)
					(length 5.08)
					(name "MGTREFCLK1P_225"
						(effects
							(font
								(size 1.27 1.27)
							)
						)
					)
					(number "T7"
						(effects
							(font
								(size 1.27 1.27)
							)
						)
					)
				)
				(pin input line
					(at 0 -53.34 0)
					(length 5.08)
					(name "MGTREFCLK1N_225"
						(effects
							(font
								(size 1.27 1.27)
							)
						)
					)
					(number "T6"
						(effects
							(font
								(size 1.27 1.27)
							)
						)
					)
				)
			)
			(symbol "XCAU25P-2FFVB676I_1_11_1"
				(rectangle
					(start 5.08 6.35)
					(end 27.94 -58.42)
					(stroke
						(width 0.254)
						(type default)
					)
					(fill
						(type background)
					)
				)
				(polyline
					(pts
						(xy 16.51 2.54) (xy 25.4 2.54) (xy 25.4 -55.88) (xy 16.51 -55.88)
					)
					(stroke
						(width 0.254)
						(type default)
					)
					(fill
						(type background)
					)
				)
				(text "GTX 226"
					(at 6.35 2.54 0)
					(effects
						(font
							(size 1.27 1.27)
							(thickness 0.15)
						)
						(justify left bottom)
					)
				)
				(text ""
					(at 50.8 -31.75 0)
					(effects
						(font
							(size 1.27 1.27)
							(thickness 0.15)
						)
						(justify left bottom)
					)
				)
				(text ""
					(at 50.8 -31.75 0)
					(effects
						(font
							(size 1.27 1.27)
							(thickness 0.15)
						)
						(justify left bottom)
					)
				)
				(pin output line
					(at 0 0 0)
					(length 5.08)
					(name "MGTYTXP0_226"
						(effects
							(font
								(size 1.27 1.27)
							)
						)
					)
					(number "N5"
						(effects
							(font
								(size 1.27 1.27)
							)
						)
					)
				)
				(pin output line
					(at 0 -2.54 0)
					(length 5.08)
					(name "MGTYTXN0_226"
						(effects
							(font
								(size 1.27 1.27)
							)
						)
					)
					(number "N4"
						(effects
							(font
								(size 1.27 1.27)
							)
						)
					)
				)
				(pin output line
					(at 0 -5.08 0)
					(length 5.08)
					(name "MGTYTXP1_226"
						(effects
							(font
								(size 1.27 1.27)
							)
						)
					)
					(number "L5"
						(effects
							(font
								(size 1.27 1.27)
							)
						)
					)
				)
				(pin output line
					(at 0 -7.62 0)
					(length 5.08)
					(name "MGTYTXN1_226"
						(effects
							(font
								(size 1.27 1.27)
							)
						)
					)
					(number "L4"
						(effects
							(font
								(size 1.27 1.27)
							)
						)
					)
				)
				(pin output line
					(at 0 -10.16 0)
					(length 5.08)
					(name "MGTYTXP2_226"
						(effects
							(font
								(size 1.27 1.27)
							)
						)
					)
					(number "J5"
						(effects
							(font
								(size 1.27 1.27)
							)
						)
					)
				)
				(pin output line
					(at 0 -12.7 0)
					(length 5.08)
					(name "MGTYTXN2_226"
						(effects
							(font
								(size 1.27 1.27)
							)
						)
					)
					(number "J4"
						(effects
							(font
								(size 1.27 1.27)
							)
						)
					)
				)
				(pin output line
					(at 0 -15.24 0)
					(length 5.08)
					(name "MGTYTXP3_226"
						(effects
							(font
								(size 1.27 1.27)
							)
						)
					)
					(number "G5"
						(effects
							(font
								(size 1.27 1.27)
							)
						)
					)
				)
				(pin output line
					(at 0 -17.78 0)
					(length 5.08)
					(name "MGTYTXN3_226"
						(effects
							(font
								(size 1.27 1.27)
							)
						)
					)
					(number "G4"
						(effects
							(font
								(size 1.27 1.27)
							)
						)
					)
				)
				(pin input line
					(at 0 -22.86 0)
					(length 5.08)
					(name "MGTYRXP0_226"
						(effects
							(font
								(size 1.27 1.27)
							)
						)
					)
					(number "M2"
						(effects
							(font
								(size 1.27 1.27)
							)
						)
					)
				)
				(pin input line
					(at 0 -25.4 0)
					(length 5.08)
					(name "MGTYRXN0_226"
						(effects
							(font
								(size 1.27 1.27)
							)
						)
					)
					(number "M1"
						(effects
							(font
								(size 1.27 1.27)
							)
						)
					)
				)
				(pin input line
					(at 0 -27.94 0)
					(length 5.08)
					(name "MGTYRXP1_226"
						(effects
							(font
								(size 1.27 1.27)
							)
						)
					)
					(number "K2"
						(effects
							(font
								(size 1.27 1.27)
							)
						)
					)
				)
				(pin input line
					(at 0 -30.48 0)
					(length 5.08)
					(name "MGTYRXN1_226"
						(effects
							(font
								(size 1.27 1.27)
							)
						)
					)
					(number "K1"
						(effects
							(font
								(size 1.27 1.27)
							)
						)
					)
				)
				(pin input line
					(at 0 -33.02 0)
					(length 5.08)
					(name "MGTYRXP2_226"
						(effects
							(font
								(size 1.27 1.27)
							)
						)
					)
					(number "H2"
						(effects
							(font
								(size 1.27 1.27)
							)
						)
					)
				)
				(pin input line
					(at 0 -35.56 0)
					(length 5.08)
					(name "MGTYRXN2_226"
						(effects
							(font
								(size 1.27 1.27)
							)
						)
					)
					(number "H1"
						(effects
							(font
								(size 1.27 1.27)
							)
						)
					)
				)
				(pin input line
					(at 0 -38.1 0)
					(length 5.08)
					(name "MGTYRXP3_226"
						(effects
							(font
								(size 1.27 1.27)
							)
						)
					)
					(number "F2"
						(effects
							(font
								(size 1.27 1.27)
							)
						)
					)
				)
				(pin input line
					(at 0 -40.64 0)
					(length 5.08)
					(name "MGTYRXN3_226"
						(effects
							(font
								(size 1.27 1.27)
							)
						)
					)
					(number "F1"
						(effects
							(font
								(size 1.27 1.27)
							)
						)
					)
				)
				(pin input line
					(at 0 -45.72 0)
					(length 5.08)
					(name "MGTREFCLK0P_226"
						(effects
							(font
								(size 1.27 1.27)
							)
						)
					)
					(number "P7"
						(effects
							(font
								(size 1.27 1.27)
							)
						)
					)
				)
				(pin input line
					(at 0 -48.26 0)
					(length 5.08)
					(name "MGTREFCLK0N_226"
						(effects
							(font
								(size 1.27 1.27)
							)
						)
					)
					(number "P6"
						(effects
							(font
								(size 1.27 1.27)
							)
						)
					)
				)
				(pin input line
					(at 0 -50.8 0)
					(length 5.08)
					(name "MGTREFCLK1P_226"
						(effects
							(font
								(size 1.27 1.27)
							)
						)
					)
					(number "M7"
						(effects
							(font
								(size 1.27 1.27)
							)
						)
					)
				)
				(pin input line
					(at 0 -53.34 0)
					(length 5.08)
					(name "MGTREFCLK1N_226"
						(effects
							(font
								(size 1.27 1.27)
							)
						)
					)
					(number "M6"
						(effects
							(font
								(size 1.27 1.27)
							)
						)
					)
				)
			)
			(symbol "XCAU25P-2FFVB676I_1_12_1"
				(rectangle
					(start 5.08 2.54)
					(end 35.56 -27.94)
					(stroke
						(width 0.254)
						(type default)
					)
					(fill
						(type background)
					)
				)
				(text ""
					(at 21.59 -3.175 900)
					(effects
						(font
							(size 1.27 1.27)
							(thickness 0.15)
						)
						(justify right top)
					)
				)
				(text ""
					(at 21.59 -3.175 900)
					(effects
						(font
							(size 1.27 1.27)
							(thickness 0.15)
						)
						(justify right top)
					)
				)
				(pin input line
					(at 0 0 0)
					(length 5.08)
					(name "MGTAVTT_R"
						(effects
							(font
								(size 1.27 1.27)
							)
						)
					)
					(number "A7"
						(effects
							(font
								(size 1.27 1.27)
							)
						)
					)
				)
				(pin passive line
					(at 0 0 0)
					(length 5.08)
					(hide yes)
					(name "MGTAVTT_R"
						(effects
							(font
								(size 1.27 1.27)
							)
						)
					)
					(number "AB5"
						(effects
							(font
								(size 1.27 1.27)
							)
						)
					)
				)
				(pin passive line
					(at 0 0 0)
					(length 5.08)
					(hide yes)
					(name "MGTAVTT_R"
						(effects
							(font
								(size 1.27 1.27)
							)
						)
					)
					(number "AE7"
						(effects
							(font
								(size 1.27 1.27)
							)
						)
					)
				)
				(pin passive line
					(at 0 0 0)
					(length 5.08)
					(hide yes)
					(name "MGTAVTT_R"
						(effects
							(font
								(size 1.27 1.27)
							)
						)
					)
					(number "C7"
						(effects
							(font
								(size 1.27 1.27)
							)
						)
					)
				)
				(pin passive line
					(at 0 0 0)
					(length 5.08)
					(hide yes)
					(name "MGTAVTT_R"
						(effects
							(font
								(size 1.27 1.27)
							)
						)
					)
					(number "E7"
						(effects
							(font
								(size 1.27 1.27)
							)
						)
					)
				)
				(pin passive line
					(at 0 0 0)
					(length 5.08)
					(hide yes)
					(name "MGTAVTT_R"
						(effects
							(font
								(size 1.27 1.27)
							)
						)
					)
					(number "F5"
						(effects
							(font
								(size 1.27 1.27)
							)
						)
					)
				)
				(pin passive line
					(at 0 0 0)
					(length 5.08)
					(hide yes)
					(name "MGTAVTT_R"
						(effects
							(font
								(size 1.27 1.27)
							)
						)
					)
					(number "G7"
						(effects
							(font
								(size 1.27 1.27)
							)
						)
					)
				)
				(pin passive line
					(at 0 0 0)
					(length 5.08)
					(hide yes)
					(name "MGTAVTT_R"
						(effects
							(font
								(size 1.27 1.27)
							)
						)
					)
					(number "H5"
						(effects
							(font
								(size 1.27 1.27)
							)
						)
					)
				)
				(pin passive line
					(at 0 0 0)
					(length 5.08)
					(hide yes)
					(name "MGTAVTT_R"
						(effects
							(font
								(size 1.27 1.27)
							)
						)
					)
					(number "K5"
						(effects
							(font
								(size 1.27 1.27)
							)
						)
					)
				)
				(pin passive line
					(at 0 0 0)
					(length 5.08)
					(hide yes)
					(name "MGTAVTT_R"
						(effects
							(font
								(size 1.27 1.27)
							)
						)
					)
					(number "M5"
						(effects
							(font
								(size 1.27 1.27)
							)
						)
					)
				)
				(pin passive line
					(at 0 0 0)
					(length 5.08)
					(hide yes)
					(name "MGTAVTT_R"
						(effects
							(font
								(size 1.27 1.27)
							)
						)
					)
					(number "P5"
						(effects
							(font
								(size 1.27 1.27)
							)
						)
					)
				)
				(pin passive line
					(at 0 0 0)
					(length 5.08)
					(hide yes)
					(name "MGTAVTT_R"
						(effects
							(font
								(size 1.27 1.27)
							)
						)
					)
					(number "T5"
						(effects
							(font
								(size 1.27 1.27)
							)
						)
					)
				)
				(pin passive line
					(at 0 0 0)
					(length 5.08)
					(hide yes)
					(name "MGTAVTT_R"
						(effects
							(font
								(size 1.27 1.27)
							)
						)
					)
					(number "V5"
						(effects
							(font
								(size 1.27 1.27)
							)
						)
					)
				)
				(pin passive line
					(at 0 0 0)
					(length 5.08)
					(hide yes)
					(name "MGTAVTT_R"
						(effects
							(font
								(size 1.27 1.27)
							)
						)
					)
					(number "Y5"
						(effects
							(font
								(size 1.27 1.27)
							)
						)
					)
				)
				(pin power_in line
					(at 0 -2.54 0)
					(length 5.08)
					(name "MGTAVCC_R"
						(effects
							(font
								(size 1.27 1.27)
							)
						)
					)
					(number "AA7"
						(effects
							(font
								(size 1.27 1.27)
							)
						)
					)
				)
				(pin passive line
					(at 0 -2.54 0)
					(length 5.08)
					(hide yes)
					(name "MGTAVCC_R"
						(effects
							(font
								(size 1.27 1.27)
							)
						)
					)
					(number "AC7"
						(effects
							(font
								(size 1.27 1.27)
							)
						)
					)
				)
				(pin passive line
					(at 0 -2.54 0)
					(length 5.08)
					(hide yes)
					(name "MGTAVCC_R"
						(effects
							(font
								(size 1.27 1.27)
							)
						)
					)
					(number "J7"
						(effects
							(font
								(size 1.27 1.27)
							)
						)
					)
				)
				(pin passive line
					(at 0 -2.54 0)
					(length 5.08)
					(hide yes)
					(name "MGTAVCC_R"
						(effects
							(font
								(size 1.27 1.27)
							)
						)
					)
					(number "L7"
						(effects
							(font
								(size 1.27 1.27)
							)
						)
					)
				)
				(pin passive line
					(at 0 -2.54 0)
					(length 5.08)
					(hide yes)
					(name "MGTAVCC_R"
						(effects
							(font
								(size 1.27 1.27)
							)
						)
					)
					(number "N7"
						(effects
							(font
								(size 1.27 1.27)
							)
						)
					)
				)
				(pin passive line
					(at 0 -2.54 0)
					(length 5.08)
					(hide yes)
					(name "MGTAVCC_R"
						(effects
							(font
								(size 1.27 1.27)
							)
						)
					)
					(number "W7"
						(effects
							(font
								(size 1.27 1.27)
							)
						)
					)
				)
				(pin input line
					(at 0 -5.08 0)
					(length 5.08)
					(name "MGTRREF_R"
						(effects
							(font
								(size 1.27 1.27)
							)
						)
					)
					(number "AD9"
						(effects
							(font
								(size 1.27 1.27)
							)
						)
					)
				)
				(pin power_in line
					(at 0 -7.62 0)
					(length 5.08)
					(name "MGTVCCAUX_R"
						(effects
							(font
								(size 1.27 1.27)
							)
						)
					)
					(number "R7"
						(effects
							(font
								(size 1.27 1.27)
							)
						)
					)
				)
				(pin passive line
					(at 0 -7.62 0)
					(length 5.08)
					(hide yes)
					(name "MGTVCCAUX_R"
						(effects
							(font
								(size 1.27 1.27)
							)
						)
					)
					(number "U7"
						(effects
							(font
								(size 1.27 1.27)
							)
						)
					)
				)
				(pin input line
					(at 0 -10.16 0)
					(length 5.08)
					(name "MGTAVTTRCAL_R"
						(effects
							(font
								(size 1.27 1.27)
							)
						)
					)
					(number "AD8"
						(effects
							(font
								(size 1.27 1.27)
							)
						)
					)
				)
				(pin input line
					(at 0 -20.32 0)
					(length 5.08)
					(name "RSVDGND"
						(effects
							(font
								(size 1.27 1.27)
							)
						)
					)
					(number "W11"
						(effects
							(font
								(size 1.27 1.27)
							)
						)
					)
				)
				(pin input line
					(at 0 -22.86 0)
					(length 5.08)
					(name "GNDADC"
						(effects
							(font
								(size 1.27 1.27)
							)
						)
					)
					(number "N13"
						(effects
							(font
								(size 1.27 1.27)
							)
						)
					)
				)
				(pin power_in line
					(at 0 -25.4 0)
					(length 5.08)
					(name "GND"
						(effects
							(font
								(size 1.27 1.27)
							)
						)
					)
					(number "A1"
						(effects
							(font
								(size 1.27 1.27)
							)
						)
					)
				)
				(pin passive line
					(at 0 -25.4 0)
					(length 5.08)
					(hide yes)
					(name "GND"
						(effects
							(font
								(size 1.27 1.27)
							)
						)
					)
					(number "A11"
						(effects
							(font
								(size 1.27 1.27)
							)
						)
					)
				)
				(pin passive line
					(at 0 -25.4 0)
					(length 5.08)
					(hide yes)
					(name "GND"
						(effects
							(font
								(size 1.27 1.27)
							)
						)
					)
					(number "A16"
						(effects
							(font
								(size 1.27 1.27)
							)
						)
					)
				)
				(pin passive line
					(at 0 -25.4 0)
					(length 5.08)
					(hide yes)
					(name "GND"
						(effects
							(font
								(size 1.27 1.27)
							)
						)
					)
					(number "A2"
						(effects
							(font
								(size 1.27 1.27)
							)
						)
					)
				)
				(pin passive line
					(at 0 -25.4 0)
					(length 5.08)
					(hide yes)
					(name "GND"
						(effects
							(font
								(size 1.27 1.27)
							)
						)
					)
					(number "A21"
						(effects
							(font
								(size 1.27 1.27)
							)
						)
					)
				)
				(pin passive line
					(at 0 -25.4 0)
					(length 5.08)
					(hide yes)
					(name "GND"
						(effects
							(font
								(size 1.27 1.27)
							)
						)
					)
					(number "A26"
						(effects
							(font
								(size 1.27 1.27)
							)
						)
					)
				)
				(pin passive line
					(at 0 -25.4 0)
					(length 5.08)
					(hide yes)
					(name "GND"
						(effects
							(font
								(size 1.27 1.27)
							)
						)
					)
					(number "A5"
						(effects
							(font
								(size 1.27 1.27)
							)
						)
					)
				)
				(pin passive line
					(at 0 -25.4 0)
					(length 5.08)
					(hide yes)
					(name "GND"
						(effects
							(font
								(size 1.27 1.27)
							)
						)
					)
					(number "A6"
						(effects
							(font
								(size 1.27 1.27)
							)
						)
					)
				)
				(pin passive line
					(at 0 -25.4 0)
					(length 5.08)
					(hide yes)
					(name "GND"
						(effects
							(font
								(size 1.27 1.27)
							)
						)
					)
					(number "A8"
						(effects
							(font
								(size 1.27 1.27)
							)
						)
					)
				)
				(pin passive line
					(at 0 -25.4 0)
					(length 5.08)
					(hide yes)
					(name "GND"
						(effects
							(font
								(size 1.27 1.27)
							)
						)
					)
					(number "AA1"
						(effects
							(font
								(size 1.27 1.27)
							)
						)
					)
				)
				(pin passive line
					(at 0 -25.4 0)
					(length 5.08)
					(hide yes)
					(name "GND"
						(effects
							(font
								(size 1.27 1.27)
							)
						)
					)
					(number "AA16"
						(effects
							(font
								(size 1.27 1.27)
							)
						)
					)
				)
				(pin passive line
					(at 0 -25.4 0)
					(length 5.08)
					(hide yes)
					(name "GND"
						(effects
							(font
								(size 1.27 1.27)
							)
						)
					)
					(number "AA2"
						(effects
							(font
								(size 1.27 1.27)
							)
						)
					)
				)
				(pin passive line
					(at 0 -25.4 0)
					(length 5.08)
					(hide yes)
					(name "GND"
						(effects
							(font
								(size 1.27 1.27)
							)
						)
					)
					(number "AA26"
						(effects
							(font
								(size 1.27 1.27)
							)
						)
					)
				)
				(pin passive line
					(at 0 -25.4 0)
					(length 5.08)
					(hide yes)
					(name "GND"
						(effects
							(font
								(size 1.27 1.27)
							)
						)
					)
					(number "AA3"
						(effects
							(font
								(size 1.27 1.27)
							)
						)
					)
				)
				(pin passive line
					(at 0 -25.4 0)
					(length 5.08)
					(hide yes)
					(name "GND"
						(effects
							(font
								(size 1.27 1.27)
							)
						)
					)
					(number "AA6"
						(effects
							(font
								(size 1.27 1.27)
							)
						)
					)
				)
				(pin passive line
					(at 0 -25.4 0)
					(length 5.08)
					(hide yes)
					(name "GND"
						(effects
							(font
								(size 1.27 1.27)
							)
						)
					)
					(number "AA8"
						(effects
							(font
								(size 1.27 1.27)
							)
						)
					)
				)
				(pin passive line
					(at 0 -25.4 0)
					(length 5.08)
					(hide yes)
					(name "GND"
						(effects
							(font
								(size 1.27 1.27)
							)
						)
					)
					(number "AB13"
						(effects
							(font
								(size 1.27 1.27)
							)
						)
					)
				)
				(pin passive line
					(at 0 -25.4 0)
					(length 5.08)
					(hide yes)
					(name "GND"
						(effects
							(font
								(size 1.27 1.27)
							)
						)
					)
					(number "AB23"
						(effects
							(font
								(size 1.27 1.27)
							)
						)
					)
				)
				(pin passive line
					(at 0 -25.4 0)
					(length 5.08)
					(hide yes)
					(name "GND"
						(effects
							(font
								(size 1.27 1.27)
							)
						)
					)
					(number "AB3"
						(effects
							(font
								(size 1.27 1.27)
							)
						)
					)
				)
				(pin passive line
					(at 0 -25.4 0)
					(length 5.08)
					(hide yes)
					(name "GND"
						(effects
							(font
								(size 1.27 1.27)
							)
						)
					)
					(number "AB4"
						(effects
							(font
								(size 1.27 1.27)
							)
						)
					)
				)
				(pin passive line
					(at 0 -25.4 0)
					(length 5.08)
					(hide yes)
					(name "GND"
						(effects
							(font
								(size 1.27 1.27)
							)
						)
					)
					(number "AB8"
						(effects
							(font
								(size 1.27 1.27)
							)
						)
					)
				)
				(pin passive line
					(at 0 -25.4 0)
					(length 5.08)
					(hide yes)
					(name "GND"
						(effects
							(font
								(size 1.27 1.27)
							)
						)
					)
					(number "AC1"
						(effects
							(font
								(size 1.27 1.27)
							)
						)
					)
				)
				(pin passive line
					(at 0 -25.4 0)
					(length 5.08)
					(hide yes)
					(name "GND"
						(effects
							(font
								(size 1.27 1.27)
							)
						)
					)
					(number "AC10"
						(effects
							(font
								(size 1.27 1.27)
							)
						)
					)
				)
				(pin passive line
					(at 0 -25.4 0)
					(length 5.08)
					(hide yes)
					(name "GND"
						(effects
							(font
								(size 1.27 1.27)
							)
						)
					)
					(number "AC2"
						(effects
							(font
								(size 1.27 1.27)
							)
						)
					)
				)
				(pin passive line
					(at 0 -25.4 0)
					(length 5.08)
					(hide yes)
					(name "GND"
						(effects
							(font
								(size 1.27 1.27)
							)
						)
					)
					(number "AC20"
						(effects
							(font
								(size 1.27 1.27)
							)
						)
					)
				)
				(pin passive line
					(at 0 -25.4 0)
					(length 5.08)
					(hide yes)
					(name "GND"
						(effects
							(font
								(size 1.27 1.27)
							)
						)
					)
					(number "AC25"
						(effects
							(font
								(size 1.27 1.27)
							)
						)
					)
				)
				(pin passive line
					(at 0 -25.4 0)
					(length 5.08)
					(hide yes)
					(name "GND"
						(effects
							(font
								(size 1.27 1.27)
							)
						)
					)
					(number "AC3"
						(effects
							(font
								(size 1.27 1.27)
							)
						)
					)
				)
				(pin passive line
					(at 0 -25.4 0)
					(length 5.08)
					(hide yes)
					(name "GND"
						(effects
							(font
								(size 1.27 1.27)
							)
						)
					)
					(number "AC6"
						(effects
							(font
								(size 1.27 1.27)
							)
						)
					)
				)
				(pin passive line
					(at 0 -25.4 0)
					(length 5.08)
					(hide yes)
					(name "GND"
						(effects
							(font
								(size 1.27 1.27)
							)
						)
					)
					(number "AC8"
						(effects
							(font
								(size 1.27 1.27)
							)
						)
					)
				)
				(pin passive line
					(at 0 -25.4 0)
					(length 5.08)
					(hide yes)
					(name "GND"
						(effects
							(font
								(size 1.27 1.27)
							)
						)
					)
					(number "AC9"
						(effects
							(font
								(size 1.27 1.27)
							)
						)
					)
				)
				(pin passive line
					(at 0 -25.4 0)
					(length 5.08)
					(hide yes)
					(name "GND"
						(effects
							(font
								(size 1.27 1.27)
							)
						)
					)
					(number "AD10"
						(effects
							(font
								(size 1.27 1.27)
							)
						)
					)
				)
				(pin passive line
					(at 0 -25.4 0)
					(length 5.08)
					(hide yes)
					(name "GND"
						(effects
							(font
								(size 1.27 1.27)
							)
						)
					)
					(number "AD17"
						(effects
							(font
								(size 1.27 1.27)
							)
						)
					)
				)
				(pin passive line
					(at 0 -25.4 0)
					(length 5.08)
					(hide yes)
					(name "GND"
						(effects
							(font
								(size 1.27 1.27)
							)
						)
					)
					(number "AD3"
						(effects
							(font
								(size 1.27 1.27)
							)
						)
					)
				)
				(pin passive line
					(at 0 -25.4 0)
					(length 5.08)
					(hide yes)
					(name "GND"
						(effects
							(font
								(size 1.27 1.27)
							)
						)
					)
					(number "AD4"
						(effects
							(font
								(size 1.27 1.27)
							)
						)
					)
				)
				(pin passive line
					(at 0 -25.4 0)
					(length 5.08)
					(hide yes)
					(name "GND"
						(effects
							(font
								(size 1.27 1.27)
							)
						)
					)
					(number "AD5"
						(effects
							(font
								(size 1.27 1.27)
							)
						)
					)
				)
				(pin passive line
					(at 0 -25.4 0)
					(length 5.08)
					(hide yes)
					(name "GND"
						(effects
							(font
								(size 1.27 1.27)
							)
						)
					)
					(number "AE1"
						(effects
							(font
								(size 1.27 1.27)
							)
						)
					)
				)
				(pin passive line
					(at 0 -25.4 0)
					(length 5.08)
					(hide yes)
					(name "GND"
						(effects
							(font
								(size 1.27 1.27)
							)
						)
					)
					(number "AE10"
						(effects
							(font
								(size 1.27 1.27)
							)
						)
					)
				)
				(pin passive line
					(at 0 -25.4 0)
					(length 5.08)
					(hide yes)
					(name "GND"
						(effects
							(font
								(size 1.27 1.27)
							)
						)
					)
					(number "AE14"
						(effects
							(font
								(size 1.27 1.27)
							)
						)
					)
				)
				(pin passive line
					(at 0 -25.4 0)
					(length 5.08)
					(hide yes)
					(name "GND"
						(effects
							(font
								(size 1.27 1.27)
							)
						)
					)
					(number "AE19"
						(effects
							(font
								(size 1.27 1.27)
							)
						)
					)
				)
				(pin passive line
					(at 0 -25.4 0)
					(length 5.08)
					(hide yes)
					(name "GND"
						(effects
							(font
								(size 1.27 1.27)
							)
						)
					)
					(number "AE2"
						(effects
							(font
								(size 1.27 1.27)
							)
						)
					)
				)
				(pin passive line
					(at 0 -25.4 0)
					(length 5.08)
					(hide yes)
					(name "GND"
						(effects
							(font
								(size 1.27 1.27)
							)
						)
					)
					(number "AE24"
						(effects
							(font
								(size 1.27 1.27)
							)
						)
					)
				)
				(pin passive line
					(at 0 -25.4 0)
					(length 5.08)
					(hide yes)
					(name "GND"
						(effects
							(font
								(size 1.27 1.27)
							)
						)
					)
					(number "AE5"
						(effects
							(font
								(size 1.27 1.27)
							)
						)
					)
				)
				(pin passive line
					(at 0 -25.4 0)
					(length 5.08)
					(hide yes)
					(name "GND"
						(effects
							(font
								(size 1.27 1.27)
							)
						)
					)
					(number "AE6"
						(effects
							(font
								(size 1.27 1.27)
							)
						)
					)
				)
				(pin passive line
					(at 0 -25.4 0)
					(length 5.08)
					(hide yes)
					(name "GND"
						(effects
							(font
								(size 1.27 1.27)
							)
						)
					)
					(number "AF10"
						(effects
							(font
								(size 1.27 1.27)
							)
						)
					)
				)
				(pin passive line
					(at 0 -25.4 0)
					(length 5.08)
					(hide yes)
					(name "GND"
						(effects
							(font
								(size 1.27 1.27)
							)
						)
					)
					(number "AF11"
						(effects
							(font
								(size 1.27 1.27)
							)
						)
					)
				)
				(pin passive line
					(at 0 -25.4 0)
					(length 5.08)
					(hide yes)
					(name "GND"
						(effects
							(font
								(size 1.27 1.27)
							)
						)
					)
					(number "AF16"
						(effects
							(font
								(size 1.27 1.27)
							)
						)
					)
				)
				(pin passive line
					(at 0 -25.4 0)
					(length 5.08)
					(hide yes)
					(name "GND"
						(effects
							(font
								(size 1.27 1.27)
							)
						)
					)
					(number "AF21"
						(effects
							(font
								(size 1.27 1.27)
							)
						)
					)
				)
				(pin passive line
					(at 0 -25.4 0)
					(length 5.08)
					(hide yes)
					(name "GND"
						(effects
							(font
								(size 1.27 1.27)
							)
						)
					)
					(number "AF26"
						(effects
							(font
								(size 1.27 1.27)
							)
						)
					)
				)
				(pin passive line
					(at 0 -25.4 0)
					(length 5.08)
					(hide yes)
					(name "GND"
						(effects
							(font
								(size 1.27 1.27)
							)
						)
					)
					(number "AF3"
						(effects
							(font
								(size 1.27 1.27)
							)
						)
					)
				)
				(pin passive line
					(at 0 -25.4 0)
					(length 5.08)
					(hide yes)
					(name "GND"
						(effects
							(font
								(size 1.27 1.27)
							)
						)
					)
					(number "AF4"
						(effects
							(font
								(size 1.27 1.27)
							)
						)
					)
				)
				(pin passive line
					(at 0 -25.4 0)
					(length 5.08)
					(hide yes)
					(name "GND"
						(effects
							(font
								(size 1.27 1.27)
							)
						)
					)
					(number "AF5"
						(effects
							(font
								(size 1.27 1.27)
							)
						)
					)
				)
				(pin passive line
					(at 0 -25.4 0)
					(length 5.08)
					(hide yes)
					(name "GND"
						(effects
							(font
								(size 1.27 1.27)
							)
						)
					)
					(number "AF8"
						(effects
							(font
								(size 1.27 1.27)
							)
						)
					)
				)
				(pin passive line
					(at 0 -25.4 0)
					(length 5.08)
					(hide yes)
					(name "GND"
						(effects
							(font
								(size 1.27 1.27)
							)
						)
					)
					(number "AF9"
						(effects
							(font
								(size 1.27 1.27)
							)
						)
					)
				)
				(pin passive line
					(at 0 -25.4 0)
					(length 5.08)
					(hide yes)
					(name "GND"
						(effects
							(font
								(size 1.27 1.27)
							)
						)
					)
					(number "B13"
						(effects
							(font
								(size 1.27 1.27)
							)
						)
					)
				)
				(pin passive line
					(at 0 -25.4 0)
					(length 5.08)
					(hide yes)
					(name "GND"
						(effects
							(font
								(size 1.27 1.27)
							)
						)
					)
					(number "B18"
						(effects
							(font
								(size 1.27 1.27)
							)
						)
					)
				)
				(pin passive line
					(at 0 -25.4 0)
					(length 5.08)
					(hide yes)
					(name "GND"
						(effects
							(font
								(size 1.27 1.27)
							)
						)
					)
					(number "B23"
						(effects
							(font
								(size 1.27 1.27)
							)
						)
					)
				)
				(pin passive line
					(at 0 -25.4 0)
					(length 5.08)
					(hide yes)
					(name "GND"
						(effects
							(font
								(size 1.27 1.27)
							)
						)
					)
					(number "B3"
						(effects
							(font
								(size 1.27 1.27)
							)
						)
					)
				)
				(pin passive line
					(at 0 -25.4 0)
					(length 5.08)
					(hide yes)
					(name "GND"
						(effects
							(font
								(size 1.27 1.27)
							)
						)
					)
					(number "B4"
						(effects
							(font
								(size 1.27 1.27)
							)
						)
					)
				)
				(pin passive line
					(at 0 -25.4 0)
					(length 5.08)
					(hide yes)
					(name "GND"
						(effects
							(font
								(size 1.27 1.27)
							)
						)
					)
					(number "B5"
						(effects
							(font
								(size 1.27 1.27)
							)
						)
					)
				)
				(pin passive line
					(at 0 -25.4 0)
					(length 5.08)
					(hide yes)
					(name "GND"
						(effects
							(font
								(size 1.27 1.27)
							)
						)
					)
					(number "B8"
						(effects
							(font
								(size 1.27 1.27)
							)
						)
					)
				)
				(pin passive line
					(at 0 -25.4 0)
					(length 5.08)
					(hide yes)
					(name "GND"
						(effects
							(font
								(size 1.27 1.27)
							)
						)
					)
					(number "C1"
						(effects
							(font
								(size 1.27 1.27)
							)
						)
					)
				)
				(pin passive line
					(at 0 -25.4 0)
					(length 5.08)
					(hide yes)
					(name "GND"
						(effects
							(font
								(size 1.27 1.27)
							)
						)
					)
					(number "C10"
						(effects
							(font
								(size 1.27 1.27)
							)
						)
					)
				)
				(pin passive line
					(at 0 -25.4 0)
					(length 5.08)
					(hide yes)
					(name "GND"
						(effects
							(font
								(size 1.27 1.27)
							)
						)
					)
					(number "C15"
						(effects
							(font
								(size 1.27 1.27)
							)
						)
					)
				)
				(pin passive line
					(at 0 -25.4 0)
					(length 5.08)
					(hide yes)
					(name "GND"
						(effects
							(font
								(size 1.27 1.27)
							)
						)
					)
					(number "C2"
						(effects
							(font
								(size 1.27 1.27)
							)
						)
					)
				)
				(pin passive line
					(at 0 -25.4 0)
					(length 5.08)
					(hide yes)
					(name "GND"
						(effects
							(font
								(size 1.27 1.27)
							)
						)
					)
					(number "C25"
						(effects
							(font
								(size 1.27 1.27)
							)
						)
					)
				)
				(pin passive line
					(at 0 -25.4 0)
					(length 5.08)
					(hide yes)
					(name "GND"
						(effects
							(font
								(size 1.27 1.27)
							)
						)
					)
					(number "C5"
						(effects
							(font
								(size 1.27 1.27)
							)
						)
					)
				)
				(pin passive line
					(at 0 -25.4 0)
					(length 5.08)
					(hide yes)
					(name "GND"
						(effects
							(font
								(size 1.27 1.27)
							)
						)
					)
					(number "C6"
						(effects
							(font
								(size 1.27 1.27)
							)
						)
					)
				)
				(pin passive line
					(at 0 -25.4 0)
					(length 5.08)
					(hide yes)
					(name "GND"
						(effects
							(font
								(size 1.27 1.27)
							)
						)
					)
					(number "C8"
						(effects
							(font
								(size 1.27 1.27)
							)
						)
					)
				)
				(pin passive line
					(at 0 -25.4 0)
					(length 5.08)
					(hide yes)
					(name "GND"
						(effects
							(font
								(size 1.27 1.27)
							)
						)
					)
					(number "D12"
						(effects
							(font
								(size 1.27 1.27)
							)
						)
					)
				)
				(pin passive line
					(at 0 -25.4 0)
					(length 5.08)
					(hide yes)
					(name "GND"
						(effects
							(font
								(size 1.27 1.27)
							)
						)
					)
					(number "D22"
						(effects
							(font
								(size 1.27 1.27)
							)
						)
					)
				)
				(pin passive line
					(at 0 -25.4 0)
					(length 5.08)
					(hide yes)
					(name "GND"
						(effects
							(font
								(size 1.27 1.27)
							)
						)
					)
					(number "D3"
						(effects
							(font
								(size 1.27 1.27)
							)
						)
					)
				)
				(pin passive line
					(at 0 -25.4 0)
					(length 5.08)
					(hide yes)
					(name "GND"
						(effects
							(font
								(size 1.27 1.27)
							)
						)
					)
					(number "D4"
						(effects
							(font
								(size 1.27 1.27)
							)
						)
					)
				)
				(pin passive line
					(at 0 -25.4 0)
					(length 5.08)
					(hide yes)
					(name "GND"
						(effects
							(font
								(size 1.27 1.27)
							)
						)
					)
					(number "D5"
						(effects
							(font
								(size 1.27 1.27)
							)
						)
					)
				)
				(pin passive line
					(at 0 -25.4 0)
					(length 5.08)
					(hide yes)
					(name "GND"
						(effects
							(font
								(size 1.27 1.27)
							)
						)
					)
					(number "D8"
						(effects
							(font
								(size 1.27 1.27)
							)
						)
					)
				)
				(pin passive line
					(at 0 -25.4 0)
					(length 5.08)
					(hide yes)
					(name "GND"
						(effects
							(font
								(size 1.27 1.27)
							)
						)
					)
					(number "E1"
						(effects
							(font
								(size 1.27 1.27)
							)
						)
					)
				)
				(pin passive line
					(at 0 -25.4 0)
					(length 5.08)
					(hide yes)
					(name "GND"
						(effects
							(font
								(size 1.27 1.27)
							)
						)
					)
					(number "E19"
						(effects
							(font
								(size 1.27 1.27)
							)
						)
					)
				)
				(pin passive line
					(at 0 -25.4 0)
					(length 5.08)
					(hide yes)
					(name "GND"
						(effects
							(font
								(size 1.27 1.27)
							)
						)
					)
					(number "E2"
						(effects
							(font
								(size 1.27 1.27)
							)
						)
					)
				)
				(pin passive line
					(at 0 -25.4 0)
					(length 5.08)
					(hide yes)
					(name "GND"
						(effects
							(font
								(size 1.27 1.27)
							)
						)
					)
					(number "E3"
						(effects
							(font
								(size 1.27 1.27)
							)
						)
					)
				)
				(pin passive line
					(at 0 -25.4 0)
					(length 5.08)
					(hide yes)
					(name "GND"
						(effects
							(font
								(size 1.27 1.27)
							)
						)
					)
					(number "E6"
						(effects
							(font
								(size 1.27 1.27)
							)
						)
					)
				)
				(pin passive line
					(at 0 -25.4 0)
					(length 5.08)
					(hide yes)
					(name "GND"
						(effects
							(font
								(size 1.27 1.27)
							)
						)
					)
					(number "E8"
						(effects
							(font
								(size 1.27 1.27)
							)
						)
					)
				)
				(pin passive line
					(at 0 -25.4 0)
					(length 5.08)
					(hide yes)
					(name "GND"
						(effects
							(font
								(size 1.27 1.27)
							)
						)
					)
					(number "F11"
						(effects
							(font
								(size 1.27 1.27)
							)
						)
					)
				)
				(pin passive line
					(at 0 -25.4 0)
					(length 5.08)
					(hide yes)
					(name "GND"
						(effects
							(font
								(size 1.27 1.27)
							)
						)
					)
					(number "F16"
						(effects
							(font
								(size 1.27 1.27)
							)
						)
					)
				)
				(pin passive line
					(at 0 -25.4 0)
					(length 5.08)
					(hide yes)
					(name "GND"
						(effects
							(font
								(size 1.27 1.27)
							)
						)
					)
					(number "F21"
						(effects
							(font
								(size 1.27 1.27)
							)
						)
					)
				)
				(pin passive line
					(at 0 -25.4 0)
					(length 5.08)
					(hide yes)
					(name "GND"
						(effects
							(font
								(size 1.27 1.27)
							)
						)
					)
					(number "F26"
						(effects
							(font
								(size 1.27 1.27)
							)
						)
					)
				)
				(pin passive line
					(at 0 -25.4 0)
					(length 5.08)
					(hide yes)
					(name "GND"
						(effects
							(font
								(size 1.27 1.27)
							)
						)
					)
					(number "F3"
						(effects
							(font
								(size 1.27 1.27)
							)
						)
					)
				)
				(pin passive line
					(at 0 -25.4 0)
					(length 5.08)
					(hide yes)
					(name "GND"
						(effects
							(font
								(size 1.27 1.27)
							)
						)
					)
					(number "F4"
						(effects
							(font
								(size 1.27 1.27)
							)
						)
					)
				)
				(pin passive line
					(at 0 -25.4 0)
					(length 5.08)
					(hide yes)
					(name "GND"
						(effects
							(font
								(size 1.27 1.27)
							)
						)
					)
					(number "F8"
						(effects
							(font
								(size 1.27 1.27)
							)
						)
					)
				)
				(pin passive line
					(at 0 -25.4 0)
					(length 5.08)
					(hide yes)
					(name "GND"
						(effects
							(font
								(size 1.27 1.27)
							)
						)
					)
					(number "G1"
						(effects
							(font
								(size 1.27 1.27)
							)
						)
					)
				)
				(pin passive line
					(at 0 -25.4 0)
					(length 5.08)
					(hide yes)
					(name "GND"
						(effects
							(font
								(size 1.27 1.27)
							)
						)
					)
					(number "G13"
						(effects
							(font
								(size 1.27 1.27)
							)
						)
					)
				)
				(pin passive line
					(at 0 -25.4 0)
					(length 5.08)
					(hide yes)
					(name "GND"
						(effects
							(font
								(size 1.27 1.27)
							)
						)
					)
					(number "G2"
						(effects
							(font
								(size 1.27 1.27)
							)
						)
					)
				)
				(pin passive line
					(at 0 -25.4 0)
					(length 5.08)
					(hide yes)
					(name "GND"
						(effects
							(font
								(size 1.27 1.27)
							)
						)
					)
					(number "G23"
						(effects
							(font
								(size 1.27 1.27)
							)
						)
					)
				)
				(pin passive line
					(at 0 -25.4 0)
					(length 5.08)
					(hide yes)
					(name "GND"
						(effects
							(font
								(size 1.27 1.27)
							)
						)
					)
					(number "G3"
						(effects
							(font
								(size 1.27 1.27)
							)
						)
					)
				)
				(pin passive line
					(at 0 -25.4 0)
					(length 5.08)
					(hide yes)
					(name "GND"
						(effects
							(font
								(size 1.27 1.27)
							)
						)
					)
					(number "G6"
						(effects
							(font
								(size 1.27 1.27)
							)
						)
					)
				)
				(pin passive line
					(at 0 -25.4 0)
					(length 5.08)
					(hide yes)
					(name "GND"
						(effects
							(font
								(size 1.27 1.27)
							)
						)
					)
					(number "G8"
						(effects
							(font
								(size 1.27 1.27)
							)
						)
					)
				)
				(pin passive line
					(at 0 -25.4 0)
					(length 5.08)
					(hide yes)
					(name "GND"
						(effects
							(font
								(size 1.27 1.27)
							)
						)
					)
					(number "H20"
						(effects
							(font
								(size 1.27 1.27)
							)
						)
					)
				)
				(pin passive line
					(at 0 -25.4 0)
					(length 5.08)
					(hide yes)
					(name "GND"
						(effects
							(font
								(size 1.27 1.27)
							)
						)
					)
					(number "H3"
						(effects
							(font
								(size 1.27 1.27)
							)
						)
					)
				)
				(pin passive line
					(at 0 -25.4 0)
					(length 5.08)
					(hide yes)
					(name "GND"
						(effects
							(font
								(size 1.27 1.27)
							)
						)
					)
					(number "H4"
						(effects
							(font
								(size 1.27 1.27)
							)
						)
					)
				)
				(pin passive line
					(at 0 -25.4 0)
					(length 5.08)
					(hide yes)
					(name "GND"
						(effects
							(font
								(size 1.27 1.27)
							)
						)
					)
					(number "H8"
						(effects
							(font
								(size 1.27 1.27)
							)
						)
					)
				)
				(pin passive line
					(at 0 -25.4 0)
					(length 5.08)
					(hide yes)
					(name "GND"
						(effects
							(font
								(size 1.27 1.27)
							)
						)
					)
					(number "J1"
						(effects
							(font
								(size 1.27 1.27)
							)
						)
					)
				)
				(pin passive line
					(at 0 -25.4 0)
					(length 5.08)
					(hide yes)
					(name "GND"
						(effects
							(font
								(size 1.27 1.27)
							)
						)
					)
					(number "J17"
						(effects
							(font
								(size 1.27 1.27)
							)
						)
					)
				)
				(pin passive line
					(at 0 -25.4 0)
					(length 5.08)
					(hide yes)
					(name "GND"
						(effects
							(font
								(size 1.27 1.27)
							)
						)
					)
					(number "J2"
						(effects
							(font
								(size 1.27 1.27)
							)
						)
					)
				)
				(pin passive line
					(at 0 -25.4 0)
					(length 5.08)
					(hide yes)
					(name "GND"
						(effects
							(font
								(size 1.27 1.27)
							)
						)
					)
					(number "J3"
						(effects
							(font
								(size 1.27 1.27)
							)
						)
					)
				)
				(pin passive line
					(at 0 -25.4 0)
					(length 5.08)
					(hide yes)
					(name "GND"
						(effects
							(font
								(size 1.27 1.27)
							)
						)
					)
					(number "J6"
						(effects
							(font
								(size 1.27 1.27)
							)
						)
					)
				)
				(pin passive line
					(at 0 -25.4 0)
					(length 5.08)
					(hide yes)
					(name "GND"
						(effects
							(font
								(size 1.27 1.27)
							)
						)
					)
					(number "J8"
						(effects
							(font
								(size 1.27 1.27)
							)
						)
					)
				)
				(pin passive line
					(at 0 -25.4 0)
					(length 5.08)
					(hide yes)
					(name "GND"
						(effects
							(font
								(size 1.27 1.27)
							)
						)
					)
					(number "K12"
						(effects
							(font
								(size 1.27 1.27)
							)
						)
					)
				)
				(pin passive line
					(at 0 -25.4 0)
					(length 5.08)
					(hide yes)
					(name "GND"
						(effects
							(font
								(size 1.27 1.27)
							)
						)
					)
					(number "K14"
						(effects
							(font
								(size 1.27 1.27)
							)
						)
					)
				)
				(pin passive line
					(at 0 -25.4 0)
					(length 5.08)
					(hide yes)
					(name "GND"
						(effects
							(font
								(size 1.27 1.27)
							)
						)
					)
					(number "K16"
						(effects
							(font
								(size 1.27 1.27)
							)
						)
					)
				)
				(pin passive line
					(at 0 -25.4 0)
					(length 5.08)
					(hide yes)
					(name "GND"
						(effects
							(font
								(size 1.27 1.27)
							)
						)
					)
					(number "K19"
						(effects
							(font
								(size 1.27 1.27)
							)
						)
					)
				)
				(pin passive line
					(at 0 -25.4 0)
					(length 5.08)
					(hide yes)
					(name "GND"
						(effects
							(font
								(size 1.27 1.27)
							)
						)
					)
					(number "K24"
						(effects
							(font
								(size 1.27 1.27)
							)
						)
					)
				)
				(pin passive line
					(at 0 -25.4 0)
					(length 5.08)
					(hide yes)
					(name "GND"
						(effects
							(font
								(size 1.27 1.27)
							)
						)
					)
					(number "K3"
						(effects
							(font
								(size 1.27 1.27)
							)
						)
					)
				)
				(pin passive line
					(at 0 -25.4 0)
					(length 5.08)
					(hide yes)
					(name "GND"
						(effects
							(font
								(size 1.27 1.27)
							)
						)
					)
					(number "K4"
						(effects
							(font
								(size 1.27 1.27)
							)
						)
					)
				)
				(pin passive line
					(at 0 -25.4 0)
					(length 5.08)
					(hide yes)
					(name "GND"
						(effects
							(font
								(size 1.27 1.27)
							)
						)
					)
					(number "K8"
						(effects
							(font
								(size 1.27 1.27)
							)
						)
					)
				)
				(pin passive line
					(at 0 -25.4 0)
					(length 5.08)
					(hide yes)
					(name "GND"
						(effects
							(font
								(size 1.27 1.27)
							)
						)
					)
					(number "L1"
						(effects
							(font
								(size 1.27 1.27)
							)
						)
					)
				)
				(pin passive line
					(at 0 -25.4 0)
					(length 5.08)
					(hide yes)
					(name "GND"
						(effects
							(font
								(size 1.27 1.27)
							)
						)
					)
					(number "L11"
						(effects
							(font
								(size 1.27 1.27)
							)
						)
					)
				)
				(pin passive line
					(at 0 -25.4 0)
					(length 5.08)
					(hide yes)
					(name "GND"
						(effects
							(font
								(size 1.27 1.27)
							)
						)
					)
					(number "L13"
						(effects
							(font
								(size 1.27 1.27)
							)
						)
					)
				)
				(pin passive line
					(at 0 -25.4 0)
					(length 5.08)
					(hide yes)
					(name "GND"
						(effects
							(font
								(size 1.27 1.27)
							)
						)
					)
					(number "L15"
						(effects
							(font
								(size 1.27 1.27)
							)
						)
					)
				)
				(pin passive line
					(at 0 -25.4 0)
					(length 5.08)
					(hide yes)
					(name "GND"
						(effects
							(font
								(size 1.27 1.27)
							)
						)
					)
					(number "L17"
						(effects
							(font
								(size 1.27 1.27)
							)
						)
					)
				)
				(pin passive line
					(at 0 -25.4 0)
					(length 5.08)
					(hide yes)
					(name "GND"
						(effects
							(font
								(size 1.27 1.27)
							)
						)
					)
					(number "L2"
						(effects
							(font
								(size 1.27 1.27)
							)
						)
					)
				)
				(pin passive line
					(at 0 -25.4 0)
					(length 5.08)
					(hide yes)
					(name "GND"
						(effects
							(font
								(size 1.27 1.27)
							)
						)
					)
					(number "L21"
						(effects
							(font
								(size 1.27 1.27)
							)
						)
					)
				)
				(pin passive line
					(at 0 -25.4 0)
					(length 5.08)
					(hide yes)
					(name "GND"
						(effects
							(font
								(size 1.27 1.27)
							)
						)
					)
					(number "L26"
						(effects
							(font
								(size 1.27 1.27)
							)
						)
					)
				)
				(pin passive line
					(at 0 -25.4 0)
					(length 5.08)
					(hide yes)
					(name "GND"
						(effects
							(font
								(size 1.27 1.27)
							)
						)
					)
					(number "L3"
						(effects
							(font
								(size 1.27 1.27)
							)
						)
					)
				)
				(pin passive line
					(at 0 -25.4 0)
					(length 5.08)
					(hide yes)
					(name "GND"
						(effects
							(font
								(size 1.27 1.27)
							)
						)
					)
					(number "L6"
						(effects
							(font
								(size 1.27 1.27)
							)
						)
					)
				)
				(pin passive line
					(at 0 -25.4 0)
					(length 5.08)
					(hide yes)
					(name "GND"
						(effects
							(font
								(size 1.27 1.27)
							)
						)
					)
					(number "L8"
						(effects
							(font
								(size 1.27 1.27)
							)
						)
					)
				)
				(pin passive line
					(at 0 -25.4 0)
					(length 5.08)
					(hide yes)
					(name "GND"
						(effects
							(font
								(size 1.27 1.27)
							)
						)
					)
					(number "M10"
						(effects
							(font
								(size 1.27 1.27)
							)
						)
					)
				)
				(pin passive line
					(at 0 -25.4 0)
					(length 5.08)
					(hide yes)
					(name "GND"
						(effects
							(font
								(size 1.27 1.27)
							)
						)
					)
					(number "M12"
						(effects
							(font
								(size 1.27 1.27)
							)
						)
					)
				)
				(pin passive line
					(at 0 -25.4 0)
					(length 5.08)
					(hide yes)
					(name "GND"
						(effects
							(font
								(size 1.27 1.27)
							)
						)
					)
					(number "M14"
						(effects
							(font
								(size 1.27 1.27)
							)
						)
					)
				)
				(pin passive line
					(at 0 -25.4 0)
					(length 5.08)
					(hide yes)
					(name "GND"
						(effects
							(font
								(size 1.27 1.27)
							)
						)
					)
					(number "M16"
						(effects
							(font
								(size 1.27 1.27)
							)
						)
					)
				)
				(pin passive line
					(at 0 -25.4 0)
					(length 5.08)
					(hide yes)
					(name "GND"
						(effects
							(font
								(size 1.27 1.27)
							)
						)
					)
					(number "M23"
						(effects
							(font
								(size 1.27 1.27)
							)
						)
					)
				)
				(pin passive line
					(at 0 -25.4 0)
					(length 5.08)
					(hide yes)
					(name "GND"
						(effects
							(font
								(size 1.27 1.27)
							)
						)
					)
					(number "M3"
						(effects
							(font
								(size 1.27 1.27)
							)
						)
					)
				)
				(pin passive line
					(at 0 -25.4 0)
					(length 5.08)
					(hide yes)
					(name "GND"
						(effects
							(font
								(size 1.27 1.27)
							)
						)
					)
					(number "M4"
						(effects
							(font
								(size 1.27 1.27)
							)
						)
					)
				)
				(pin passive line
					(at 0 -25.4 0)
					(length 5.08)
					(hide yes)
					(name "GND"
						(effects
							(font
								(size 1.27 1.27)
							)
						)
					)
					(number "M8"
						(effects
							(font
								(size 1.27 1.27)
							)
						)
					)
				)
				(pin passive line
					(at 0 -25.4 0)
					(length 5.08)
					(hide yes)
					(name "GND"
						(effects
							(font
								(size 1.27 1.27)
							)
						)
					)
					(number "N1"
						(effects
							(font
								(size 1.27 1.27)
							)
						)
					)
				)
				(pin passive line
					(at 0 -25.4 0)
					(length 5.08)
					(hide yes)
					(name "GND"
						(effects
							(font
								(size 1.27 1.27)
							)
						)
					)
					(number "N11"
						(effects
							(font
								(size 1.27 1.27)
							)
						)
					)
				)
				(pin passive line
					(at 0 -25.4 0)
					(length 5.08)
					(hide yes)
					(name "GND"
						(effects
							(font
								(size 1.27 1.27)
							)
						)
					)
					(number "N15"
						(effects
							(font
								(size 1.27 1.27)
							)
						)
					)
				)
				(pin passive line
					(at 0 -25.4 0)
					(length 5.08)
					(hide yes)
					(name "GND"
						(effects
							(font
								(size 1.27 1.27)
							)
						)
					)
					(number "N17"
						(effects
							(font
								(size 1.27 1.27)
							)
						)
					)
				)
				(pin passive line
					(at 0 -25.4 0)
					(length 5.08)
					(hide yes)
					(name "GND"
						(effects
							(font
								(size 1.27 1.27)
							)
						)
					)
					(number "N2"
						(effects
							(font
								(size 1.27 1.27)
							)
						)
					)
				)
				(pin passive line
					(at 0 -25.4 0)
					(length 5.08)
					(hide yes)
					(name "GND"
						(effects
							(font
								(size 1.27 1.27)
							)
						)
					)
					(number "N20"
						(effects
							(font
								(size 1.27 1.27)
							)
						)
					)
				)
				(pin passive line
					(at 0 -25.4 0)
					(length 5.08)
					(hide yes)
					(name "GND"
						(effects
							(font
								(size 1.27 1.27)
							)
						)
					)
					(number "N25"
						(effects
							(font
								(size 1.27 1.27)
							)
						)
					)
				)
				(pin passive line
					(at 0 -25.4 0)
					(length 5.08)
					(hide yes)
					(name "GND"
						(effects
							(font
								(size 1.27 1.27)
							)
						)
					)
					(number "N3"
						(effects
							(font
								(size 1.27 1.27)
							)
						)
					)
				)
				(pin passive line
					(at 0 -25.4 0)
					(length 5.08)
					(hide yes)
					(name "GND"
						(effects
							(font
								(size 1.27 1.27)
							)
						)
					)
					(number "N6"
						(effects
							(font
								(size 1.27 1.27)
							)
						)
					)
				)
				(pin passive line
					(at 0 -25.4 0)
					(length 5.08)
					(hide yes)
					(name "GND"
						(effects
							(font
								(size 1.27 1.27)
							)
						)
					)
					(number "N8"
						(effects
							(font
								(size 1.27 1.27)
							)
						)
					)
				)
				(pin passive line
					(at 0 -25.4 0)
					(length 5.08)
					(hide yes)
					(name "GND"
						(effects
							(font
								(size 1.27 1.27)
							)
						)
					)
					(number "P10"
						(effects
							(font
								(size 1.27 1.27)
							)
						)
					)
				)
				(pin passive line
					(at 0 -25.4 0)
					(length 5.08)
					(hide yes)
					(name "GND"
						(effects
							(font
								(size 1.27 1.27)
							)
						)
					)
					(number "P12"
						(effects
							(font
								(size 1.27 1.27)
							)
						)
					)
				)
				(pin passive line
					(at 0 -25.4 0)
					(length 5.08)
					(hide yes)
					(name "GND"
						(effects
							(font
								(size 1.27 1.27)
							)
						)
					)
					(number "P16"
						(effects
							(font
								(size 1.27 1.27)
							)
						)
					)
				)
				(pin passive line
					(at 0 -25.4 0)
					(length 5.08)
					(hide yes)
					(name "GND"
						(effects
							(font
								(size 1.27 1.27)
							)
						)
					)
					(number "P3"
						(effects
							(font
								(size 1.27 1.27)
							)
						)
					)
				)
				(pin passive line
					(at 0 -25.4 0)
					(length 5.08)
					(hide yes)
					(name "GND"
						(effects
							(font
								(size 1.27 1.27)
							)
						)
					)
					(number "P4"
						(effects
							(font
								(size 1.27 1.27)
							)
						)
					)
				)
				(pin passive line
					(at 0 -25.4 0)
					(length 5.08)
					(hide yes)
					(name "GND"
						(effects
							(font
								(size 1.27 1.27)
							)
						)
					)
					(number "P8"
						(effects
							(font
								(size 1.27 1.27)
							)
						)
					)
				)
				(pin passive line
					(at 0 -25.4 0)
					(length 5.08)
					(hide yes)
					(name "GND"
						(effects
							(font
								(size 1.27 1.27)
							)
						)
					)
					(number "R1"
						(effects
							(font
								(size 1.27 1.27)
							)
						)
					)
				)
				(pin passive line
					(at 0 -25.4 0)
					(length 5.08)
					(hide yes)
					(name "GND"
						(effects
							(font
								(size 1.27 1.27)
							)
						)
					)
					(number "R11"
						(effects
							(font
								(size 1.27 1.27)
							)
						)
					)
				)
				(pin passive line
					(at 0 -25.4 0)
					(length 5.08)
					(hide yes)
					(name "GND"
						(effects
							(font
								(size 1.27 1.27)
							)
						)
					)
					(number "R15"
						(effects
							(font
								(size 1.27 1.27)
							)
						)
					)
				)
				(pin passive line
					(at 0 -25.4 0)
					(length 5.08)
					(hide yes)
					(name "GND"
						(effects
							(font
								(size 1.27 1.27)
							)
						)
					)
					(number "R17"
						(effects
							(font
								(size 1.27 1.27)
							)
						)
					)
				)
				(pin passive line
					(at 0 -25.4 0)
					(length 5.08)
					(hide yes)
					(name "GND"
						(effects
							(font
								(size 1.27 1.27)
							)
						)
					)
					(number "R19"
						(effects
							(font
								(size 1.27 1.27)
							)
						)
					)
				)
				(pin passive line
					(at 0 -25.4 0)
					(length 5.08)
					(hide yes)
					(name "GND"
						(effects
							(font
								(size 1.27 1.27)
							)
						)
					)
					(number "R2"
						(effects
							(font
								(size 1.27 1.27)
							)
						)
					)
				)
				(pin passive line
					(at 0 -25.4 0)
					(length 5.08)
					(hide yes)
					(name "GND"
						(effects
							(font
								(size 1.27 1.27)
							)
						)
					)
					(number "R24"
						(effects
							(font
								(size 1.27 1.27)
							)
						)
					)
				)
				(pin passive line
					(at 0 -25.4 0)
					(length 5.08)
					(hide yes)
					(name "GND"
						(effects
							(font
								(size 1.27 1.27)
							)
						)
					)
					(number "R3"
						(effects
							(font
								(size 1.27 1.27)
							)
						)
					)
				)
				(pin passive line
					(at 0 -25.4 0)
					(length 5.08)
					(hide yes)
					(name "GND"
						(effects
							(font
								(size 1.27 1.27)
							)
						)
					)
					(number "R6"
						(effects
							(font
								(size 1.27 1.27)
							)
						)
					)
				)
				(pin passive line
					(at 0 -25.4 0)
					(length 5.08)
					(hide yes)
					(name "GND"
						(effects
							(font
								(size 1.27 1.27)
							)
						)
					)
					(number "R8"
						(effects
							(font
								(size 1.27 1.27)
							)
						)
					)
				)
				(pin passive line
					(at 0 -25.4 0)
					(length 5.08)
					(hide yes)
					(name "GND"
						(effects
							(font
								(size 1.27 1.27)
							)
						)
					)
					(number "T10"
						(effects
							(font
								(size 1.27 1.27)
							)
						)
					)
				)
				(pin passive line
					(at 0 -25.4 0)
					(length 5.08)
					(hide yes)
					(name "GND"
						(effects
							(font
								(size 1.27 1.27)
							)
						)
					)
					(number "T12"
						(effects
							(font
								(size 1.27 1.27)
							)
						)
					)
				)
				(pin passive line
					(at 0 -25.4 0)
					(length 5.08)
					(hide yes)
					(name "GND"
						(effects
							(font
								(size 1.27 1.27)
							)
						)
					)
					(number "T16"
						(effects
							(font
								(size 1.27 1.27)
							)
						)
					)
				)
				(pin passive line
					(at 0 -25.4 0)
					(length 5.08)
					(hide yes)
					(name "GND"
						(effects
							(font
								(size 1.27 1.27)
							)
						)
					)
					(number "T21"
						(effects
							(font
								(size 1.27 1.27)
							)
						)
					)
				)
				(pin passive line
					(at 0 -25.4 0)
					(length 5.08)
					(hide yes)
					(name "GND"
						(effects
							(font
								(size 1.27 1.27)
							)
						)
					)
					(number "T26"
						(effects
							(font
								(size 1.27 1.27)
							)
						)
					)
				)
				(pin passive line
					(at 0 -25.4 0)
					(length 5.08)
					(hide yes)
					(name "GND"
						(effects
							(font
								(size 1.27 1.27)
							)
						)
					)
					(number "T3"
						(effects
							(font
								(size 1.27 1.27)
							)
						)
					)
				)
				(pin passive line
					(at 0 -25.4 0)
					(length 5.08)
					(hide yes)
					(name "GND"
						(effects
							(font
								(size 1.27 1.27)
							)
						)
					)
					(number "T4"
						(effects
							(font
								(size 1.27 1.27)
							)
						)
					)
				)
				(pin passive line
					(at 0 -25.4 0)
					(length 5.08)
					(hide yes)
					(name "GND"
						(effects
							(font
								(size 1.27 1.27)
							)
						)
					)
					(number "T8"
						(effects
							(font
								(size 1.27 1.27)
							)
						)
					)
				)
				(pin passive line
					(at 0 -25.4 0)
					(length 5.08)
					(hide yes)
					(name "GND"
						(effects
							(font
								(size 1.27 1.27)
							)
						)
					)
					(number "U1"
						(effects
							(font
								(size 1.27 1.27)
							)
						)
					)
				)
				(pin passive line
					(at 0 -25.4 0)
					(length 5.08)
					(hide yes)
					(name "GND"
						(effects
							(font
								(size 1.27 1.27)
							)
						)
					)
					(number "U11"
						(effects
							(font
								(size 1.27 1.27)
							)
						)
					)
				)
				(pin passive line
					(at 0 -25.4 0)
					(length 5.08)
					(hide yes)
					(name "GND"
						(effects
							(font
								(size 1.27 1.27)
							)
						)
					)
					(number "U13"
						(effects
							(font
								(size 1.27 1.27)
							)
						)
					)
				)
				(pin passive line
					(at 0 -25.4 0)
					(length 5.08)
					(hide yes)
					(name "GND"
						(effects
							(font
								(size 1.27 1.27)
							)
						)
					)
					(number "U15"
						(effects
							(font
								(size 1.27 1.27)
							)
						)
					)
				)
				(pin passive line
					(at 0 -25.4 0)
					(length 5.08)
					(hide yes)
					(name "GND"
						(effects
							(font
								(size 1.27 1.27)
							)
						)
					)
					(number "U17"
						(effects
							(font
								(size 1.27 1.27)
							)
						)
					)
				)
				(pin passive line
					(at 0 -25.4 0)
					(length 5.08)
					(hide yes)
					(name "GND"
						(effects
							(font
								(size 1.27 1.27)
							)
						)
					)
					(number "U18"
						(effects
							(font
								(size 1.27 1.27)
							)
						)
					)
				)
				(pin passive line
					(at 0 -25.4 0)
					(length 5.08)
					(hide yes)
					(name "GND"
						(effects
							(font
								(size 1.27 1.27)
							)
						)
					)
					(number "U2"
						(effects
							(font
								(size 1.27 1.27)
							)
						)
					)
				)
				(pin passive line
					(at 0 -25.4 0)
					(length 5.08)
					(hide yes)
					(name "GND"
						(effects
							(font
								(size 1.27 1.27)
							)
						)
					)
					(number "U3"
						(effects
							(font
								(size 1.27 1.27)
							)
						)
					)
				)
				(pin passive line
					(at 0 -25.4 0)
					(length 5.08)
					(hide yes)
					(name "GND"
						(effects
							(font
								(size 1.27 1.27)
							)
						)
					)
					(number "U6"
						(effects
							(font
								(size 1.27 1.27)
							)
						)
					)
				)
				(pin passive line
					(at 0 -25.4 0)
					(length 5.08)
					(hide yes)
					(name "GND"
						(effects
							(font
								(size 1.27 1.27)
							)
						)
					)
					(number "U8"
						(effects
							(font
								(size 1.27 1.27)
							)
						)
					)
				)
				(pin passive line
					(at 0 -25.4 0)
					(length 5.08)
					(hide yes)
					(name "GND"
						(effects
							(font
								(size 1.27 1.27)
							)
						)
					)
					(number "V10"
						(effects
							(font
								(size 1.27 1.27)
							)
						)
					)
				)
				(pin passive line
					(at 0 -25.4 0)
					(length 5.08)
					(hide yes)
					(name "GND"
						(effects
							(font
								(size 1.27 1.27)
							)
						)
					)
					(number "V12"
						(effects
							(font
								(size 1.27 1.27)
							)
						)
					)
				)
				(pin passive line
					(at 0 -25.4 0)
					(length 5.08)
					(hide yes)
					(name "GND"
						(effects
							(font
								(size 1.27 1.27)
							)
						)
					)
					(number "V14"
						(effects
							(font
								(size 1.27 1.27)
							)
						)
					)
				)
				(pin passive line
					(at 0 -25.4 0)
					(length 5.08)
					(hide yes)
					(name "GND"
						(effects
							(font
								(size 1.27 1.27)
							)
						)
					)
					(number "V16"
						(effects
							(font
								(size 1.27 1.27)
							)
						)
					)
				)
				(pin passive line
					(at 0 -25.4 0)
					(length 5.08)
					(hide yes)
					(name "GND"
						(effects
							(font
								(size 1.27 1.27)
							)
						)
					)
					(number "V20"
						(effects
							(font
								(size 1.27 1.27)
							)
						)
					)
				)
				(pin passive line
					(at 0 -25.4 0)
					(length 5.08)
					(hide yes)
					(name "GND"
						(effects
							(font
								(size 1.27 1.27)
							)
						)
					)
					(number "V25"
						(effects
							(font
								(size 1.27 1.27)
							)
						)
					)
				)
				(pin passive line
					(at 0 -25.4 0)
					(length 5.08)
					(hide yes)
					(name "GND"
						(effects
							(font
								(size 1.27 1.27)
							)
						)
					)
					(number "V3"
						(effects
							(font
								(size 1.27 1.27)
							)
						)
					)
				)
				(pin passive line
					(at 0 -25.4 0)
					(length 5.08)
					(hide yes)
					(name "GND"
						(effects
							(font
								(size 1.27 1.27)
							)
						)
					)
					(number "V4"
						(effects
							(font
								(size 1.27 1.27)
							)
						)
					)
				)
				(pin passive line
					(at 0 -25.4 0)
					(length 5.08)
					(hide yes)
					(name "GND"
						(effects
							(font
								(size 1.27 1.27)
							)
						)
					)
					(number "V8"
						(effects
							(font
								(size 1.27 1.27)
							)
						)
					)
				)
				(pin passive line
					(at 0 -25.4 0)
					(length 5.08)
					(hide yes)
					(name "GND"
						(effects
							(font
								(size 1.27 1.27)
							)
						)
					)
					(number "W1"
						(effects
							(font
								(size 1.27 1.27)
							)
						)
					)
				)
				(pin passive line
					(at 0 -25.4 0)
					(length 5.08)
					(hide yes)
					(name "GND"
						(effects
							(font
								(size 1.27 1.27)
							)
						)
					)
					(number "W17"
						(effects
							(font
								(size 1.27 1.27)
							)
						)
					)
				)
				(pin passive line
					(at 0 -25.4 0)
					(length 5.08)
					(hide yes)
					(name "GND"
						(effects
							(font
								(size 1.27 1.27)
							)
						)
					)
					(number "W2"
						(effects
							(font
								(size 1.27 1.27)
							)
						)
					)
				)
				(pin passive line
					(at 0 -25.4 0)
					(length 5.08)
					(hide yes)
					(name "GND"
						(effects
							(font
								(size 1.27 1.27)
							)
						)
					)
					(number "W22"
						(effects
							(font
								(size 1.27 1.27)
							)
						)
					)
				)
				(pin passive line
					(at 0 -25.4 0)
					(length 5.08)
					(hide yes)
					(name "GND"
						(effects
							(font
								(size 1.27 1.27)
							)
						)
					)
					(number "W3"
						(effects
							(font
								(size 1.27 1.27)
							)
						)
					)
				)
				(pin passive line
					(at 0 -25.4 0)
					(length 5.08)
					(hide yes)
					(name "GND"
						(effects
							(font
								(size 1.27 1.27)
							)
						)
					)
					(number "W6"
						(effects
							(font
								(size 1.27 1.27)
							)
						)
					)
				)
				(pin passive line
					(at 0 -25.4 0)
					(length 5.08)
					(hide yes)
					(name "GND"
						(effects
							(font
								(size 1.27 1.27)
							)
						)
					)
					(number "W8"
						(effects
							(font
								(size 1.27 1.27)
							)
						)
					)
				)
				(pin passive line
					(at 0 -25.4 0)
					(length 5.08)
					(hide yes)
					(name "GND"
						(effects
							(font
								(size 1.27 1.27)
							)
						)
					)
					(number "Y19"
						(effects
							(font
								(size 1.27 1.27)
							)
						)
					)
				)
				(pin passive line
					(at 0 -25.4 0)
					(length 5.08)
					(hide yes)
					(name "GND"
						(effects
							(font
								(size 1.27 1.27)
							)
						)
					)
					(number "Y3"
						(effects
							(font
								(size 1.27 1.27)
							)
						)
					)
				)
				(pin passive line
					(at 0 -25.4 0)
					(length 5.08)
					(hide yes)
					(name "GND"
						(effects
							(font
								(size 1.27 1.27)
							)
						)
					)
					(number "Y4"
						(effects
							(font
								(size 1.27 1.27)
							)
						)
					)
				)
				(pin passive line
					(at 0 -25.4 0)
					(length 5.08)
					(hide yes)
					(name "GND"
						(effects
							(font
								(size 1.27 1.27)
							)
						)
					)
					(number "Y8"
						(effects
							(font
								(size 1.27 1.27)
							)
						)
					)
				)
				(pin no_connect line
					(at 7.62 2.54 270)
					(length 5.08)
					(hide yes)
					(name "NC"
						(effects
							(font
								(size 1.27 1.27)
							)
						)
					)
					(number "B2"
						(effects
							(font
								(size 1.27 1.27)
							)
						)
					)
				)
				(pin no_connect line
					(at 10.16 2.54 270)
					(length 5.08)
					(hide yes)
					(name "NC"
						(effects
							(font
								(size 1.27 1.27)
							)
						)
					)
					(number "C4"
						(effects
							(font
								(size 1.27 1.27)
							)
						)
					)
				)
				(pin no_connect line
					(at 10.16 -27.94 90)
					(length 5.08)
					(hide yes)
					(name "NC"
						(effects
							(font
								(size 1.27 1.27)
							)
						)
					)
					(number "A4"
						(effects
							(font
								(size 1.27 1.27)
							)
						)
					)
				)
				(pin no_connect line
					(at 12.7 2.54 270)
					(length 5.08)
					(hide yes)
					(name "NC"
						(effects
							(font
								(size 1.27 1.27)
							)
						)
					)
					(number "D2"
						(effects
							(font
								(size 1.27 1.27)
							)
						)
					)
				)
				(pin no_connect line
					(at 12.7 -27.94 90)
					(length 5.08)
					(hide yes)
					(name "NC"
						(effects
							(font
								(size 1.27 1.27)
							)
						)
					)
					(number "F6"
						(effects
							(font
								(size 1.27 1.27)
							)
						)
					)
				)
				(pin no_connect line
					(at 15.24 2.54 270)
					(length 5.08)
					(hide yes)
					(name "NC"
						(effects
							(font
								(size 1.27 1.27)
							)
						)
					)
					(number "A3"
						(effects
							(font
								(size 1.27 1.27)
							)
						)
					)
				)
				(pin no_connect line
					(at 15.24 -27.94 90)
					(length 5.08)
					(hide yes)
					(name "NC"
						(effects
							(font
								(size 1.27 1.27)
							)
						)
					)
					(number "E4"
						(effects
							(font
								(size 1.27 1.27)
							)
						)
					)
				)
				(pin no_connect line
					(at 17.78 2.54 270)
					(length 5.08)
					(hide yes)
					(name "NC"
						(effects
							(font
								(size 1.27 1.27)
							)
						)
					)
					(number "B1"
						(effects
							(font
								(size 1.27 1.27)
							)
						)
					)
				)
				(pin no_connect line
					(at 17.78 -27.94 90)
					(length 5.08)
					(hide yes)
					(name "NC"
						(effects
							(font
								(size 1.27 1.27)
							)
						)
					)
					(number "D6"
						(effects
							(font
								(size 1.27 1.27)
							)
						)
					)
				)
				(pin no_connect line
					(at 20.32 2.54 270)
					(length 5.08)
					(hide yes)
					(name "NC"
						(effects
							(font
								(size 1.27 1.27)
							)
						)
					)
					(number "C3"
						(effects
							(font
								(size 1.27 1.27)
							)
						)
					)
				)
				(pin no_connect line
					(at 20.32 -27.94 90)
					(length 5.08)
					(hide yes)
					(name "NC"
						(effects
							(font
								(size 1.27 1.27)
							)
						)
					)
					(number "B6"
						(effects
							(font
								(size 1.27 1.27)
							)
						)
					)
				)
				(pin no_connect line
					(at 22.86 2.54 270)
					(length 5.08)
					(hide yes)
					(name "NC"
						(effects
							(font
								(size 1.27 1.27)
							)
						)
					)
					(number "D1"
						(effects
							(font
								(size 1.27 1.27)
							)
						)
					)
				)
				(pin no_connect line
					(at 22.86 -27.94 90)
					(length 5.08)
					(hide yes)
					(name "NC"
						(effects
							(font
								(size 1.27 1.27)
							)
						)
					)
					(number "F7"
						(effects
							(font
								(size 1.27 1.27)
							)
						)
					)
				)
				(pin no_connect line
					(at 25.4 2.54 270)
					(length 5.08)
					(hide yes)
					(name "NC"
						(effects
							(font
								(size 1.27 1.27)
							)
						)
					)
					(number "H7"
						(effects
							(font
								(size 1.27 1.27)
							)
						)
					)
				)
				(pin no_connect line
					(at 25.4 -27.94 90)
					(length 5.08)
					(hide yes)
					(name "NC"
						(effects
							(font
								(size 1.27 1.27)
							)
						)
					)
					(number "E5"
						(effects
							(font
								(size 1.27 1.27)
							)
						)
					)
				)
				(pin no_connect line
					(at 27.94 2.54 270)
					(length 5.08)
					(hide yes)
					(name "NC"
						(effects
							(font
								(size 1.27 1.27)
							)
						)
					)
					(number "H6"
						(effects
							(font
								(size 1.27 1.27)
							)
						)
					)
				)
				(pin no_connect line
					(at 27.94 -27.94 90)
					(length 5.08)
					(hide yes)
					(name "NC"
						(effects
							(font
								(size 1.27 1.27)
							)
						)
					)
					(number "D7"
						(effects
							(font
								(size 1.27 1.27)
							)
						)
					)
				)
				(pin no_connect line
					(at 30.48 2.54 270)
					(length 5.08)
					(hide yes)
					(name "NC"
						(effects
							(font
								(size 1.27 1.27)
							)
						)
					)
					(number "K7"
						(effects
							(font
								(size 1.27 1.27)
							)
						)
					)
				)
				(pin no_connect line
					(at 30.48 -27.94 90)
					(length 5.08)
					(hide yes)
					(name "NC"
						(effects
							(font
								(size 1.27 1.27)
							)
						)
					)
					(number "B7"
						(effects
							(font
								(size 1.27 1.27)
							)
						)
					)
				)
				(pin no_connect line
					(at 33.02 2.54 270)
					(length 5.08)
					(hide yes)
					(name "NC"
						(effects
							(font
								(size 1.27 1.27)
							)
						)
					)
					(number "K6"
						(effects
							(font
								(size 1.27 1.27)
							)
						)
					)
				)
				(pin power_in line
					(at 40.64 0 180)
					(length 5.08)
					(name "VCCINT"
						(effects
							(font
								(size 1.27 1.27)
							)
						)
					)
					(number "K11"
						(effects
							(font
								(size 1.27 1.27)
							)
						)
					)
				)
				(pin passive line
					(at 40.64 0 180)
					(length 5.08)
					(hide yes)
					(name "VCCINT"
						(effects
							(font
								(size 1.27 1.27)
							)
						)
					)
					(number "K13"
						(effects
							(font
								(size 1.27 1.27)
							)
						)
					)
				)
				(pin passive line
					(at 40.64 0 180)
					(length 5.08)
					(hide yes)
					(name "VCCINT"
						(effects
							(font
								(size 1.27 1.27)
							)
						)
					)
					(number "K15"
						(effects
							(font
								(size 1.27 1.27)
							)
						)
					)
				)
				(pin passive line
					(at 40.64 0 180)
					(length 5.08)
					(hide yes)
					(name "VCCINT"
						(effects
							(font
								(size 1.27 1.27)
							)
						)
					)
					(number "K17"
						(effects
							(font
								(size 1.27 1.27)
							)
						)
					)
				)
				(pin passive line
					(at 40.64 0 180)
					(length 5.08)
					(hide yes)
					(name "VCCINT"
						(effects
							(font
								(size 1.27 1.27)
							)
						)
					)
					(number "L10"
						(effects
							(font
								(size 1.27 1.27)
							)
						)
					)
				)
				(pin passive line
					(at 40.64 0 180)
					(length 5.08)
					(hide yes)
					(name "VCCINT"
						(effects
							(font
								(size 1.27 1.27)
							)
						)
					)
					(number "L12"
						(effects
							(font
								(size 1.27 1.27)
							)
						)
					)
				)
				(pin passive line
					(at 40.64 0 180)
					(length 5.08)
					(hide yes)
					(name "VCCINT"
						(effects
							(font
								(size 1.27 1.27)
							)
						)
					)
					(number "L14"
						(effects
							(font
								(size 1.27 1.27)
							)
						)
					)
				)
				(pin passive line
					(at 40.64 0 180)
					(length 5.08)
					(hide yes)
					(name "VCCINT"
						(effects
							(font
								(size 1.27 1.27)
							)
						)
					)
					(number "L16"
						(effects
							(font
								(size 1.27 1.27)
							)
						)
					)
				)
				(pin passive line
					(at 40.64 0 180)
					(length 5.08)
					(hide yes)
					(name "VCCINT"
						(effects
							(font
								(size 1.27 1.27)
							)
						)
					)
					(number "M11"
						(effects
							(font
								(size 1.27 1.27)
							)
						)
					)
				)
				(pin passive line
					(at 40.64 0 180)
					(length 5.08)
					(hide yes)
					(name "VCCINT"
						(effects
							(font
								(size 1.27 1.27)
							)
						)
					)
					(number "M13"
						(effects
							(font
								(size 1.27 1.27)
							)
						)
					)
				)
				(pin passive line
					(at 40.64 0 180)
					(length 5.08)
					(hide yes)
					(name "VCCINT"
						(effects
							(font
								(size 1.27 1.27)
							)
						)
					)
					(number "M15"
						(effects
							(font
								(size 1.27 1.27)
							)
						)
					)
				)
				(pin passive line
					(at 40.64 0 180)
					(length 5.08)
					(hide yes)
					(name "VCCINT"
						(effects
							(font
								(size 1.27 1.27)
							)
						)
					)
					(number "M17"
						(effects
							(font
								(size 1.27 1.27)
							)
						)
					)
				)
				(pin passive line
					(at 40.64 0 180)
					(length 5.08)
					(hide yes)
					(name "VCCINT"
						(effects
							(font
								(size 1.27 1.27)
							)
						)
					)
					(number "N10"
						(effects
							(font
								(size 1.27 1.27)
							)
						)
					)
				)
				(pin passive line
					(at 40.64 0 180)
					(length 5.08)
					(hide yes)
					(name "VCCINT"
						(effects
							(font
								(size 1.27 1.27)
							)
						)
					)
					(number "N12"
						(effects
							(font
								(size 1.27 1.27)
							)
						)
					)
				)
				(pin passive line
					(at 40.64 0 180)
					(length 5.08)
					(hide yes)
					(name "VCCINT"
						(effects
							(font
								(size 1.27 1.27)
							)
						)
					)
					(number "N16"
						(effects
							(font
								(size 1.27 1.27)
							)
						)
					)
				)
				(pin passive line
					(at 40.64 0 180)
					(length 5.08)
					(hide yes)
					(name "VCCINT"
						(effects
							(font
								(size 1.27 1.27)
							)
						)
					)
					(number "P11"
						(effects
							(font
								(size 1.27 1.27)
							)
						)
					)
				)
				(pin passive line
					(at 40.64 0 180)
					(length 5.08)
					(hide yes)
					(name "VCCINT"
						(effects
							(font
								(size 1.27 1.27)
							)
						)
					)
					(number "P15"
						(effects
							(font
								(size 1.27 1.27)
							)
						)
					)
				)
				(pin passive line
					(at 40.64 0 180)
					(length 5.08)
					(hide yes)
					(name "VCCINT"
						(effects
							(font
								(size 1.27 1.27)
							)
						)
					)
					(number "P17"
						(effects
							(font
								(size 1.27 1.27)
							)
						)
					)
				)
				(pin passive line
					(at 40.64 0 180)
					(length 5.08)
					(hide yes)
					(name "VCCINT"
						(effects
							(font
								(size 1.27 1.27)
							)
						)
					)
					(number "R10"
						(effects
							(font
								(size 1.27 1.27)
							)
						)
					)
				)
				(pin passive line
					(at 40.64 0 180)
					(length 5.08)
					(hide yes)
					(name "VCCINT"
						(effects
							(font
								(size 1.27 1.27)
							)
						)
					)
					(number "R12"
						(effects
							(font
								(size 1.27 1.27)
							)
						)
					)
				)
				(pin passive line
					(at 40.64 0 180)
					(length 5.08)
					(hide yes)
					(name "VCCINT"
						(effects
							(font
								(size 1.27 1.27)
							)
						)
					)
					(number "R16"
						(effects
							(font
								(size 1.27 1.27)
							)
						)
					)
				)
				(pin passive line
					(at 40.64 0 180)
					(length 5.08)
					(hide yes)
					(name "VCCINT"
						(effects
							(font
								(size 1.27 1.27)
							)
						)
					)
					(number "T11"
						(effects
							(font
								(size 1.27 1.27)
							)
						)
					)
				)
				(pin passive line
					(at 40.64 0 180)
					(length 5.08)
					(hide yes)
					(name "VCCINT"
						(effects
							(font
								(size 1.27 1.27)
							)
						)
					)
					(number "T15"
						(effects
							(font
								(size 1.27 1.27)
							)
						)
					)
				)
				(pin passive line
					(at 40.64 0 180)
					(length 5.08)
					(hide yes)
					(name "VCCINT"
						(effects
							(font
								(size 1.27 1.27)
							)
						)
					)
					(number "T17"
						(effects
							(font
								(size 1.27 1.27)
							)
						)
					)
				)
				(pin passive line
					(at 40.64 0 180)
					(length 5.08)
					(hide yes)
					(name "VCCINT"
						(effects
							(font
								(size 1.27 1.27)
							)
						)
					)
					(number "U10"
						(effects
							(font
								(size 1.27 1.27)
							)
						)
					)
				)
				(pin passive line
					(at 40.64 0 180)
					(length 5.08)
					(hide yes)
					(name "VCCINT"
						(effects
							(font
								(size 1.27 1.27)
							)
						)
					)
					(number "U12"
						(effects
							(font
								(size 1.27 1.27)
							)
						)
					)
				)
				(pin passive line
					(at 40.64 0 180)
					(length 5.08)
					(hide yes)
					(name "VCCINT"
						(effects
							(font
								(size 1.27 1.27)
							)
						)
					)
					(number "U14"
						(effects
							(font
								(size 1.27 1.27)
							)
						)
					)
				)
				(pin passive line
					(at 40.64 0 180)
					(length 5.08)
					(hide yes)
					(name "VCCINT"
						(effects
							(font
								(size 1.27 1.27)
							)
						)
					)
					(number "U16"
						(effects
							(font
								(size 1.27 1.27)
							)
						)
					)
				)
				(pin passive line
					(at 40.64 0 180)
					(length 5.08)
					(hide yes)
					(name "VCCINT"
						(effects
							(font
								(size 1.27 1.27)
							)
						)
					)
					(number "V11"
						(effects
							(font
								(size 1.27 1.27)
							)
						)
					)
				)
				(pin passive line
					(at 40.64 0 180)
					(length 5.08)
					(hide yes)
					(name "VCCINT"
						(effects
							(font
								(size 1.27 1.27)
							)
						)
					)
					(number "V13"
						(effects
							(font
								(size 1.27 1.27)
							)
						)
					)
				)
				(pin passive line
					(at 40.64 0 180)
					(length 5.08)
					(hide yes)
					(name "VCCINT"
						(effects
							(font
								(size 1.27 1.27)
							)
						)
					)
					(number "V15"
						(effects
							(font
								(size 1.27 1.27)
							)
						)
					)
				)
				(pin passive line
					(at 40.64 0 180)
					(length 5.08)
					(hide yes)
					(name "VCCINT"
						(effects
							(font
								(size 1.27 1.27)
							)
						)
					)
					(number "V17"
						(effects
							(font
								(size 1.27 1.27)
							)
						)
					)
				)
				(pin power_in line
					(at 40.64 -2.54 180)
					(length 5.08)
					(name "VCCINT_IO"
						(effects
							(font
								(size 1.27 1.27)
							)
						)
					)
					(number "L9"
						(effects
							(font
								(size 1.27 1.27)
							)
						)
					)
				)
				(pin passive line
					(at 40.64 -2.54 180)
					(length 5.08)
					(hide yes)
					(name "VCCINT_IO"
						(effects
							(font
								(size 1.27 1.27)
							)
						)
					)
					(number "M9"
						(effects
							(font
								(size 1.27 1.27)
							)
						)
					)
				)
				(pin passive line
					(at 40.64 -2.54 180)
					(length 5.08)
					(hide yes)
					(name "VCCINT_IO"
						(effects
							(font
								(size 1.27 1.27)
							)
						)
					)
					(number "N9"
						(effects
							(font
								(size 1.27 1.27)
							)
						)
					)
				)
				(pin passive line
					(at 40.64 -2.54 180)
					(length 5.08)
					(hide yes)
					(name "VCCINT_IO"
						(effects
							(font
								(size 1.27 1.27)
							)
						)
					)
					(number "P9"
						(effects
							(font
								(size 1.27 1.27)
							)
						)
					)
				)
				(pin power_in line
					(at 40.64 -7.62 180)
					(length 5.08)
					(name "VCCAUX"
						(effects
							(font
								(size 1.27 1.27)
							)
						)
					)
					(number "M18"
						(effects
							(font
								(size 1.27 1.27)
							)
						)
					)
				)
				(pin passive line
					(at 40.64 -7.62 180)
					(length 5.08)
					(hide yes)
					(name "VCCAUX"
						(effects
							(font
								(size 1.27 1.27)
							)
						)
					)
					(number "N18"
						(effects
							(font
								(size 1.27 1.27)
							)
						)
					)
				)
				(pin power_in line
					(at 40.64 -10.16 180)
					(length 5.08)
					(name "VCCAUX_IO"
						(effects
							(font
								(size 1.27 1.27)
							)
						)
					)
					(number "P18"
						(effects
							(font
								(size 1.27 1.27)
							)
						)
					)
				)
				(pin passive line
					(at 40.64 -10.16 180)
					(length 5.08)
					(hide yes)
					(name "VCCAUX_IO"
						(effects
							(font
								(size 1.27 1.27)
							)
						)
					)
					(number "R18"
						(effects
							(font
								(size 1.27 1.27)
							)
						)
					)
				)
				(pin passive line
					(at 40.64 -10.16 180)
					(length 5.08)
					(hide yes)
					(name "VCCAUX_IO"
						(effects
							(font
								(size 1.27 1.27)
							)
						)
					)
					(number "T18"
						(effects
							(font
								(size 1.27 1.27)
							)
						)
					)
				)
				(pin power_in line
					(at 40.64 -15.24 180)
					(length 5.08)
					(name "VCCBRAM"
						(effects
							(font
								(size 1.27 1.27)
							)
						)
					)
					(number "R9"
						(effects
							(font
								(size 1.27 1.27)
							)
						)
					)
				)
				(pin passive line
					(at 40.64 -15.24 180)
					(length 5.08)
					(hide yes)
					(name "VCCBRAM"
						(effects
							(font
								(size 1.27 1.27)
							)
						)
					)
					(number "T9"
						(effects
							(font
								(size 1.27 1.27)
							)
						)
					)
				)
				(pin passive line
					(at 40.64 -15.24 180)
					(length 5.08)
					(hide yes)
					(name "VCCBRAM"
						(effects
							(font
								(size 1.27 1.27)
							)
						)
					)
					(number "U9"
						(effects
							(font
								(size 1.27 1.27)
							)
						)
					)
				)
				(pin passive line
					(at 40.64 -15.24 180)
					(length 5.08)
					(hide yes)
					(name "VCCBRAM"
						(effects
							(font
								(size 1.27 1.27)
							)
						)
					)
					(number "V9"
						(effects
							(font
								(size 1.27 1.27)
							)
						)
					)
				)
				(pin power_in line
					(at 40.64 -20.32 180)
					(length 5.08)
					(name "VCCADC"
						(effects
							(font
								(size 1.27 1.27)
							)
						)
					)
					(number "N14"
						(effects
							(font
								(size 1.27 1.27)
							)
						)
					)
				)
				(pin power_in line
					(at 40.64 -25.4 180)
					(length 5.08)
					(name "VBATT"
						(effects
							(font
								(size 1.27 1.27)
							)
						)
					)
					(number "Y9"
						(effects
							(font
								(size 1.27 1.27)
							)
						)
					)
				)
			)
		)
	(symbol "XCAU25P-2FFVB676I_2"
			(exclude_from_sim no)
			(in_bom yes)
			(on_board yes)
			(property "Reference" "U"
				(at 63.5 0 0)
				(effects
					(font
						(size 1.27 1.27)
						(thickness 0.15)
					)
					(justify left bottom)
				)
			)
			(property "Value" "XCAU25P-2FFVB676I"
				(at 63.5 -5.08 0)
				(effects
					(font
						(size 1.27 1.27)
						(thickness 0.15)
					)
					(justify left bottom)
					(hide yes)
				)
			)
			(property "Footprint" "antmicro-footprints:BGA-676_27x27mm_Layout26x26_P1x1mm_FFVB676"
				(at 63.5 -7.62 0)
				(effects
					(font
						(size 1.27 1.27)
						(thickness 0.15)
					)
					(justify left bottom)
					(hide yes)
				)
			)
			(property "Datasheet" "https://docs.xilinx.com/viewer/book-attachment/2PXOpPtpaABIt0fkzeBLnw/hvbsEUaOT0OxFhln7VEVyA"
				(at 63.5 -10.16 0)
				(effects
					(font
						(size 1.27 1.27)
						(thickness 0.15)
					)
					(justify left bottom)
					(hide yes)
				)
			)
			(property "Description" "Artix UltraScale+ Field Programmable Gate Array"
				(at 0 0 0)
				(effects
					(font
						(size 1.27 1.27)
					)
					(hide yes)
				)
			)
			(property "MPN" "XCAU25P-2FFVB676I"
				(at 63.5 -2.54 0)
				(effects
					(font
						(size 1.27 1.27)
						(thickness 0.15)
					)
					(justify left bottom)
				)
			)
			(property "Manufacturer" "AMD-Xilinx"
				(at 63.5 -12.7 0)
				(effects
					(font
						(size 1.27 1.27)
						(thickness 0.15)
					)
					(justify left bottom)
					(hide yes)
				)
			)
			(property "Author" "Antmicro"
				(at 63.5 -15.24 0)
				(effects
					(font
						(size 1.27 1.27)
						(thickness 0.15)
					)
					(justify left bottom)
					(hide yes)
				)
			)
			(property "License" "Apache-2.0"
				(at 63.5 -17.78 0)
				(effects
					(font
						(size 1.27 1.27)
						(thickness 0.15)
					)
					(justify left bottom)
					(hide yes)
				)
			)
			(property "ki_locked" ""
				(at 0 0 0)
				(effects
					(font
						(size 1.27 1.27)
					)
				)
			)
			(property "ki_keywords" "FPGA, LVDS, MIPI, CMOS, BGA, ETHERNET, VIDEO, DSP, BRIDGE"
				(at 0 0 0)
				(effects
					(font
						(size 1.27 1.27)
					)
					(hide yes)
				)
			)
			(symbol "XCAU25P-2FFVB676I_2_1_1"
				(rectangle
					(start 5.08 2.54)
					(end 25.4 -87.63)
					(stroke
						(width 0.254)
						(type default)
					)
					(fill
						(type background)
					)
				)
				(polyline
					(pts
						(xy 15.24 -3.81) (xy 22.86 -3.81) (xy 22.86 -83.82) (xy 15.24 -83.82)
					)
					(stroke
						(width 0.254)
						(type default)
					)
					(fill
						(type background)
					)
				)
				(text "CFG"
					(at 15.24 -3.81 0)
					(effects
						(font
							(size 1.27 1.27)
							(thickness 0.15)
						)
						(justify left bottom)
					)
				)
				(text ""
					(at 50.8 -31.75 0)
					(effects
						(font
							(size 1.27 1.27)
							(thickness 0.15)
						)
						(justify left bottom)
					)
				)
				(text ""
					(at 50.8 -31.75 0)
					(effects
						(font
							(size 1.27 1.27)
							(thickness 0.15)
						)
						(justify left bottom)
					)
				)
				(pin power_in line
					(at 0 0 0)
					(length 5.08)
					(name "VCCO_0"
						(effects
							(font
								(size 1.27 1.27)
							)
						)
					)
					(number "AA11"
						(effects
							(font
								(size 1.27 1.27)
							)
						)
					)
				)
				(pin passive line
					(at 0 0 0)
					(length 5.08)
					(hide yes)
					(name "VCCO_0"
						(effects
							(font
								(size 1.27 1.27)
							)
						)
					)
					(number "AD12"
						(effects
							(font
								(size 1.27 1.27)
							)
						)
					)
				)
				(pin bidirectional line
					(at 0 -5.08 0)
					(length 5.08)
					(name "DONE_0"
						(effects
							(font
								(size 1.27 1.27)
							)
						)
					)
					(number "AB11"
						(effects
							(font
								(size 1.27 1.27)
							)
						)
					)
				)
				(pin bidirectional line
					(at 0 -7.62 0)
					(length 5.08)
					(name "INIT_B_0"
						(effects
							(font
								(size 1.27 1.27)
							)
						)
					)
					(number "W10"
						(effects
							(font
								(size 1.27 1.27)
							)
						)
					)
				)
				(pin input line
					(at 0 -10.16 0)
					(length 5.08)
					(name "PROGRAM_B_0"
						(effects
							(font
								(size 1.27 1.27)
							)
						)
					)
					(number "AB9"
						(effects
							(font
								(size 1.27 1.27)
							)
						)
					)
				)
				(pin bidirectional line
					(at 0 -12.7 0)
					(length 5.08)
					(name "RDWR_FCS_B_0"
						(effects
							(font
								(size 1.27 1.27)
							)
						)
					)
					(number "AA12"
						(effects
							(font
								(size 1.27 1.27)
							)
						)
					)
				)
				(pin bidirectional line
					(at 0 -17.78 0)
					(length 5.08)
					(name "CCLK_0"
						(effects
							(font
								(size 1.27 1.27)
							)
						)
					)
					(number "Y11"
						(effects
							(font
								(size 1.27 1.27)
							)
						)
					)
				)
				(pin input line
					(at 0 -20.32 0)
					(length 5.08)
					(name "M0_0"
						(effects
							(font
								(size 1.27 1.27)
							)
						)
					)
					(number "AA10"
						(effects
							(font
								(size 1.27 1.27)
							)
						)
					)
				)
				(pin input line
					(at 0 -22.86 0)
					(length 5.08)
					(name "M1_0"
						(effects
							(font
								(size 1.27 1.27)
							)
						)
					)
					(number "AA9"
						(effects
							(font
								(size 1.27 1.27)
							)
						)
					)
				)
				(pin input line
					(at 0 -25.4 0)
					(length 5.08)
					(name "M2_0"
						(effects
							(font
								(size 1.27 1.27)
							)
						)
					)
					(number "AF12"
						(effects
							(font
								(size 1.27 1.27)
							)
						)
					)
				)
				(pin input line
					(at 0 -30.48 0)
					(length 5.08)
					(name "TCK_0"
						(effects
							(font
								(size 1.27 1.27)
							)
						)
					)
					(number "AE12"
						(effects
							(font
								(size 1.27 1.27)
							)
						)
					)
				)
				(pin input line
					(at 0 -33.02 0)
					(length 5.08)
					(name "TDI_0"
						(effects
							(font
								(size 1.27 1.27)
							)
						)
					)
					(number "AB12"
						(effects
							(font
								(size 1.27 1.27)
							)
						)
					)
				)
				(pin output line
					(at 0 -35.56 0)
					(length 5.08)
					(name "TDO_0"
						(effects
							(font
								(size 1.27 1.27)
							)
						)
					)
					(number "Y10"
						(effects
							(font
								(size 1.27 1.27)
							)
						)
					)
				)
				(pin input line
					(at 0 -38.1 0)
					(length 5.08)
					(name "TMS_0"
						(effects
							(font
								(size 1.27 1.27)
							)
						)
					)
					(number "AB10"
						(effects
							(font
								(size 1.27 1.27)
							)
						)
					)
				)
				(pin bidirectional line
					(at 0 -43.18 0)
					(length 5.08)
					(name "D00_MOSI_0"
						(effects
							(font
								(size 1.27 1.27)
							)
						)
					)
					(number "AD11"
						(effects
							(font
								(size 1.27 1.27)
							)
						)
					)
				)
				(pin bidirectional line
					(at 0 -45.72 0)
					(length 5.08)
					(name "D01_DIN_0"
						(effects
							(font
								(size 1.27 1.27)
							)
						)
					)
					(number "AC12"
						(effects
							(font
								(size 1.27 1.27)
							)
						)
					)
				)
				(pin bidirectional line
					(at 0 -48.26 0)
					(length 5.08)
					(name "D02_0"
						(effects
							(font
								(size 1.27 1.27)
							)
						)
					)
					(number "AC11"
						(effects
							(font
								(size 1.27 1.27)
							)
						)
					)
				)
				(pin bidirectional line
					(at 0 -50.8 0)
					(length 5.08)
					(name "D03_0"
						(effects
							(font
								(size 1.27 1.27)
							)
						)
					)
					(number "AE11"
						(effects
							(font
								(size 1.27 1.27)
							)
						)
					)
				)
				(pin input line
					(at 0 -55.88 0)
					(length 5.08)
					(name "VP"
						(effects
							(font
								(size 1.27 1.27)
							)
						)
					)
					(number "P14"
						(effects
							(font
								(size 1.27 1.27)
							)
						)
					)
				)
				(pin input line
					(at 0 -58.42 0)
					(length 5.08)
					(name "VN"
						(effects
							(font
								(size 1.27 1.27)
							)
						)
					)
					(number "R13"
						(effects
							(font
								(size 1.27 1.27)
							)
						)
					)
				)
				(pin input line
					(at 0 -63.5 0)
					(length 5.08)
					(name "VREFP"
						(effects
							(font
								(size 1.27 1.27)
							)
						)
					)
					(number "R14"
						(effects
							(font
								(size 1.27 1.27)
							)
						)
					)
				)
				(pin input line
					(at 0 -66.04 0)
					(length 5.08)
					(name "VREFN"
						(effects
							(font
								(size 1.27 1.27)
							)
						)
					)
					(number "P13"
						(effects
							(font
								(size 1.27 1.27)
							)
						)
					)
				)
				(pin passive line
					(at 0 -71.12 0)
					(length 5.08)
					(name "DXP"
						(effects
							(font
								(size 1.27 1.27)
							)
						)
					)
					(number "T14"
						(effects
							(font
								(size 1.27 1.27)
							)
						)
					)
				)
				(pin passive line
					(at 0 -73.66 0)
					(length 5.08)
					(name "DXN"
						(effects
							(font
								(size 1.27 1.27)
							)
						)
					)
					(number "T13"
						(effects
							(font
								(size 1.27 1.27)
							)
						)
					)
				)
				(pin input line
					(at 0 -78.74 0)
					(length 5.08)
					(name "POR_OVERRIDE"
						(effects
							(font
								(size 1.27 1.27)
							)
						)
					)
					(number "Y12"
						(effects
							(font
								(size 1.27 1.27)
							)
						)
					)
				)
				(pin input line
					(at 0 -81.28 0)
					(length 5.08)
					(name "PUDC_B_0"
						(effects
							(font
								(size 1.27 1.27)
							)
						)
					)
					(number "W9"
						(effects
							(font
								(size 1.27 1.27)
							)
						)
					)
				)
			)
			(symbol "XCAU25P-2FFVB676I_2_2_1"
				(rectangle
					(start 5.08 2.54)
					(end 43.18 -142.24)
					(stroke
						(width 0.254)
						(type default)
					)
					(fill
						(type background)
					)
				)
				(polyline
					(pts
						(xy 30.48 -6.35) (xy 39.37 -6.35) (xy 39.37 -138.43) (xy 31.75 -138.43)
					)
					(stroke
						(width 0.254)
						(type default)
					)
					(fill
						(type background)
					)
				)
				(text "BANK 64"
					(at 30.48 -5.08 0)
					(effects
						(font
							(size 1.27 1.27)
							(thickness 0.15)
						)
						(justify left bottom)
					)
				)
				(text ""
					(at 50.8 -31.75 0)
					(effects
						(font
							(size 1.27 1.27)
							(thickness 0.15)
						)
						(justify left bottom)
					)
				)
				(text ""
					(at 50.8 -31.75 0)
					(effects
						(font
							(size 1.27 1.27)
							(thickness 0.15)
						)
						(justify left bottom)
					)
				)
				(pin power_in line
					(at 0 0 0)
					(length 5.08)
					(name "VCCO_64"
						(effects
							(font
								(size 1.27 1.27)
							)
						)
					)
					(number "AA21"
						(effects
							(font
								(size 1.27 1.27)
							)
						)
					)
				)
				(pin passive line
					(at 0 0 0)
					(length 5.08)
					(hide yes)
					(name "VCCO_64"
						(effects
							(font
								(size 1.27 1.27)
							)
						)
					)
					(number "AB18"
						(effects
							(font
								(size 1.27 1.27)
							)
						)
					)
				)
				(pin passive line
					(at 0 0 0)
					(length 5.08)
					(hide yes)
					(name "VCCO_64"
						(effects
							(font
								(size 1.27 1.27)
							)
						)
					)
					(number "AD22"
						(effects
							(font
								(size 1.27 1.27)
							)
						)
					)
				)
				(pin input line
					(at 0 -2.54 0)
					(length 5.08)
					(name "VREF_64"
						(effects
							(font
								(size 1.27 1.27)
							)
						)
					)
					(number "W18"
						(effects
							(font
								(size 1.27 1.27)
							)
						)
					)
				)
				(pin bidirectional line
					(at 0 -7.62 0)
					(length 5.08)
					(name "IO_L1P_T0L_N0_DBC_64"
						(effects
							(font
								(size 1.27 1.27)
							)
						)
					)
					(number "AE25"
						(effects
							(font
								(size 1.27 1.27)
							)
						)
					)
				)
				(pin bidirectional line
					(at 0 -10.16 0)
					(length 5.08)
					(name "IO_L1N_T0L_N1_DBC_64"
						(effects
							(font
								(size 1.27 1.27)
							)
						)
					)
					(number "AE26"
						(effects
							(font
								(size 1.27 1.27)
							)
						)
					)
				)
				(pin bidirectional line
					(at 0 -12.7 0)
					(length 5.08)
					(name "IO_L2P_T0L_N2_64"
						(effects
							(font
								(size 1.27 1.27)
							)
						)
					)
					(number "AB25"
						(effects
							(font
								(size 1.27 1.27)
							)
						)
					)
				)
				(pin bidirectional line
					(at 0 -15.24 0)
					(length 5.08)
					(name "IO_L2N_T0L_N3_64"
						(effects
							(font
								(size 1.27 1.27)
							)
						)
					)
					(number "AB26"
						(effects
							(font
								(size 1.27 1.27)
							)
						)
					)
				)
				(pin bidirectional line
					(at 0 -17.78 0)
					(length 5.08)
					(name "IO_L3P_T0L_N4_AD15P_64"
						(effects
							(font
								(size 1.27 1.27)
							)
						)
					)
					(number "AF24"
						(effects
							(font
								(size 1.27 1.27)
							)
						)
					)
				)
				(pin bidirectional line
					(at 0 -20.32 0)
					(length 5.08)
					(name "IO_L3N_T0L_N5_AD15N_64"
						(effects
							(font
								(size 1.27 1.27)
							)
						)
					)
					(number "AF25"
						(effects
							(font
								(size 1.27 1.27)
							)
						)
					)
				)
				(pin bidirectional line
					(at 0 -22.86 0)
					(length 5.08)
					(name "IO_L4P_T0U_N6_DBC_AD7P_64"
						(effects
							(font
								(size 1.27 1.27)
							)
						)
					)
					(number "AC26"
						(effects
							(font
								(size 1.27 1.27)
							)
						)
					)
				)
				(pin bidirectional line
					(at 0 -25.4 0)
					(length 5.08)
					(name "IO_L4N_T0U_N7_DBC_AD7N_64"
						(effects
							(font
								(size 1.27 1.27)
							)
						)
					)
					(number "AD26"
						(effects
							(font
								(size 1.27 1.27)
							)
						)
					)
				)
				(pin bidirectional line
					(at 0 -27.94 0)
					(length 5.08)
					(name "IO_L5P_T0U_N8_AD14P_64"
						(effects
							(font
								(size 1.27 1.27)
							)
						)
					)
					(number "AD24"
						(effects
							(font
								(size 1.27 1.27)
							)
						)
					)
				)
				(pin bidirectional line
					(at 0 -30.48 0)
					(length 5.08)
					(name "IO_L5N_T0U_N9_AD14N_64"
						(effects
							(font
								(size 1.27 1.27)
							)
						)
					)
					(number "AD25"
						(effects
							(font
								(size 1.27 1.27)
							)
						)
					)
				)
				(pin bidirectional line
					(at 0 -33.02 0)
					(length 5.08)
					(name "IO_L6P_T0U_N10_AD6P_64"
						(effects
							(font
								(size 1.27 1.27)
							)
						)
					)
					(number "AB24"
						(effects
							(font
								(size 1.27 1.27)
							)
						)
					)
				)
				(pin bidirectional line
					(at 0 -35.56 0)
					(length 5.08)
					(name "IO_L6N_T0U_N11_AD6N_64"
						(effects
							(font
								(size 1.27 1.27)
							)
						)
					)
					(number "AC24"
						(effects
							(font
								(size 1.27 1.27)
							)
						)
					)
				)
				(pin bidirectional line
					(at 0 -38.1 0)
					(length 5.08)
					(name "IO_T0U_N12_VRP_64"
						(effects
							(font
								(size 1.27 1.27)
							)
						)
					)
					(number "AF23"
						(effects
							(font
								(size 1.27 1.27)
							)
						)
					)
				)
				(pin bidirectional line
					(at 0 -40.64 0)
					(length 5.08)
					(name "IO_L7P_T1L_N0_QBC_AD13P_64"
						(effects
							(font
								(size 1.27 1.27)
							)
						)
					)
					(number "AE22"
						(effects
							(font
								(size 1.27 1.27)
							)
						)
					)
				)
				(pin bidirectional line
					(at 0 -43.18 0)
					(length 5.08)
					(name "IO_L7N_T1L_N1_QBC_AD13N_64"
						(effects
							(font
								(size 1.27 1.27)
							)
						)
					)
					(number "AF22"
						(effects
							(font
								(size 1.27 1.27)
							)
						)
					)
				)
				(pin bidirectional line
					(at 0 -45.72 0)
					(length 5.08)
					(name "IO_L8P_T1L_N2_AD5P_64"
						(effects
							(font
								(size 1.27 1.27)
							)
						)
					)
					(number "AD23"
						(effects
							(font
								(size 1.27 1.27)
							)
						)
					)
				)
				(pin bidirectional line
					(at 0 -48.26 0)
					(length 5.08)
					(name "IO_L8N_T1L_N3_AD5N_64"
						(effects
							(font
								(size 1.27 1.27)
							)
						)
					)
					(number "AE23"
						(effects
							(font
								(size 1.27 1.27)
							)
						)
					)
				)
				(pin bidirectional line
					(at 0 -50.8 0)
					(length 5.08)
					(name "IO_L9P_T1L_N4_AD12P_64"
						(effects
							(font
								(size 1.27 1.27)
							)
						)
					)
					(number "AC22"
						(effects
							(font
								(size 1.27 1.27)
							)
						)
					)
				)
				(pin bidirectional line
					(at 0 -53.34 0)
					(length 5.08)
					(name "IO_L9N_T1L_N5_AD12N_64"
						(effects
							(font
								(size 1.27 1.27)
							)
						)
					)
					(number "AC23"
						(effects
							(font
								(size 1.27 1.27)
							)
						)
					)
				)
				(pin bidirectional line
					(at 0 -55.88 0)
					(length 5.08)
					(name "IO_L10P_T1U_N6_QBC_AD4P_64"
						(effects
							(font
								(size 1.27 1.27)
							)
						)
					)
					(number "AA22"
						(effects
							(font
								(size 1.27 1.27)
							)
						)
					)
				)
				(pin bidirectional line
					(at 0 -58.42 0)
					(length 5.08)
					(name "IO_L10N_T1U_N7_QBC_AD4N_64"
						(effects
							(font
								(size 1.27 1.27)
							)
						)
					)
					(number "AB22"
						(effects
							(font
								(size 1.27 1.27)
							)
						)
					)
				)
				(pin bidirectional line
					(at 0 -60.96 0)
					(length 5.08)
					(name "IO_L11P_T1U_N8_GC_64"
						(effects
							(font
								(size 1.27 1.27)
							)
						)
					)
					(number "AD21"
						(effects
							(font
								(size 1.27 1.27)
							)
						)
					)
				)
				(pin bidirectional line
					(at 0 -63.5 0)
					(length 5.08)
					(name "IO_L11N_T1U_N9_GC_64"
						(effects
							(font
								(size 1.27 1.27)
							)
						)
					)
					(number "AE21"
						(effects
							(font
								(size 1.27 1.27)
							)
						)
					)
				)
				(pin bidirectional line
					(at 0 -66.04 0)
					(length 5.08)
					(name "IO_L12P_T1U_N10_GC_64"
						(effects
							(font
								(size 1.27 1.27)
							)
						)
					)
					(number "AB21"
						(effects
							(font
								(size 1.27 1.27)
							)
						)
					)
				)
				(pin bidirectional line
					(at 0 -68.58 0)
					(length 5.08)
					(name "IO_L12N_T1U_N11_GC_64"
						(effects
							(font
								(size 1.27 1.27)
							)
						)
					)
					(number "AC21"
						(effects
							(font
								(size 1.27 1.27)
							)
						)
					)
				)
				(pin bidirectional line
					(at 0 -71.12 0)
					(length 5.08)
					(name "IO_T1U_N12_64"
						(effects
							(font
								(size 1.27 1.27)
							)
						)
					)
					(number "AF20"
						(effects
							(font
								(size 1.27 1.27)
							)
						)
					)
				)
				(pin bidirectional line
					(at 0 -73.66 0)
					(length 5.08)
					(name "IO_L13P_T2L_N0_GC_QBC_64"
						(effects
							(font
								(size 1.27 1.27)
							)
						)
					)
					(number "AD20"
						(effects
							(font
								(size 1.27 1.27)
							)
						)
					)
				)
				(pin bidirectional line
					(at 0 -76.2 0)
					(length 5.08)
					(name "IO_L13N_T2L_N1_GC_QBC_64"
						(effects
							(font
								(size 1.27 1.27)
							)
						)
					)
					(number "AE20"
						(effects
							(font
								(size 1.27 1.27)
							)
						)
					)
				)
				(pin bidirectional line
					(at 0 -78.74 0)
					(length 5.08)
					(name "IO_L14P_T2L_N2_GC_64"
						(effects
							(font
								(size 1.27 1.27)
							)
						)
					)
					(number "AC19"
						(effects
							(font
								(size 1.27 1.27)
							)
						)
					)
				)
				(pin bidirectional line
					(at 0 -81.28 0)
					(length 5.08)
					(name "IO_L14N_T2L_N3_GC_64"
						(effects
							(font
								(size 1.27 1.27)
							)
						)
					)
					(number "AD19"
						(effects
							(font
								(size 1.27 1.27)
							)
						)
					)
				)
				(pin bidirectional line
					(at 0 -83.82 0)
					(length 5.08)
					(name "IO_L15P_T2L_N4_AD11P_64"
						(effects
							(font
								(size 1.27 1.27)
							)
						)
					)
					(number "AF18"
						(effects
							(font
								(size 1.27 1.27)
							)
						)
					)
				)
				(pin bidirectional line
					(at 0 -86.36 0)
					(length 5.08)
					(name "IO_L15N_T2L_N5_AD11N_64"
						(effects
							(font
								(size 1.27 1.27)
							)
						)
					)
					(number "AF19"
						(effects
							(font
								(size 1.27 1.27)
							)
						)
					)
				)
				(pin bidirectional line
					(at 0 -88.9 0)
					(length 5.08)
					(name "IO_L16P_T2U_N6_QBC_AD3P_64"
						(effects
							(font
								(size 1.27 1.27)
							)
						)
					)
					(number "AC18"
						(effects
							(font
								(size 1.27 1.27)
							)
						)
					)
				)
				(pin bidirectional line
					(at 0 -91.44 0)
					(length 5.08)
					(name "IO_L16N_T2U_N7_QBC_AD3N_64"
						(effects
							(font
								(size 1.27 1.27)
							)
						)
					)
					(number "AD18"
						(effects
							(font
								(size 1.27 1.27)
							)
						)
					)
				)
				(pin bidirectional line
					(at 0 -93.98 0)
					(length 5.08)
					(name "IO_L17P_T2U_N8_AD10P_64"
						(effects
							(font
								(size 1.27 1.27)
							)
						)
					)
					(number "AE17"
						(effects
							(font
								(size 1.27 1.27)
							)
						)
					)
				)
				(pin bidirectional line
					(at 0 -96.52 0)
					(length 5.08)
					(name "IO_L17N_T2U_N9_AD10N_64"
						(effects
							(font
								(size 1.27 1.27)
							)
						)
					)
					(number "AF17"
						(effects
							(font
								(size 1.27 1.27)
							)
						)
					)
				)
				(pin bidirectional line
					(at 0 -99.06 0)
					(length 5.08)
					(name "IO_L18P_T2U_N10_AD2P_64"
						(effects
							(font
								(size 1.27 1.27)
							)
						)
					)
					(number "AD16"
						(effects
							(font
								(size 1.27 1.27)
							)
						)
					)
				)
				(pin bidirectional line
					(at 0 -101.6 0)
					(length 5.08)
					(name "IO_L18N_T2U_N11_AD2N_64"
						(effects
							(font
								(size 1.27 1.27)
							)
						)
					)
					(number "AE16"
						(effects
							(font
								(size 1.27 1.27)
							)
						)
					)
				)
				(pin bidirectional line
					(at 0 -104.14 0)
					(length 5.08)
					(name "IO_T2U_N12_64"
						(effects
							(font
								(size 1.27 1.27)
							)
						)
					)
					(number "AE18"
						(effects
							(font
								(size 1.27 1.27)
							)
						)
					)
				)
				(pin bidirectional line
					(at 0 -106.68 0)
					(length 5.08)
					(name "IO_L19P_T3L_N0_DBC_AD9P_64"
						(effects
							(font
								(size 1.27 1.27)
							)
						)
					)
					(number "Y20"
						(effects
							(font
								(size 1.27 1.27)
							)
						)
					)
				)
				(pin bidirectional line
					(at 0 -109.22 0)
					(length 5.08)
					(name "IO_L19N_T3L_N1_DBC_AD9N_64"
						(effects
							(font
								(size 1.27 1.27)
							)
						)
					)
					(number "Y21"
						(effects
							(font
								(size 1.27 1.27)
							)
						)
					)
				)
				(pin bidirectional line
					(at 0 -111.76 0)
					(length 5.08)
					(name "IO_L20P_T3L_N2_AD1P_64"
						(effects
							(font
								(size 1.27 1.27)
							)
						)
					)
					(number "AA19"
						(effects
							(font
								(size 1.27 1.27)
							)
						)
					)
				)
				(pin bidirectional line
					(at 0 -114.3 0)
					(length 5.08)
					(name "IO_L20N_T3L_N3_AD1N_64"
						(effects
							(font
								(size 1.27 1.27)
							)
						)
					)
					(number "AB19"
						(effects
							(font
								(size 1.27 1.27)
							)
						)
					)
				)
				(pin bidirectional line
					(at 0 -116.84 0)
					(length 5.08)
					(name "IO_L21P_T3L_N4_AD8P_64"
						(effects
							(font
								(size 1.27 1.27)
							)
						)
					)
					(number "AA20"
						(effects
							(font
								(size 1.27 1.27)
							)
						)
					)
				)
				(pin bidirectional line
					(at 0 -119.38 0)
					(length 5.08)
					(name "IO_L21N_T3L_N5_AD8N_64"
						(effects
							(font
								(size 1.27 1.27)
							)
						)
					)
					(number "AB20"
						(effects
							(font
								(size 1.27 1.27)
							)
						)
					)
				)
				(pin bidirectional line
					(at 0 -121.92 0)
					(length 5.08)
					(name "IO_L22P_T3U_N6_DBC_AD0P_64"
						(effects
							(font
								(size 1.27 1.27)
							)
						)
					)
					(number "AB17"
						(effects
							(font
								(size 1.27 1.27)
							)
						)
					)
				)
				(pin bidirectional line
					(at 0 -124.46 0)
					(length 5.08)
					(name "IO_L22N_T3U_N7_DBC_AD0N_64"
						(effects
							(font
								(size 1.27 1.27)
							)
						)
					)
					(number "AC17"
						(effects
							(font
								(size 1.27 1.27)
							)
						)
					)
				)
				(pin bidirectional line
					(at 0 -127 0)
					(length 5.08)
					(name "IO_L23P_T3U_N8_64"
						(effects
							(font
								(size 1.27 1.27)
							)
						)
					)
					(number "Y17"
						(effects
							(font
								(size 1.27 1.27)
							)
						)
					)
				)
				(pin bidirectional line
					(at 0 -129.54 0)
					(length 5.08)
					(name "IO_L23N_T3U_N9_64"
						(effects
							(font
								(size 1.27 1.27)
							)
						)
					)
					(number "AA17"
						(effects
							(font
								(size 1.27 1.27)
							)
						)
					)
				)
				(pin bidirectional line
					(at 0 -132.08 0)
					(length 5.08)
					(name "IO_L24P_T3U_N10_64"
						(effects
							(font
								(size 1.27 1.27)
							)
						)
					)
					(number "Y18"
						(effects
							(font
								(size 1.27 1.27)
							)
						)
					)
				)
				(pin bidirectional line
					(at 0 -134.62 0)
					(length 5.08)
					(name "IO_L24N_T3U_N11_64"
						(effects
							(font
								(size 1.27 1.27)
							)
						)
					)
					(number "AA18"
						(effects
							(font
								(size 1.27 1.27)
							)
						)
					)
				)
				(pin bidirectional line
					(at 0 -137.16 0)
					(length 5.08)
					(name "IO_T3U_N12_64"
						(effects
							(font
								(size 1.27 1.27)
							)
						)
					)
					(number "AC16"
						(effects
							(font
								(size 1.27 1.27)
							)
						)
					)
				)
			)
			(symbol "XCAU25P-2FFVB676I_2_3_1"
				(rectangle
					(start 5.08 2.54)
					(end 50.8 -142.24)
					(stroke
						(width 0.254)
						(type default)
					)
					(fill
						(type background)
					)
				)
				(polyline
					(pts
						(xy 36.83 -5.08) (xy 44.45 -5.08) (xy 44.45 -138.43) (xy 36.83 -138.43)
					)
					(stroke
						(width 0.254)
						(type default)
					)
					(fill
						(type background)
					)
				)
				(text "BANK 65"
					(at 36.83 -3.81 0)
					(effects
						(font
							(size 1.27 1.27)
							(thickness 0.15)
						)
						(justify left bottom)
					)
				)
				(text ""
					(at 50.8 -31.75 0)
					(effects
						(font
							(size 1.27 1.27)
							(thickness 0.15)
						)
						(justify left bottom)
					)
				)
				(text ""
					(at 50.8 -31.75 0)
					(effects
						(font
							(size 1.27 1.27)
							(thickness 0.15)
						)
						(justify left bottom)
					)
				)
				(pin power_in line
					(at 0 0 0)
					(length 5.08)
					(name "VCCO_65"
						(effects
							(font
								(size 1.27 1.27)
							)
						)
					)
					(number "P22"
						(effects
							(font
								(size 1.27 1.27)
							)
						)
					)
				)
				(pin passive line
					(at 0 0 0)
					(length 5.08)
					(hide yes)
					(name "VCCO_65"
						(effects
							(font
								(size 1.27 1.27)
							)
						)
					)
					(number "U23"
						(effects
							(font
								(size 1.27 1.27)
							)
						)
					)
				)
				(pin passive line
					(at 0 0 0)
					(length 5.08)
					(hide yes)
					(name "VCCO_65"
						(effects
							(font
								(size 1.27 1.27)
							)
						)
					)
					(number "Y24"
						(effects
							(font
								(size 1.27 1.27)
							)
						)
					)
				)
				(pin input line
					(at 0 -2.54 0)
					(length 5.08)
					(name "VREF_65"
						(effects
							(font
								(size 1.27 1.27)
							)
						)
					)
					(number "V18"
						(effects
							(font
								(size 1.27 1.27)
							)
						)
					)
				)
				(pin bidirectional line
					(at 0 -7.62 0)
					(length 5.08)
					(name "IO_L1P_T0L_N0_DBC_RS0_65"
						(effects
							(font
								(size 1.27 1.27)
							)
						)
					)
					(number "U19"
						(effects
							(font
								(size 1.27 1.27)
							)
						)
					)
				)
				(pin bidirectional line
					(at 0 -10.16 0)
					(length 5.08)
					(name "IO_L1N_T0L_N1_DBC_RS1_65"
						(effects
							(font
								(size 1.27 1.27)
							)
						)
					)
					(number "V19"
						(effects
							(font
								(size 1.27 1.27)
							)
						)
					)
				)
				(pin bidirectional line
					(at 0 -12.7 0)
					(length 5.08)
					(name "IO_L2P_T0L_N2_FOE_B_65"
						(effects
							(font
								(size 1.27 1.27)
							)
						)
					)
					(number "U21"
						(effects
							(font
								(size 1.27 1.27)
							)
						)
					)
				)
				(pin bidirectional line
					(at 0 -15.24 0)
					(length 5.08)
					(name "IO_L2N_T0L_N3_FWE_FCS2_B_65"
						(effects
							(font
								(size 1.27 1.27)
							)
						)
					)
					(number "U22"
						(effects
							(font
								(size 1.27 1.27)
							)
						)
					)
				)
				(pin bidirectional line
					(at 0 -17.78 0)
					(length 5.08)
					(name "IO_L3P_T0L_N4_AD15P_A26_65"
						(effects
							(font
								(size 1.27 1.27)
							)
						)
					)
					(number "T20"
						(effects
							(font
								(size 1.27 1.27)
							)
						)
					)
				)
				(pin bidirectional line
					(at 0 -20.32 0)
					(length 5.08)
					(name "IO_L3N_T0L_N5_AD15N_A27_65"
						(effects
							(font
								(size 1.27 1.27)
							)
						)
					)
					(number "U20"
						(effects
							(font
								(size 1.27 1.27)
							)
						)
					)
				)
				(pin bidirectional line
					(at 0 -22.86 0)
					(length 5.08)
					(name "IO_L4P_T0U_N6_DBC_AD7P_A24_65"
						(effects
							(font
								(size 1.27 1.27)
							)
						)
					)
					(number "V21"
						(effects
							(font
								(size 1.27 1.27)
							)
						)
					)
				)
				(pin bidirectional line
					(at 0 -25.4 0)
					(length 5.08)
					(name "IO_L4N_T0U_N7_DBC_AD7N_A25_65"
						(effects
							(font
								(size 1.27 1.27)
							)
						)
					)
					(number "V22"
						(effects
							(font
								(size 1.27 1.27)
							)
						)
					)
				)
				(pin bidirectional line
					(at 0 -27.94 0)
					(length 5.08)
					(name "IO_L5P_T0U_N8_AD14P_A22_65"
						(effects
							(font
								(size 1.27 1.27)
							)
						)
					)
					(number "T22"
						(effects
							(font
								(size 1.27 1.27)
							)
						)
					)
				)
				(pin bidirectional line
					(at 0 -30.48 0)
					(length 5.08)
					(name "IO_L5N_T0U_N9_AD14N_A23_65"
						(effects
							(font
								(size 1.27 1.27)
							)
						)
					)
					(number "T23"
						(effects
							(font
								(size 1.27 1.27)
							)
						)
					)
				)
				(pin bidirectional line
					(at 0 -33.02 0)
					(length 5.08)
					(name "IO_L6P_T0U_N10_AD6P_A20_65"
						(effects
							(font
								(size 1.27 1.27)
							)
						)
					)
					(number "W19"
						(effects
							(font
								(size 1.27 1.27)
							)
						)
					)
				)
				(pin bidirectional line
					(at 0 -35.56 0)
					(length 5.08)
					(name "IO_L6N_T0U_N11_AD6N_A21_65"
						(effects
							(font
								(size 1.27 1.27)
							)
						)
					)
					(number "W20"
						(effects
							(font
								(size 1.27 1.27)
							)
						)
					)
				)
				(pin bidirectional line
					(at 0 -38.1 0)
					(length 5.08)
					(name "IO_T0U_N12_VRP_A28_65"
						(effects
							(font
								(size 1.27 1.27)
							)
						)
					)
					(number "W21"
						(effects
							(font
								(size 1.27 1.27)
							)
						)
					)
				)
				(pin bidirectional line
					(at 0 -40.64 0)
					(length 5.08)
					(name "IO_L7P_T1L_N0_QBC_AD13P_A18_65"
						(effects
							(font
								(size 1.27 1.27)
							)
						)
					)
					(number "Y22"
						(effects
							(font
								(size 1.27 1.27)
							)
						)
					)
				)
				(pin bidirectional line
					(at 0 -43.18 0)
					(length 5.08)
					(name "IO_L7N_T1L_N1_QBC_AD13N_A19_65"
						(effects
							(font
								(size 1.27 1.27)
							)
						)
					)
					(number "Y23"
						(effects
							(font
								(size 1.27 1.27)
							)
						)
					)
				)
				(pin bidirectional line
					(at 0 -45.72 0)
					(length 5.08)
					(name "IO_L8P_T1L_N2_AD5P_A16_65"
						(effects
							(font
								(size 1.27 1.27)
							)
						)
					)
					(number "Y25"
						(effects
							(font
								(size 1.27 1.27)
							)
						)
					)
				)
				(pin bidirectional line
					(at 0 -48.26 0)
					(length 5.08)
					(name "IO_L8N_T1L_N3_AD5N_A17_65"
						(effects
							(font
								(size 1.27 1.27)
							)
						)
					)
					(number "Y26"
						(effects
							(font
								(size 1.27 1.27)
							)
						)
					)
				)
				(pin bidirectional line
					(at 0 -50.8 0)
					(length 5.08)
					(name "IO_L9P_T1L_N4_AD12P_A14_D30_65"
						(effects
							(font
								(size 1.27 1.27)
							)
						)
					)
					(number "AA24"
						(effects
							(font
								(size 1.27 1.27)
							)
						)
					)
				)
				(pin bidirectional line
					(at 0 -53.34 0)
					(length 5.08)
					(name "IO_L9N_T1L_N5_AD12N_A15_D31_65"
						(effects
							(font
								(size 1.27 1.27)
							)
						)
					)
					(number "AA25"
						(effects
							(font
								(size 1.27 1.27)
							)
						)
					)
				)
				(pin bidirectional line
					(at 0 -55.88 0)
					(length 5.08)
					(name "IO_L10P_T1U_N6_QBC_AD4P_A12_D28_65"
						(effects
							(font
								(size 1.27 1.27)
							)
						)
					)
					(number "W25"
						(effects
							(font
								(size 1.27 1.27)
							)
						)
					)
				)
				(pin bidirectional line
					(at 0 -58.42 0)
					(length 5.08)
					(name "IO_L10N_T1U_N7_QBC_AD4N_A13_D29_65"
						(effects
							(font
								(size 1.27 1.27)
							)
						)
					)
					(number "W26"
						(effects
							(font
								(size 1.27 1.27)
							)
						)
					)
				)
				(pin bidirectional line
					(at 0 -60.96 0)
					(length 5.08)
					(name "IO_L11P_T1U_N8_GC_A10_D26_65"
						(effects
							(font
								(size 1.27 1.27)
							)
						)
					)
					(number "V23"
						(effects
							(font
								(size 1.27 1.27)
							)
						)
					)
				)
				(pin bidirectional line
					(at 0 -63.5 0)
					(length 5.08)
					(name "IO_L11N_T1U_N9_GC_A11_D27_65"
						(effects
							(font
								(size 1.27 1.27)
							)
						)
					)
					(number "W23"
						(effects
							(font
								(size 1.27 1.27)
							)
						)
					)
				)
				(pin bidirectional line
					(at 0 -66.04 0)
					(length 5.08)
					(name "IO_L12P_T1U_N10_GC_A08_D24_65"
						(effects
							(font
								(size 1.27 1.27)
							)
						)
					)
					(number "V24"
						(effects
							(font
								(size 1.27 1.27)
							)
						)
					)
				)
				(pin bidirectional line
					(at 0 -68.58 0)
					(length 5.08)
					(name "IO_L12N_T1U_N11_GC_A09_D25_65"
						(effects
							(font
								(size 1.27 1.27)
							)
						)
					)
					(number "W24"
						(effects
							(font
								(size 1.27 1.27)
							)
						)
					)
				)
				(pin bidirectional line
					(at 0 -71.12 0)
					(length 5.08)
					(name "IO_T1U_N12_SMBALERT_65"
						(effects
							(font
								(size 1.27 1.27)
							)
						)
					)
					(number "AA23"
						(effects
							(font
								(size 1.27 1.27)
							)
						)
					)
				)
				(pin bidirectional line
					(at 0 -73.66 0)
					(length 5.08)
					(name "IO_L13P_T2L_N0_GC_QBC_A06_D22_65"
						(effects
							(font
								(size 1.27 1.27)
							)
						)
					)
					(number "T24"
						(effects
							(font
								(size 1.27 1.27)
							)
						)
					)
				)
				(pin bidirectional line
					(at 0 -76.2 0)
					(length 5.08)
					(name "IO_L13N_T2L_N1_GC_QBC_A07_D23_65"
						(effects
							(font
								(size 1.27 1.27)
							)
						)
					)
					(number "U24"
						(effects
							(font
								(size 1.27 1.27)
							)
						)
					)
				)
				(pin bidirectional line
					(at 0 -78.74 0)
					(length 5.08)
					(name "IO_L14P_T2L_N2_GC_A04_D20_65"
						(effects
							(font
								(size 1.27 1.27)
							)
						)
					)
					(number "T25"
						(effects
							(font
								(size 1.27 1.27)
							)
						)
					)
				)
				(pin bidirectional line
					(at 0 -81.28 0)
					(length 5.08)
					(name "IO_L14N_T2L_N3_GC_A05_D21_65"
						(effects
							(font
								(size 1.27 1.27)
							)
						)
					)
					(number "U25"
						(effects
							(font
								(size 1.27 1.27)
							)
						)
					)
				)
				(pin bidirectional line
					(at 0 -83.82 0)
					(length 5.08)
					(name "IO_L15P_T2L_N4_AD11P_A02_D18_65"
						(effects
							(font
								(size 1.27 1.27)
							)
						)
					)
					(number "N24"
						(effects
							(font
								(size 1.27 1.27)
							)
						)
					)
				)
				(pin bidirectional line
					(at 0 -86.36 0)
					(length 5.08)
					(name "IO_L15N_T2L_N5_AD11N_A03_D19_65"
						(effects
							(font
								(size 1.27 1.27)
							)
						)
					)
					(number "P24"
						(effects
							(font
								(size 1.27 1.27)
							)
						)
					)
				)
				(pin bidirectional line
					(at 0 -88.9 0)
					(length 5.08)
					(name "IO_L16P_T2U_N6_QBC_AD3P_A00_D16_65"
						(effects
							(font
								(size 1.27 1.27)
							)
						)
					)
					(number "U26"
						(effects
							(font
								(size 1.27 1.27)
							)
						)
					)
				)
				(pin bidirectional line
					(at 0 -91.44 0)
					(length 5.08)
					(name "IO_L16N_T2U_N7_QBC_AD3N_A01_D17_65"
						(effects
							(font
								(size 1.27 1.27)
							)
						)
					)
					(number "V26"
						(effects
							(font
								(size 1.27 1.27)
							)
						)
					)
				)
				(pin bidirectional line
					(at 0 -93.98 0)
					(length 5.08)
					(name "IO_L17P_T2U_N8_AD10P_D14_65"
						(effects
							(font
								(size 1.27 1.27)
							)
						)
					)
					(number "P25"
						(effects
							(font
								(size 1.27 1.27)
							)
						)
					)
				)
				(pin bidirectional line
					(at 0 -96.52 0)
					(length 5.08)
					(name "IO_L17N_T2U_N9_AD10N_D15_65"
						(effects
							(font
								(size 1.27 1.27)
							)
						)
					)
					(number "P26"
						(effects
							(font
								(size 1.27 1.27)
							)
						)
					)
				)
				(pin bidirectional line
					(at 0 -99.06 0)
					(length 5.08)
					(name "IO_L18P_T2U_N10_AD2P_D12_65"
						(effects
							(font
								(size 1.27 1.27)
							)
						)
					)
					(number "R25"
						(effects
							(font
								(size 1.27 1.27)
							)
						)
					)
				)
				(pin bidirectional line
					(at 0 -101.6 0)
					(length 5.08)
					(name "IO_L18N_T2U_N11_AD2N_D13_65"
						(effects
							(font
								(size 1.27 1.27)
							)
						)
					)
					(number "R26"
						(effects
							(font
								(size 1.27 1.27)
							)
						)
					)
				)
				(pin bidirectional line
					(at 0 -104.14 0)
					(length 5.08)
					(name "IO_T2U_N12_CSI_ADV_B_65"
						(effects
							(font
								(size 1.27 1.27)
							)
						)
					)
					(number "N26"
						(effects
							(font
								(size 1.27 1.27)
							)
						)
					)
				)
				(pin bidirectional line
					(at 0 -106.68 0)
					(length 5.08)
					(name "IO_L19P_T3L_N0_DBC_AD9P_D10_65"
						(effects
							(font
								(size 1.27 1.27)
							)
						)
					)
					(number "R22"
						(effects
							(font
								(size 1.27 1.27)
							)
						)
					)
				)
				(pin bidirectional line
					(at 0 -109.22 0)
					(length 5.08)
					(name "IO_L19N_T3L_N1_DBC_AD9N_D11_65"
						(effects
							(font
								(size 1.27 1.27)
							)
						)
					)
					(number "R23"
						(effects
							(font
								(size 1.27 1.27)
							)
						)
					)
				)
				(pin bidirectional line
					(at 0 -111.76 0)
					(length 5.08)
					(name "IO_L20P_T3L_N2_AD1P_D08_65"
						(effects
							(font
								(size 1.27 1.27)
							)
						)
					)
					(number "P20"
						(effects
							(font
								(size 1.27 1.27)
							)
						)
					)
				)
				(pin bidirectional line
					(at 0 -114.3 0)
					(length 5.08)
					(name "IO_L20N_T3L_N3_AD1N_D09_65"
						(effects
							(font
								(size 1.27 1.27)
							)
						)
					)
					(number "P21"
						(effects
							(font
								(size 1.27 1.27)
							)
						)
					)
				)
				(pin bidirectional line
					(at 0 -116.84 0)
					(length 5.08)
					(name "IO_L21P_T3L_N4_AD8P_D06_65"
						(effects
							(font
								(size 1.27 1.27)
							)
						)
					)
					(number "R20"
						(effects
							(font
								(size 1.27 1.27)
							)
						)
					)
				)
				(pin bidirectional line
					(at 0 -119.38 0)
					(length 5.08)
					(name "IO_L21N_T3L_N5_AD8N_D07_65"
						(effects
							(font
								(size 1.27 1.27)
							)
						)
					)
					(number "R21"
						(effects
							(font
								(size 1.27 1.27)
							)
						)
					)
				)
				(pin bidirectional line
					(at 0 -121.92 0)
					(length 5.08)
					(name "IO_L22P_T3U_N6_DBC_AD0P_D04_65"
						(effects
							(font
								(size 1.27 1.27)
							)
						)
					)
					(number "N23"
						(effects
							(font
								(size 1.27 1.27)
							)
						)
					)
				)
				(pin bidirectional line
					(at 0 -124.46 0)
					(length 5.08)
					(name "IO_L22N_T3U_N7_DBC_AD0N_D05_65"
						(effects
							(font
								(size 1.27 1.27)
							)
						)
					)
					(number "P23"
						(effects
							(font
								(size 1.27 1.27)
							)
						)
					)
				)
				(pin bidirectional line
					(at 0 -127 0)
					(length 5.08)
					(name "IO_L23P_T3U_N8_I2C_SCLK_65"
						(effects
							(font
								(size 1.27 1.27)
							)
						)
					)
					(number "N19"
						(effects
							(font
								(size 1.27 1.27)
							)
						)
					)
				)
				(pin bidirectional line
					(at 0 -129.54 0)
					(length 5.08)
					(name "IO_L23N_T3U_N9_PERSTN1_I2C_SDA_65"
						(effects
							(font
								(size 1.27 1.27)
							)
						)
					)
					(number "P19"
						(effects
							(font
								(size 1.27 1.27)
							)
						)
					)
				)
				(pin bidirectional line
					(at 0 -132.08 0)
					(length 5.08)
					(name "IO_L24P_T3U_N10_EMCCLK_65"
						(effects
							(font
								(size 1.27 1.27)
							)
						)
					)
					(number "N21"
						(effects
							(font
								(size 1.27 1.27)
							)
						)
					)
				)
				(pin bidirectional line
					(at 0 -134.62 0)
					(length 5.08)
					(name "IO_L24N_T3U_N11_DOUT_CSO_B_65"
						(effects
							(font
								(size 1.27 1.27)
							)
						)
					)
					(number "N22"
						(effects
							(font
								(size 1.27 1.27)
							)
						)
					)
				)
				(pin bidirectional line
					(at 0 -137.16 0)
					(length 5.08)
					(name "IO_T3U_N12_PERSTN0_65"
						(effects
							(font
								(size 1.27 1.27)
							)
						)
					)
					(number "T19"
						(effects
							(font
								(size 1.27 1.27)
							)
						)
					)
				)
			)
			(symbol "XCAU25P-2FFVB676I_2_4_1"
				(rectangle
					(start 5.08 2.54)
					(end 43.18 -142.24)
					(stroke
						(width 0.254)
						(type default)
					)
					(fill
						(type background)
					)
				)
				(polyline
					(pts
						(xy 30.48 -6.35) (xy 39.37 -6.35) (xy 39.37 -138.43) (xy 31.75 -138.43)
					)
					(stroke
						(width 0.254)
						(type default)
					)
					(fill
						(type background)
					)
				)
				(text "BANK 66"
					(at 30.48 -5.08 0)
					(effects
						(font
							(size 1.27 1.27)
							(thickness 0.15)
						)
						(justify left bottom)
					)
				)
				(text ""
					(at 50.8 -31.75 0)
					(effects
						(font
							(size 1.27 1.27)
							(thickness 0.15)
						)
						(justify left bottom)
					)
				)
				(text ""
					(at 50.8 -31.75 0)
					(effects
						(font
							(size 1.27 1.27)
							(thickness 0.15)
						)
						(justify left bottom)
					)
				)
				(pin power_in line
					(at 0 0 0)
					(length 5.08)
					(name "VCCO_66"
						(effects
							(font
								(size 1.27 1.27)
							)
						)
					)
					(number "E24"
						(effects
							(font
								(size 1.27 1.27)
							)
						)
					)
				)
				(pin passive line
					(at 0 0 0)
					(length 5.08)
					(hide yes)
					(name "VCCO_66"
						(effects
							(font
								(size 1.27 1.27)
							)
						)
					)
					(number "H25"
						(effects
							(font
								(size 1.27 1.27)
							)
						)
					)
				)
				(pin passive line
					(at 0 0 0)
					(length 5.08)
					(hide yes)
					(name "VCCO_66"
						(effects
							(font
								(size 1.27 1.27)
							)
						)
					)
					(number "J22"
						(effects
							(font
								(size 1.27 1.27)
							)
						)
					)
				)
				(pin input line
					(at 0 -2.54 0)
					(length 5.08)
					(name "VREF_66"
						(effects
							(font
								(size 1.27 1.27)
							)
						)
					)
					(number "J18"
						(effects
							(font
								(size 1.27 1.27)
							)
						)
					)
				)
				(pin bidirectional line
					(at 0 -7.62 0)
					(length 5.08)
					(name "IO_L1P_T0L_N0_DBC_66"
						(effects
							(font
								(size 1.27 1.27)
							)
						)
					)
					(number "L18"
						(effects
							(font
								(size 1.27 1.27)
							)
						)
					)
				)
				(pin bidirectional line
					(at 0 -10.16 0)
					(length 5.08)
					(name "IO_L1N_T0L_N1_DBC_66"
						(effects
							(font
								(size 1.27 1.27)
							)
						)
					)
					(number "K18"
						(effects
							(font
								(size 1.27 1.27)
							)
						)
					)
				)
				(pin bidirectional line
					(at 0 -12.7 0)
					(length 5.08)
					(name "IO_L2P_T0L_N2_66"
						(effects
							(font
								(size 1.27 1.27)
							)
						)
					)
					(number "M20"
						(effects
							(font
								(size 1.27 1.27)
							)
						)
					)
				)
				(pin bidirectional line
					(at 0 -15.24 0)
					(length 5.08)
					(name "IO_L2N_T0L_N3_66"
						(effects
							(font
								(size 1.27 1.27)
							)
						)
					)
					(number "M21"
						(effects
							(font
								(size 1.27 1.27)
							)
						)
					)
				)
				(pin bidirectional line
					(at 0 -17.78 0)
					(length 5.08)
					(name "IO_L3P_T0L_N4_AD15P_66"
						(effects
							(font
								(size 1.27 1.27)
							)
						)
					)
					(number "J19"
						(effects
							(font
								(size 1.27 1.27)
							)
						)
					)
				)
				(pin bidirectional line
					(at 0 -20.32 0)
					(length 5.08)
					(name "IO_L3N_T0L_N5_AD15N_66"
						(effects
							(font
								(size 1.27 1.27)
							)
						)
					)
					(number "J20"
						(effects
							(font
								(size 1.27 1.27)
							)
						)
					)
				)
				(pin bidirectional line
					(at 0 -22.86 0)
					(length 5.08)
					(name "IO_L4P_T0U_N6_DBC_AD7P_66"
						(effects
							(font
								(size 1.27 1.27)
							)
						)
					)
					(number "M19"
						(effects
							(font
								(size 1.27 1.27)
							)
						)
					)
				)
				(pin bidirectional line
					(at 0 -25.4 0)
					(length 5.08)
					(name "IO_L4N_T0U_N7_DBC_AD7N_66"
						(effects
							(font
								(size 1.27 1.27)
							)
						)
					)
					(number "L19"
						(effects
							(font
								(size 1.27 1.27)
							)
						)
					)
				)
				(pin bidirectional line
					(at 0 -27.94 0)
					(length 5.08)
					(name "IO_L5P_T0U_N8_AD14P_66"
						(effects
							(font
								(size 1.27 1.27)
							)
						)
					)
					(number "K21"
						(effects
							(font
								(size 1.27 1.27)
							)
						)
					)
				)
				(pin bidirectional line
					(at 0 -30.48 0)
					(length 5.08)
					(name "IO_L5N_T0U_N9_AD14N_66"
						(effects
							(font
								(size 1.27 1.27)
							)
						)
					)
					(number "J21"
						(effects
							(font
								(size 1.27 1.27)
							)
						)
					)
				)
				(pin bidirectional line
					(at 0 -33.02 0)
					(length 5.08)
					(name "IO_L6P_T0U_N10_AD6P_66"
						(effects
							(font
								(size 1.27 1.27)
							)
						)
					)
					(number "L20"
						(effects
							(font
								(size 1.27 1.27)
							)
						)
					)
				)
				(pin bidirectional line
					(at 0 -35.56 0)
					(length 5.08)
					(name "IO_L6N_T0U_N11_AD6N_66"
						(effects
							(font
								(size 1.27 1.27)
							)
						)
					)
					(number "K20"
						(effects
							(font
								(size 1.27 1.27)
							)
						)
					)
				)
				(pin bidirectional line
					(at 0 -38.1 0)
					(length 5.08)
					(name "IO_T0U_N12_VRP_66"
						(effects
							(font
								(size 1.27 1.27)
							)
						)
					)
					(number "M22"
						(effects
							(font
								(size 1.27 1.27)
							)
						)
					)
				)
				(pin bidirectional line
					(at 0 -40.64 0)
					(length 5.08)
					(name "IO_L7P_T1L_N0_QBC_AD13P_66"
						(effects
							(font
								(size 1.27 1.27)
							)
						)
					)
					(number "L22"
						(effects
							(font
								(size 1.27 1.27)
							)
						)
					)
				)
				(pin bidirectional line
					(at 0 -43.18 0)
					(length 5.08)
					(name "IO_L7N_T1L_N1_QBC_AD13N_66"
						(effects
							(font
								(size 1.27 1.27)
							)
						)
					)
					(number "L23"
						(effects
							(font
								(size 1.27 1.27)
							)
						)
					)
				)
				(pin bidirectional line
					(at 0 -45.72 0)
					(length 5.08)
					(name "IO_L8P_T1L_N2_AD5P_66"
						(effects
							(font
								(size 1.27 1.27)
							)
						)
					)
					(number "M25"
						(effects
							(font
								(size 1.27 1.27)
							)
						)
					)
				)
				(pin bidirectional line
					(at 0 -48.26 0)
					(length 5.08)
					(name "IO_L8N_T1L_N3_AD5N_66"
						(effects
							(font
								(size 1.27 1.27)
							)
						)
					)
					(number "M26"
						(effects
							(font
								(size 1.27 1.27)
							)
						)
					)
				)
				(pin bidirectional line
					(at 0 -50.8 0)
					(length 5.08)
					(name "IO_L9P_T1L_N4_AD12P_66"
						(effects
							(font
								(size 1.27 1.27)
							)
						)
					)
					(number "K25"
						(effects
							(font
								(size 1.27 1.27)
							)
						)
					)
				)
				(pin bidirectional line
					(at 0 -53.34 0)
					(length 5.08)
					(name "IO_L9N_T1L_N5_AD12N_66"
						(effects
							(font
								(size 1.27 1.27)
							)
						)
					)
					(number "K26"
						(effects
							(font
								(size 1.27 1.27)
							)
						)
					)
				)
				(pin bidirectional line
					(at 0 -55.88 0)
					(length 5.08)
					(name "IO_L10P_T1U_N6_QBC_AD4P_66"
						(effects
							(font
								(size 1.27 1.27)
							)
						)
					)
					(number "L24"
						(effects
							(font
								(size 1.27 1.27)
							)
						)
					)
				)
				(pin bidirectional line
					(at 0 -58.42 0)
					(length 5.08)
					(name "IO_L10N_T1U_N7_QBC_AD4N_66"
						(effects
							(font
								(size 1.27 1.27)
							)
						)
					)
					(number "L25"
						(effects
							(font
								(size 1.27 1.27)
							)
						)
					)
				)
				(pin bidirectional line
					(at 0 -60.96 0)
					(length 5.08)
					(name "IO_L11P_T1U_N8_GC_66"
						(effects
							(font
								(size 1.27 1.27)
							)
						)
					)
					(number "K22"
						(effects
							(font
								(size 1.27 1.27)
							)
						)
					)
				)
				(pin bidirectional line
					(at 0 -63.5 0)
					(length 5.08)
					(name "IO_L11N_T1U_N9_GC_66"
						(effects
							(font
								(size 1.27 1.27)
							)
						)
					)
					(number "K23"
						(effects
							(font
								(size 1.27 1.27)
							)
						)
					)
				)
				(pin bidirectional line
					(at 0 -66.04 0)
					(length 5.08)
					(name "IO_L12P_T1U_N10_GC_66"
						(effects
							(font
								(size 1.27 1.27)
							)
						)
					)
					(number "J23"
						(effects
							(font
								(size 1.27 1.27)
							)
						)
					)
				)
				(pin bidirectional line
					(at 0 -68.58 0)
					(length 5.08)
					(name "IO_L12N_T1U_N11_GC_66"
						(effects
							(font
								(size 1.27 1.27)
							)
						)
					)
					(number "J24"
						(effects
							(font
								(size 1.27 1.27)
							)
						)
					)
				)
				(pin bidirectional line
					(at 0 -71.12 0)
					(length 5.08)
					(name "IO_T1U_N12_66"
						(effects
							(font
								(size 1.27 1.27)
							)
						)
					)
					(number "M24"
						(effects
							(font
								(size 1.27 1.27)
							)
						)
					)
				)
				(pin bidirectional line
					(at 0 -73.66 0)
					(length 5.08)
					(name "IO_L13P_T2L_N0_GC_QBC_66"
						(effects
							(font
								(size 1.27 1.27)
							)
						)
					)
					(number "G24"
						(effects
							(font
								(size 1.27 1.27)
							)
						)
					)
				)
				(pin bidirectional line
					(at 0 -76.2 0)
					(length 5.08)
					(name "IO_L13N_T2L_N1_GC_QBC_66"
						(effects
							(font
								(size 1.27 1.27)
							)
						)
					)
					(number "G25"
						(effects
							(font
								(size 1.27 1.27)
							)
						)
					)
				)
				(pin bidirectional line
					(at 0 -78.74 0)
					(length 5.08)
					(name "IO_L14P_T2L_N2_GC_66"
						(effects
							(font
								(size 1.27 1.27)
							)
						)
					)
					(number "H23"
						(effects
							(font
								(size 1.27 1.27)
							)
						)
					)
				)
				(pin bidirectional line
					(at 0 -81.28 0)
					(length 5.08)
					(name "IO_L14N_T2L_N3_GC_66"
						(effects
							(font
								(size 1.27 1.27)
							)
						)
					)
					(number "H24"
						(effects
							(font
								(size 1.27 1.27)
							)
						)
					)
				)
				(pin bidirectional line
					(at 0 -83.82 0)
					(length 5.08)
					(name "IO_L15P_T2L_N4_AD11P_66"
						(effects
							(font
								(size 1.27 1.27)
							)
						)
					)
					(number "J25"
						(effects
							(font
								(size 1.27 1.27)
							)
						)
					)
				)
				(pin bidirectional line
					(at 0 -86.36 0)
					(length 5.08)
					(name "IO_L15N_T2L_N5_AD11N_66"
						(effects
							(font
								(size 1.27 1.27)
							)
						)
					)
					(number "J26"
						(effects
							(font
								(size 1.27 1.27)
							)
						)
					)
				)
				(pin bidirectional line
					(at 0 -88.9 0)
					(length 5.08)
					(name "IO_L16P_T2U_N6_QBC_AD3P_66"
						(effects
							(font
								(size 1.27 1.27)
							)
						)
					)
					(number "F24"
						(effects
							(font
								(size 1.27 1.27)
							)
						)
					)
				)
				(pin bidirectional line
					(at 0 -91.44 0)
					(length 5.08)
					(name "IO_L16N_T2U_N7_QBC_AD3N_66"
						(effects
							(font
								(size 1.27 1.27)
							)
						)
					)
					(number "F25"
						(effects
							(font
								(size 1.27 1.27)
							)
						)
					)
				)
				(pin bidirectional line
					(at 0 -93.98 0)
					(length 5.08)
					(name "IO_L17P_T2U_N8_AD10P_66"
						(effects
							(font
								(size 1.27 1.27)
							)
						)
					)
					(number "H26"
						(effects
							(font
								(size 1.27 1.27)
							)
						)
					)
				)
				(pin bidirectional line
					(at 0 -96.52 0)
					(length 5.08)
					(name "IO_L17N_T2U_N9_AD10N_66"
						(effects
							(font
								(size 1.27 1.27)
							)
						)
					)
					(number "G26"
						(effects
							(font
								(size 1.27 1.27)
							)
						)
					)
				)
				(pin bidirectional line
					(at 0 -99.06 0)
					(length 5.08)
					(name "IO_L18P_T2U_N10_AD2P_66"
						(effects
							(font
								(size 1.27 1.27)
							)
						)
					)
					(number "H21"
						(effects
							(font
								(size 1.27 1.27)
							)
						)
					)
				)
				(pin bidirectional line
					(at 0 -101.6 0)
					(length 5.08)
					(name "IO_L18N_T2U_N11_AD2N_66"
						(effects
							(font
								(size 1.27 1.27)
							)
						)
					)
					(number "H22"
						(effects
							(font
								(size 1.27 1.27)
							)
						)
					)
				)
				(pin bidirectional line
					(at 0 -104.14 0)
					(length 5.08)
					(name "IO_T2U_N12_66"
						(effects
							(font
								(size 1.27 1.27)
							)
						)
					)
					(number "G22"
						(effects
							(font
								(size 1.27 1.27)
							)
						)
					)
				)
				(pin bidirectional line
					(at 0 -106.68 0)
					(length 5.08)
					(name "IO_L19P_T3L_N0_DBC_AD9P_66"
						(effects
							(font
								(size 1.27 1.27)
							)
						)
					)
					(number "E25"
						(effects
							(font
								(size 1.27 1.27)
							)
						)
					)
				)
				(pin bidirectional line
					(at 0 -109.22 0)
					(length 5.08)
					(name "IO_L19N_T3L_N1_DBC_AD9N_66"
						(effects
							(font
								(size 1.27 1.27)
							)
						)
					)
					(number "E26"
						(effects
							(font
								(size 1.27 1.27)
							)
						)
					)
				)
				(pin bidirectional line
					(at 0 -111.76 0)
					(length 5.08)
					(name "IO_L20P_T3L_N2_AD1P_66"
						(effects
							(font
								(size 1.27 1.27)
							)
						)
					)
					(number "F23"
						(effects
							(font
								(size 1.27 1.27)
							)
						)
					)
				)
				(pin bidirectional line
					(at 0 -114.3 0)
					(length 5.08)
					(name "IO_L20N_T3L_N3_AD1N_66"
						(effects
							(font
								(size 1.27 1.27)
							)
						)
					)
					(number "E23"
						(effects
							(font
								(size 1.27 1.27)
							)
						)
					)
				)
				(pin bidirectional line
					(at 0 -116.84 0)
					(length 5.08)
					(name "IO_L21P_T3L_N4_AD8P_66"
						(effects
							(font
								(size 1.27 1.27)
							)
						)
					)
					(number "D24"
						(effects
							(font
								(size 1.27 1.27)
							)
						)
					)
				)
				(pin bidirectional line
					(at 0 -119.38 0)
					(length 5.08)
					(name "IO_L21N_T3L_N5_AD8N_66"
						(effects
							(font
								(size 1.27 1.27)
							)
						)
					)
					(number "D25"
						(effects
							(font
								(size 1.27 1.27)
							)
						)
					)
				)
				(pin bidirectional line
					(at 0 -121.92 0)
					(length 5.08)
					(name "IO_L22P_T3U_N6_DBC_AD0P_66"
						(effects
							(font
								(size 1.27 1.27)
							)
						)
					)
					(number "D23"
						(effects
							(font
								(size 1.27 1.27)
							)
						)
					)
				)
				(pin bidirectional line
					(at 0 -124.46 0)
					(length 5.08)
					(name "IO_L22N_T3U_N7_DBC_AD0N_66"
						(effects
							(font
								(size 1.27 1.27)
							)
						)
					)
					(number "C24"
						(effects
							(font
								(size 1.27 1.27)
							)
						)
					)
				)
				(pin bidirectional line
					(at 0 -127 0)
					(length 5.08)
					(name "IO_L23P_T3U_N8_66"
						(effects
							(font
								(size 1.27 1.27)
							)
						)
					)
					(number "D26"
						(effects
							(font
								(size 1.27 1.27)
							)
						)
					)
				)
				(pin bidirectional line
					(at 0 -129.54 0)
					(length 5.08)
					(name "IO_L23N_T3U_N9_66"
						(effects
							(font
								(size 1.27 1.27)
							)
						)
					)
					(number "C26"
						(effects
							(font
								(size 1.27 1.27)
							)
						)
					)
				)
				(pin bidirectional line
					(at 0 -132.08 0)
					(length 5.08)
					(name "IO_L24P_T3U_N10_66"
						(effects
							(font
								(size 1.27 1.27)
							)
						)
					)
					(number "B25"
						(effects
							(font
								(size 1.27 1.27)
							)
						)
					)
				)
				(pin bidirectional line
					(at 0 -134.62 0)
					(length 5.08)
					(name "IO_L24N_T3U_N11_66"
						(effects
							(font
								(size 1.27 1.27)
							)
						)
					)
					(number "B26"
						(effects
							(font
								(size 1.27 1.27)
							)
						)
					)
				)
				(pin bidirectional line
					(at 0 -137.16 0)
					(length 5.08)
					(name "IO_T3U_N12_66"
						(effects
							(font
								(size 1.27 1.27)
							)
						)
					)
					(number "F22"
						(effects
							(font
								(size 1.27 1.27)
							)
						)
					)
				)
			)
			(symbol "XCAU25P-2FFVB676I_2_5_1"
				(rectangle
					(start 5.08 2.54)
					(end 43.18 -142.24)
					(stroke
						(width 0.254)
						(type default)
					)
					(fill
						(type background)
					)
				)
				(polyline
					(pts
						(xy 30.48 -6.35) (xy 39.37 -6.35) (xy 39.37 -138.43) (xy 31.75 -138.43)
					)
					(stroke
						(width 0.254)
						(type default)
					)
					(fill
						(type background)
					)
				)
				(text "BANK 67"
					(at 30.48 -5.08 0)
					(effects
						(font
							(size 1.27 1.27)
							(thickness 0.15)
						)
						(justify left bottom)
					)
				)
				(text ""
					(at 50.8 -31.75 0)
					(effects
						(font
							(size 1.27 1.27)
							(thickness 0.15)
						)
						(justify left bottom)
					)
				)
				(text ""
					(at 50.8 -31.75 0)
					(effects
						(font
							(size 1.27 1.27)
							(thickness 0.15)
						)
						(justify left bottom)
					)
				)
				(pin power_in line
					(at 0 0 0)
					(length 5.08)
					(name "VCCO_67"
						(effects
							(font
								(size 1.27 1.27)
							)
						)
					)
					(number "C20"
						(effects
							(font
								(size 1.27 1.27)
							)
						)
					)
				)
				(pin passive line
					(at 0 0 0)
					(length 5.08)
					(hide yes)
					(name "VCCO_67"
						(effects
							(font
								(size 1.27 1.27)
							)
						)
					)
					(number "D17"
						(effects
							(font
								(size 1.27 1.27)
							)
						)
					)
				)
				(pin passive line
					(at 0 0 0)
					(length 5.08)
					(hide yes)
					(name "VCCO_67"
						(effects
							(font
								(size 1.27 1.27)
							)
						)
					)
					(number "G18"
						(effects
							(font
								(size 1.27 1.27)
							)
						)
					)
				)
				(pin input line
					(at 0 -2.54 0)
					(length 5.08)
					(name "VREF_67"
						(effects
							(font
								(size 1.27 1.27)
							)
						)
					)
					(number "J16"
						(effects
							(font
								(size 1.27 1.27)
							)
						)
					)
				)
				(pin bidirectional line
					(at 0 -7.62 0)
					(length 5.08)
					(name "IO_L1P_T0L_N0_DBC_67"
						(effects
							(font
								(size 1.27 1.27)
							)
						)
					)
					(number "G15"
						(effects
							(font
								(size 1.27 1.27)
							)
						)
					)
				)
				(pin bidirectional line
					(at 0 -10.16 0)
					(length 5.08)
					(name "IO_L1N_T0L_N1_DBC_67"
						(effects
							(font
								(size 1.27 1.27)
							)
						)
					)
					(number "F15"
						(effects
							(font
								(size 1.27 1.27)
							)
						)
					)
				)
				(pin bidirectional line
					(at 0 -12.7 0)
					(length 5.08)
					(name "IO_L2P_T0L_N2_67"
						(effects
							(font
								(size 1.27 1.27)
							)
						)
					)
					(number "H17"
						(effects
							(font
								(size 1.27 1.27)
							)
						)
					)
				)
				(pin bidirectional line
					(at 0 -15.24 0)
					(length 5.08)
					(name "IO_L2N_T0L_N3_67"
						(effects
							(font
								(size 1.27 1.27)
							)
						)
					)
					(number "G17"
						(effects
							(font
								(size 1.27 1.27)
							)
						)
					)
				)
				(pin bidirectional line
					(at 0 -17.78 0)
					(length 5.08)
					(name "IO_L3P_T0L_N4_AD15P_67"
						(effects
							(font
								(size 1.27 1.27)
							)
						)
					)
					(number "E15"
						(effects
							(font
								(size 1.27 1.27)
							)
						)
					)
				)
				(pin bidirectional line
					(at 0 -20.32 0)
					(length 5.08)
					(name "IO_L3N_T0L_N5_AD15N_67"
						(effects
							(font
								(size 1.27 1.27)
							)
						)
					)
					(number "D15"
						(effects
							(font
								(size 1.27 1.27)
							)
						)
					)
				)
				(pin bidirectional line
					(at 0 -22.86 0)
					(length 5.08)
					(name "IO_L4P_T0U_N6_DBC_AD7P_67"
						(effects
							(font
								(size 1.27 1.27)
							)
						)
					)
					(number "E16"
						(effects
							(font
								(size 1.27 1.27)
							)
						)
					)
				)
				(pin bidirectional line
					(at 0 -25.4 0)
					(length 5.08)
					(name "IO_L4N_T0U_N7_DBC_AD7N_67"
						(effects
							(font
								(size 1.27 1.27)
							)
						)
					)
					(number "E17"
						(effects
							(font
								(size 1.27 1.27)
							)
						)
					)
				)
				(pin bidirectional line
					(at 0 -27.94 0)
					(length 5.08)
					(name "IO_L5P_T0U_N8_AD14P_67"
						(effects
							(font
								(size 1.27 1.27)
							)
						)
					)
					(number "H16"
						(effects
							(font
								(size 1.27 1.27)
							)
						)
					)
				)
				(pin bidirectional line
					(at 0 -30.48 0)
					(length 5.08)
					(name "IO_L5N_T0U_N9_AD14N_67"
						(effects
							(font
								(size 1.27 1.27)
							)
						)
					)
					(number "G16"
						(effects
							(font
								(size 1.27 1.27)
							)
						)
					)
				)
				(pin bidirectional line
					(at 0 -33.02 0)
					(length 5.08)
					(name "IO_L6P_T0U_N10_AD6P_67"
						(effects
							(font
								(size 1.27 1.27)
							)
						)
					)
					(number "D16"
						(effects
							(font
								(size 1.27 1.27)
							)
						)
					)
				)
				(pin bidirectional line
					(at 0 -35.56 0)
					(length 5.08)
					(name "IO_L6N_T0U_N11_AD6N_67"
						(effects
							(font
								(size 1.27 1.27)
							)
						)
					)
					(number "C16"
						(effects
							(font
								(size 1.27 1.27)
							)
						)
					)
				)
				(pin bidirectional line
					(at 0 -38.1 0)
					(length 5.08)
					(name "IO_T0U_N12_VRP_67"
						(effects
							(font
								(size 1.27 1.27)
							)
						)
					)
					(number "F17"
						(effects
							(font
								(size 1.27 1.27)
							)
						)
					)
				)
				(pin bidirectional line
					(at 0 -40.64 0)
					(length 5.08)
					(name "IO_L7P_T1L_N0_QBC_AD13P_67"
						(effects
							(font
								(size 1.27 1.27)
							)
						)
					)
					(number "H18"
						(effects
							(font
								(size 1.27 1.27)
							)
						)
					)
				)
				(pin bidirectional line
					(at 0 -43.18 0)
					(length 5.08)
					(name "IO_L7N_T1L_N1_QBC_AD13N_67"
						(effects
							(font
								(size 1.27 1.27)
							)
						)
					)
					(number "H19"
						(effects
							(font
								(size 1.27 1.27)
							)
						)
					)
				)
				(pin bidirectional line
					(at 0 -45.72 0)
					(length 5.08)
					(name "IO_L8P_T1L_N2_AD5P_67"
						(effects
							(font
								(size 1.27 1.27)
							)
						)
					)
					(number "F18"
						(effects
							(font
								(size 1.27 1.27)
							)
						)
					)
				)
				(pin bidirectional line
					(at 0 -48.26 0)
					(length 5.08)
					(name "IO_L8N_T1L_N3_AD5N_67"
						(effects
							(font
								(size 1.27 1.27)
							)
						)
					)
					(number "F19"
						(effects
							(font
								(size 1.27 1.27)
							)
						)
					)
				)
				(pin bidirectional line
					(at 0 -50.8 0)
					(length 5.08)
					(name "IO_L9P_T1L_N4_AD12P_67"
						(effects
							(font
								(size 1.27 1.27)
							)
						)
					)
					(number "G20"
						(effects
							(font
								(size 1.27 1.27)
							)
						)
					)
				)
				(pin bidirectional line
					(at 0 -53.34 0)
					(length 5.08)
					(name "IO_L9N_T1L_N5_AD12N_67"
						(effects
							(font
								(size 1.27 1.27)
							)
						)
					)
					(number "G21"
						(effects
							(font
								(size 1.27 1.27)
							)
						)
					)
				)
				(pin bidirectional line
					(at 0 -55.88 0)
					(length 5.08)
					(name "IO_L10P_T1U_N6_QBC_AD4P_67"
						(effects
							(font
								(size 1.27 1.27)
							)
						)
					)
					(number "F20"
						(effects
							(font
								(size 1.27 1.27)
							)
						)
					)
				)
				(pin bidirectional line
					(at 0 -58.42 0)
					(length 5.08)
					(name "IO_L10N_T1U_N7_QBC_AD4N_67"
						(effects
							(font
								(size 1.27 1.27)
							)
						)
					)
					(number "E20"
						(effects
							(font
								(size 1.27 1.27)
							)
						)
					)
				)
				(pin bidirectional line
					(at 0 -60.96 0)
					(length 5.08)
					(name "IO_L11P_T1U_N8_GC_67"
						(effects
							(font
								(size 1.27 1.27)
							)
						)
					)
					(number "E18"
						(effects
							(font
								(size 1.27 1.27)
							)
						)
					)
				)
				(pin bidirectional line
					(at 0 -63.5 0)
					(length 5.08)
					(name "IO_L11N_T1U_N9_GC_67"
						(effects
							(font
								(size 1.27 1.27)
							)
						)
					)
					(number "D18"
						(effects
							(font
								(size 1.27 1.27)
							)
						)
					)
				)
				(pin bidirectional line
					(at 0 -66.04 0)
					(length 5.08)
					(name "IO_L12P_T1U_N10_GC_67"
						(effects
							(font
								(size 1.27 1.27)
							)
						)
					)
					(number "D19"
						(effects
							(font
								(size 1.27 1.27)
							)
						)
					)
				)
				(pin bidirectional line
					(at 0 -68.58 0)
					(length 5.08)
					(name "IO_L12N_T1U_N11_GC_67"
						(effects
							(font
								(size 1.27 1.27)
							)
						)
					)
					(number "D20"
						(effects
							(font
								(size 1.27 1.27)
							)
						)
					)
				)
				(pin bidirectional line
					(at 0 -71.12 0)
					(length 5.08)
					(name "IO_T1U_N12_67"
						(effects
							(font
								(size 1.27 1.27)
							)
						)
					)
					(number "G19"
						(effects
							(font
								(size 1.27 1.27)
							)
						)
					)
				)
				(pin bidirectional line
					(at 0 -73.66 0)
					(length 5.08)
					(name "IO_L13P_T2L_N0_GC_QBC_67"
						(effects
							(font
								(size 1.27 1.27)
							)
						)
					)
					(number "C18"
						(effects
							(font
								(size 1.27 1.27)
							)
						)
					)
				)
				(pin bidirectional line
					(at 0 -76.2 0)
					(length 5.08)
					(name "IO_L13N_T2L_N1_GC_QBC_67"
						(effects
							(font
								(size 1.27 1.27)
							)
						)
					)
					(number "C19"
						(effects
							(font
								(size 1.27 1.27)
							)
						)
					)
				)
				(pin bidirectional line
					(at 0 -78.74 0)
					(length 5.08)
					(name "IO_L14P_T2L_N2_GC_67"
						(effects
							(font
								(size 1.27 1.27)
							)
						)
					)
					(number "B19"
						(effects
							(font
								(size 1.27 1.27)
							)
						)
					)
				)
				(pin bidirectional line
					(at 0 -81.28 0)
					(length 5.08)
					(name "IO_L14N_T2L_N3_GC_67"
						(effects
							(font
								(size 1.27 1.27)
							)
						)
					)
					(number "B20"
						(effects
							(font
								(size 1.27 1.27)
							)
						)
					)
				)
				(pin bidirectional line
					(at 0 -83.82 0)
					(length 5.08)
					(name "IO_L15P_T2L_N4_AD11P_67"
						(effects
							(font
								(size 1.27 1.27)
							)
						)
					)
					(number "C17"
						(effects
							(font
								(size 1.27 1.27)
							)
						)
					)
				)
				(pin bidirectional line
					(at 0 -86.36 0)
					(length 5.08)
					(name "IO_L15N_T2L_N5_AD11N_67"
						(effects
							(font
								(size 1.27 1.27)
							)
						)
					)
					(number "B17"
						(effects
							(font
								(size 1.27 1.27)
							)
						)
					)
				)
				(pin bidirectional line
					(at 0 -88.9 0)
					(length 5.08)
					(name "IO_L16P_T2U_N6_QBC_AD3P_67"
						(effects
							(font
								(size 1.27 1.27)
							)
						)
					)
					(number "A17"
						(effects
							(font
								(size 1.27 1.27)
							)
						)
					)
				)
				(pin bidirectional line
					(at 0 -91.44 0)
					(length 5.08)
					(name "IO_L16N_T2U_N7_QBC_AD3N_67"
						(effects
							(font
								(size 1.27 1.27)
							)
						)
					)
					(number "A18"
						(effects
							(font
								(size 1.27 1.27)
							)
						)
					)
				)
				(pin bidirectional line
					(at 0 -93.98 0)
					(length 5.08)
					(name "IO_L17P_T2U_N8_AD10P_67"
						(effects
							(font
								(size 1.27 1.27)
							)
						)
					)
					(number "B15"
						(effects
							(font
								(size 1.27 1.27)
							)
						)
					)
				)
				(pin bidirectional line
					(at 0 -96.52 0)
					(length 5.08)
					(name "IO_L17N_T2U_N9_AD10N_67"
						(effects
							(font
								(size 1.27 1.27)
							)
						)
					)
					(number "A15"
						(effects
							(font
								(size 1.27 1.27)
							)
						)
					)
				)
				(pin bidirectional line
					(at 0 -99.06 0)
					(length 5.08)
					(name "IO_L18P_T2U_N10_AD2P_67"
						(effects
							(font
								(size 1.27 1.27)
							)
						)
					)
					(number "A19"
						(effects
							(font
								(size 1.27 1.27)
							)
						)
					)
				)
				(pin bidirectional line
					(at 0 -101.6 0)
					(length 5.08)
					(name "IO_L18N_T2U_N11_AD2N_67"
						(effects
							(font
								(size 1.27 1.27)
							)
						)
					)
					(number "A20"
						(effects
							(font
								(size 1.27 1.27)
							)
						)
					)
				)
				(pin bidirectional line
					(at 0 -104.14 0)
					(length 5.08)
					(name "IO_T2U_N12_67"
						(effects
							(font
								(size 1.27 1.27)
							)
						)
					)
					(number "B16"
						(effects
							(font
								(size 1.27 1.27)
							)
						)
					)
				)
				(pin bidirectional line
					(at 0 -106.68 0)
					(length 5.08)
					(name "IO_L19P_T3L_N0_DBC_AD9P_67"
						(effects
							(font
								(size 1.27 1.27)
							)
						)
					)
					(number "A22"
						(effects
							(font
								(size 1.27 1.27)
							)
						)
					)
				)
				(pin bidirectional line
					(at 0 -109.22 0)
					(length 5.08)
					(name "IO_L19N_T3L_N1_DBC_AD9N_67"
						(effects
							(font
								(size 1.27 1.27)
							)
						)
					)
					(number "A23"
						(effects
							(font
								(size 1.27 1.27)
							)
						)
					)
				)
				(pin bidirectional line
					(at 0 -111.76 0)
					(length 5.08)
					(name "IO_L20P_T3L_N2_AD1P_67"
						(effects
							(font
								(size 1.27 1.27)
							)
						)
					)
					(number "E21"
						(effects
							(font
								(size 1.27 1.27)
							)
						)
					)
				)
				(pin bidirectional line
					(at 0 -114.3 0)
					(length 5.08)
					(name "IO_L20N_T3L_N3_AD1N_67"
						(effects
							(font
								(size 1.27 1.27)
							)
						)
					)
					(number "D21"
						(effects
							(font
								(size 1.27 1.27)
							)
						)
					)
				)
				(pin bidirectional line
					(at 0 -116.84 0)
					(length 5.08)
					(name "IO_L21P_T3L_N4_AD8P_67"
						(effects
							(font
								(size 1.27 1.27)
							)
						)
					)
					(number "C23"
						(effects
							(font
								(size 1.27 1.27)
							)
						)
					)
				)
				(pin bidirectional line
					(at 0 -119.38 0)
					(length 5.08)
					(name "IO_L21N_T3L_N5_AD8N_67"
						(effects
							(font
								(size 1.27 1.27)
							)
						)
					)
					(number "B24"
						(effects
							(font
								(size 1.27 1.27)
							)
						)
					)
				)
				(pin bidirectional line
					(at 0 -121.92 0)
					(length 5.08)
					(name "IO_L22P_T3U_N6_DBC_AD0P_67"
						(effects
							(font
								(size 1.27 1.27)
							)
						)
					)
					(number "C21"
						(effects
							(font
								(size 1.27 1.27)
							)
						)
					)
				)
				(pin bidirectional line
					(at 0 -124.46 0)
					(length 5.08)
					(name "IO_L22N_T3U_N7_DBC_AD0N_67"
						(effects
							(font
								(size 1.27 1.27)
							)
						)
					)
					(number "B21"
						(effects
							(font
								(size 1.27 1.27)
							)
						)
					)
				)
				(pin bidirectional line
					(at 0 -127 0)
					(length 5.08)
					(name "IO_L23P_T3U_N8_67"
						(effects
							(font
								(size 1.27 1.27)
							)
						)
					)
					(number "A24"
						(effects
							(font
								(size 1.27 1.27)
							)
						)
					)
				)
				(pin bidirectional line
					(at 0 -129.54 0)
					(length 5.08)
					(name "IO_L23N_T3U_N9_67"
						(effects
							(font
								(size 1.27 1.27)
							)
						)
					)
					(number "A25"
						(effects
							(font
								(size 1.27 1.27)
							)
						)
					)
				)
				(pin bidirectional line
					(at 0 -132.08 0)
					(length 5.08)
					(name "IO_L24P_T3U_N10_67"
						(effects
							(font
								(size 1.27 1.27)
							)
						)
					)
					(number "C22"
						(effects
							(font
								(size 1.27 1.27)
							)
						)
					)
				)
				(pin bidirectional line
					(at 0 -134.62 0)
					(length 5.08)
					(name "IO_L24N_T3U_N11_67"
						(effects
							(font
								(size 1.27 1.27)
							)
						)
					)
					(number "B22"
						(effects
							(font
								(size 1.27 1.27)
							)
						)
					)
				)
				(pin bidirectional line
					(at 0 -137.16 0)
					(length 5.08)
					(name "IO_T3U_N12_67"
						(effects
							(font
								(size 1.27 1.27)
							)
						)
					)
					(number "E22"
						(effects
							(font
								(size 1.27 1.27)
							)
						)
					)
				)
			)
			(symbol "XCAU25P-2FFVB676I_2_6_1"
				(rectangle
					(start 5.08 2.54)
					(end 33.02 -68.58)
					(stroke
						(width 0.254)
						(type default)
					)
					(fill
						(type background)
					)
				)
				(polyline
					(pts
						(xy 22.86 -3.81) (xy 30.48 -3.81) (xy 30.48 -64.77) (xy 22.86 -64.77)
					)
					(stroke
						(width 0.254)
						(type default)
					)
					(fill
						(type background)
					)
				)
				(text "BANK 84"
					(at 22.86 -2.54 0)
					(effects
						(font
							(size 1.27 1.27)
							(thickness 0.15)
						)
						(justify left bottom)
					)
				)
				(text ""
					(at 50.8 -31.75 0)
					(effects
						(font
							(size 1.27 1.27)
							(thickness 0.15)
						)
						(justify left bottom)
					)
				)
				(text ""
					(at 50.8 -31.75 0)
					(effects
						(font
							(size 1.27 1.27)
							(thickness 0.15)
						)
						(justify left bottom)
					)
				)
				(pin power_in line
					(at 0 0 0)
					(length 5.08)
					(name "VCCO_84"
						(effects
							(font
								(size 1.27 1.27)
							)
						)
					)
					(number "AC15"
						(effects
							(font
								(size 1.27 1.27)
							)
						)
					)
				)
				(pin passive line
					(at 0 0 0)
					(length 5.08)
					(hide yes)
					(name "VCCO_84"
						(effects
							(font
								(size 1.27 1.27)
							)
						)
					)
					(number "Y14"
						(effects
							(font
								(size 1.27 1.27)
							)
						)
					)
				)
				(pin bidirectional line
					(at 0 -5.08 0)
					(length 5.08)
					(name "IO_L1P_AD11P_84"
						(effects
							(font
								(size 1.27 1.27)
							)
						)
					)
					(number "AF14"
						(effects
							(font
								(size 1.27 1.27)
							)
						)
					)
				)
				(pin bidirectional line
					(at 0 -7.62 0)
					(length 5.08)
					(name "IO_L1N_AD11N_84"
						(effects
							(font
								(size 1.27 1.27)
							)
						)
					)
					(number "AF15"
						(effects
							(font
								(size 1.27 1.27)
							)
						)
					)
				)
				(pin bidirectional line
					(at 0 -10.16 0)
					(length 5.08)
					(name "IO_L2P_AD10P_84"
						(effects
							(font
								(size 1.27 1.27)
							)
						)
					)
					(number "AE13"
						(effects
							(font
								(size 1.27 1.27)
							)
						)
					)
				)
				(pin bidirectional line
					(at 0 -12.7 0)
					(length 5.08)
					(name "IO_L2N_AD10N_84"
						(effects
							(font
								(size 1.27 1.27)
							)
						)
					)
					(number "AF13"
						(effects
							(font
								(size 1.27 1.27)
							)
						)
					)
				)
				(pin bidirectional line
					(at 0 -15.24 0)
					(length 5.08)
					(name "IO_L3P_AD9P_84"
						(effects
							(font
								(size 1.27 1.27)
							)
						)
					)
					(number "AD15"
						(effects
							(font
								(size 1.27 1.27)
							)
						)
					)
				)
				(pin bidirectional line
					(at 0 -17.78 0)
					(length 5.08)
					(name "IO_L3N_AD9N_84"
						(effects
							(font
								(size 1.27 1.27)
							)
						)
					)
					(number "AE15"
						(effects
							(font
								(size 1.27 1.27)
							)
						)
					)
				)
				(pin bidirectional line
					(at 0 -20.32 0)
					(length 5.08)
					(name "IO_L4P_AD8P_84"
						(effects
							(font
								(size 1.27 1.27)
							)
						)
					)
					(number "AD13"
						(effects
							(font
								(size 1.27 1.27)
							)
						)
					)
				)
				(pin bidirectional line
					(at 0 -22.86 0)
					(length 5.08)
					(name "IO_L4N_AD8N_84"
						(effects
							(font
								(size 1.27 1.27)
							)
						)
					)
					(number "AD14"
						(effects
							(font
								(size 1.27 1.27)
							)
						)
					)
				)
				(pin bidirectional line
					(at 0 -25.4 0)
					(length 5.08)
					(name "IO_L5P_HDGC_AD7P_84"
						(effects
							(font
								(size 1.27 1.27)
							)
						)
					)
					(number "AC13"
						(effects
							(font
								(size 1.27 1.27)
							)
						)
					)
				)
				(pin bidirectional line
					(at 0 -27.94 0)
					(length 5.08)
					(name "IO_L5N_HDGC_AD7N_84"
						(effects
							(font
								(size 1.27 1.27)
							)
						)
					)
					(number "AC14"
						(effects
							(font
								(size 1.27 1.27)
							)
						)
					)
				)
				(pin bidirectional line
					(at 0 -30.48 0)
					(length 5.08)
					(name "IO_L6P_HDGC_AD6P_84"
						(effects
							(font
								(size 1.27 1.27)
							)
						)
					)
					(number "AB15"
						(effects
							(font
								(size 1.27 1.27)
							)
						)
					)
				)
				(pin bidirectional line
					(at 0 -33.02 0)
					(length 5.08)
					(name "IO_L6N_HDGC_AD6N_84"
						(effects
							(font
								(size 1.27 1.27)
							)
						)
					)
					(number "AB16"
						(effects
							(font
								(size 1.27 1.27)
							)
						)
					)
				)
				(pin bidirectional line
					(at 0 -35.56 0)
					(length 5.08)
					(name "IO_L7P_HDGC_AD5P_84"
						(effects
							(font
								(size 1.27 1.27)
							)
						)
					)
					(number "Y15"
						(effects
							(font
								(size 1.27 1.27)
							)
						)
					)
				)
				(pin bidirectional line
					(at 0 -38.1 0)
					(length 5.08)
					(name "IO_L7N_HDGC_AD5N_84"
						(effects
							(font
								(size 1.27 1.27)
							)
						)
					)
					(number "AA15"
						(effects
							(font
								(size 1.27 1.27)
							)
						)
					)
				)
				(pin bidirectional line
					(at 0 -40.64 0)
					(length 5.08)
					(name "IO_L8P_HDGC_AD4P_84"
						(effects
							(font
								(size 1.27 1.27)
							)
						)
					)
					(number "AA14"
						(effects
							(font
								(size 1.27 1.27)
							)
						)
					)
				)
				(pin bidirectional line
					(at 0 -43.18 0)
					(length 5.08)
					(name "IO_L8N_HDGC_AD4N_84"
						(effects
							(font
								(size 1.27 1.27)
							)
						)
					)
					(number "AB14"
						(effects
							(font
								(size 1.27 1.27)
							)
						)
					)
				)
				(pin bidirectional line
					(at 0 -45.72 0)
					(length 5.08)
					(name "IO_L9P_AD3P_84"
						(effects
							(font
								(size 1.27 1.27)
							)
						)
					)
					(number "W16"
						(effects
							(font
								(size 1.27 1.27)
							)
						)
					)
				)
				(pin bidirectional line
					(at 0 -48.26 0)
					(length 5.08)
					(name "IO_L9N_AD3N_84"
						(effects
							(font
								(size 1.27 1.27)
							)
						)
					)
					(number "Y16"
						(effects
							(font
								(size 1.27 1.27)
							)
						)
					)
				)
				(pin bidirectional line
					(at 0 -50.8 0)
					(length 5.08)
					(name "IO_L10P_AD2P_84"
						(effects
							(font
								(size 1.27 1.27)
							)
						)
					)
					(number "W14"
						(effects
							(font
								(size 1.27 1.27)
							)
						)
					)
				)
				(pin bidirectional line
					(at 0 -53.34 0)
					(length 5.08)
					(name "IO_L10N_AD2N_84"
						(effects
							(font
								(size 1.27 1.27)
							)
						)
					)
					(number "W15"
						(effects
							(font
								(size 1.27 1.27)
							)
						)
					)
				)
				(pin bidirectional line
					(at 0 -55.88 0)
					(length 5.08)
					(name "IO_L11P_AD1P_84"
						(effects
							(font
								(size 1.27 1.27)
							)
						)
					)
					(number "Y13"
						(effects
							(font
								(size 1.27 1.27)
							)
						)
					)
				)
				(pin bidirectional line
					(at 0 -58.42 0)
					(length 5.08)
					(name "IO_L11N_AD1N_84"
						(effects
							(font
								(size 1.27 1.27)
							)
						)
					)
					(number "AA13"
						(effects
							(font
								(size 1.27 1.27)
							)
						)
					)
				)
				(pin bidirectional line
					(at 0 -60.96 0)
					(length 5.08)
					(name "IO_L12P_AD0P_84"
						(effects
							(font
								(size 1.27 1.27)
							)
						)
					)
					(number "W12"
						(effects
							(font
								(size 1.27 1.27)
							)
						)
					)
				)
				(pin bidirectional line
					(at 0 -63.5 0)
					(length 5.08)
					(name "IO_L12N_AD0N_84"
						(effects
							(font
								(size 1.27 1.27)
							)
						)
					)
					(number "W13"
						(effects
							(font
								(size 1.27 1.27)
							)
						)
					)
				)
			)
			(symbol "XCAU25P-2FFVB676I_2_7_1"
				(rectangle
					(start 5.08 2.54)
					(end 33.02 -68.58)
					(stroke
						(width 0.254)
						(type default)
					)
					(fill
						(type background)
					)
				)
				(polyline
					(pts
						(xy 22.86 -3.81) (xy 30.48 -3.81) (xy 30.48 -64.77) (xy 22.86 -64.77)
					)
					(stroke
						(width 0.254)
						(type default)
					)
					(fill
						(type background)
					)
				)
				(text "BANK 86"
					(at 22.86 -2.54 0)
					(effects
						(font
							(size 1.27 1.27)
							(thickness 0.15)
						)
						(justify left bottom)
					)
				)
				(text ""
					(at 50.8 -31.75 0)
					(effects
						(font
							(size 1.27 1.27)
							(thickness 0.15)
						)
						(justify left bottom)
					)
				)
				(text ""
					(at 50.8 -31.75 0)
					(effects
						(font
							(size 1.27 1.27)
							(thickness 0.15)
						)
						(justify left bottom)
					)
				)
				(pin power_in line
					(at 0 0 0)
					(length 5.08)
					(name "VCCO_86"
						(effects
							(font
								(size 1.27 1.27)
							)
						)
					)
					(number "E9"
						(effects
							(font
								(size 1.27 1.27)
							)
						)
					)
				)
				(pin passive line
					(at 0 0 0)
					(length 5.08)
					(hide yes)
					(name "VCCO_86"
						(effects
							(font
								(size 1.27 1.27)
							)
						)
					)
					(number "H10"
						(effects
							(font
								(size 1.27 1.27)
							)
						)
					)
				)
				(pin bidirectional line
					(at 0 -5.08 0)
					(length 5.08)
					(name "IO_L1P_AD11P_86"
						(effects
							(font
								(size 1.27 1.27)
							)
						)
					)
					(number "K10"
						(effects
							(font
								(size 1.27 1.27)
							)
						)
					)
				)
				(pin bidirectional line
					(at 0 -7.62 0)
					(length 5.08)
					(name "IO_L1N_AD11N_86"
						(effects
							(font
								(size 1.27 1.27)
							)
						)
					)
					(number "K9"
						(effects
							(font
								(size 1.27 1.27)
							)
						)
					)
				)
				(pin bidirectional line
					(at 0 -10.16 0)
					(length 5.08)
					(name "IO_L2P_AD10P_86"
						(effects
							(font
								(size 1.27 1.27)
							)
						)
					)
					(number "J11"
						(effects
							(font
								(size 1.27 1.27)
							)
						)
					)
				)
				(pin bidirectional line
					(at 0 -12.7 0)
					(length 5.08)
					(name "IO_L2N_AD10N_86"
						(effects
							(font
								(size 1.27 1.27)
							)
						)
					)
					(number "J10"
						(effects
							(font
								(size 1.27 1.27)
							)
						)
					)
				)
				(pin bidirectional line
					(at 0 -15.24 0)
					(length 5.08)
					(name "IO_L3P_AD9P_86"
						(effects
							(font
								(size 1.27 1.27)
							)
						)
					)
					(number "J9"
						(effects
							(font
								(size 1.27 1.27)
							)
						)
					)
				)
				(pin bidirectional line
					(at 0 -17.78 0)
					(length 5.08)
					(name "IO_L3N_AD9N_86"
						(effects
							(font
								(size 1.27 1.27)
							)
						)
					)
					(number "H9"
						(effects
							(font
								(size 1.27 1.27)
							)
						)
					)
				)
				(pin bidirectional line
					(at 0 -20.32 0)
					(length 5.08)
					(name "IO_L4P_AD8P_86"
						(effects
							(font
								(size 1.27 1.27)
							)
						)
					)
					(number "H11"
						(effects
							(font
								(size 1.27 1.27)
							)
						)
					)
				)
				(pin bidirectional line
					(at 0 -22.86 0)
					(length 5.08)
					(name "IO_L4N_AD8N_86"
						(effects
							(font
								(size 1.27 1.27)
							)
						)
					)
					(number "G11"
						(effects
							(font
								(size 1.27 1.27)
							)
						)
					)
				)
				(pin bidirectional line
					(at 0 -25.4 0)
					(length 5.08)
					(name "IO_L5P_HDGC_AD7P_86"
						(effects
							(font
								(size 1.27 1.27)
							)
						)
					)
					(number "G10"
						(effects
							(font
								(size 1.27 1.27)
							)
						)
					)
				)
				(pin bidirectional line
					(at 0 -27.94 0)
					(length 5.08)
					(name "IO_L5N_HDGC_AD7N_86"
						(effects
							(font
								(size 1.27 1.27)
							)
						)
					)
					(number "G9"
						(effects
							(font
								(size 1.27 1.27)
							)
						)
					)
				)
				(pin bidirectional line
					(at 0 -30.48 0)
					(length 5.08)
					(name "IO_L6P_HDGC_AD6P_86"
						(effects
							(font
								(size 1.27 1.27)
							)
						)
					)
					(number "F10"
						(effects
							(font
								(size 1.27 1.27)
							)
						)
					)
				)
				(pin bidirectional line
					(at 0 -33.02 0)
					(length 5.08)
					(name "IO_L6N_HDGC_AD6N_86"
						(effects
							(font
								(size 1.27 1.27)
							)
						)
					)
					(number "F9"
						(effects
							(font
								(size 1.27 1.27)
							)
						)
					)
				)
				(pin bidirectional line
					(at 0 -35.56 0)
					(length 5.08)
					(name "IO_L7P_HDGC_AD5P_86"
						(effects
							(font
								(size 1.27 1.27)
							)
						)
					)
					(number "E11"
						(effects
							(font
								(size 1.27 1.27)
							)
						)
					)
				)
				(pin bidirectional line
					(at 0 -38.1 0)
					(length 5.08)
					(name "IO_L7N_HDGC_AD5N_86"
						(effects
							(font
								(size 1.27 1.27)
							)
						)
					)
					(number "E10"
						(effects
							(font
								(size 1.27 1.27)
							)
						)
					)
				)
				(pin bidirectional line
					(at 0 -40.64 0)
					(length 5.08)
					(name "IO_L8P_HDGC_AD4P_86"
						(effects
							(font
								(size 1.27 1.27)
							)
						)
					)
					(number "D11"
						(effects
							(font
								(size 1.27 1.27)
							)
						)
					)
				)
				(pin bidirectional line
					(at 0 -43.18 0)
					(length 5.08)
					(name "IO_L8N_HDGC_AD4N_86"
						(effects
							(font
								(size 1.27 1.27)
							)
						)
					)
					(number "D10"
						(effects
							(font
								(size 1.27 1.27)
							)
						)
					)
				)
				(pin bidirectional line
					(at 0 -45.72 0)
					(length 5.08)
					(name "IO_L9P_AD3P_86"
						(effects
							(font
								(size 1.27 1.27)
							)
						)
					)
					(number "D9"
						(effects
							(font
								(size 1.27 1.27)
							)
						)
					)
				)
				(pin bidirectional line
					(at 0 -48.26 0)
					(length 5.08)
					(name "IO_L9N_AD3N_86"
						(effects
							(font
								(size 1.27 1.27)
							)
						)
					)
					(number "C9"
						(effects
							(font
								(size 1.27 1.27)
							)
						)
					)
				)
				(pin bidirectional line
					(at 0 -50.8 0)
					(length 5.08)
					(name "IO_L10P_AD2P_86"
						(effects
							(font
								(size 1.27 1.27)
							)
						)
					)
					(number "B9"
						(effects
							(font
								(size 1.27 1.27)
							)
						)
					)
				)
				(pin bidirectional line
					(at 0 -53.34 0)
					(length 5.08)
					(name "IO_L10N_AD2N_86"
						(effects
							(font
								(size 1.27 1.27)
							)
						)
					)
					(number "A9"
						(effects
							(font
								(size 1.27 1.27)
							)
						)
					)
				)
				(pin bidirectional line
					(at 0 -55.88 0)
					(length 5.08)
					(name "IO_L11P_AD1P_86"
						(effects
							(font
								(size 1.27 1.27)
							)
						)
					)
					(number "B10"
						(effects
							(font
								(size 1.27 1.27)
							)
						)
					)
				)
				(pin bidirectional line
					(at 0 -58.42 0)
					(length 5.08)
					(name "IO_L11N_AD1N_86"
						(effects
							(font
								(size 1.27 1.27)
							)
						)
					)
					(number "A10"
						(effects
							(font
								(size 1.27 1.27)
							)
						)
					)
				)
				(pin bidirectional line
					(at 0 -60.96 0)
					(length 5.08)
					(name "IO_L12P_AD0P_86"
						(effects
							(font
								(size 1.27 1.27)
							)
						)
					)
					(number "C11"
						(effects
							(font
								(size 1.27 1.27)
							)
						)
					)
				)
				(pin bidirectional line
					(at 0 -63.5 0)
					(length 5.08)
					(name "IO_L12N_AD0N_86"
						(effects
							(font
								(size 1.27 1.27)
							)
						)
					)
					(number "B11"
						(effects
							(font
								(size 1.27 1.27)
							)
						)
					)
				)
			)
			(symbol "XCAU25P-2FFVB676I_2_8_1"
				(rectangle
					(start 5.08 2.54)
					(end 33.02 -67.31)
					(stroke
						(width 0.254)
						(type default)
					)
					(fill
						(type background)
					)
				)
				(polyline
					(pts
						(xy 22.86 -3.81) (xy 30.48 -3.81) (xy 30.48 -64.77) (xy 22.86 -64.77)
					)
					(stroke
						(width 0.254)
						(type default)
					)
					(fill
						(type background)
					)
				)
				(text "BANK 87"
					(at 22.86 -2.54 0)
					(effects
						(font
							(size 1.27 1.27)
							(thickness 0.15)
						)
						(justify left bottom)
					)
				)
				(text ""
					(at 50.8 -31.75 0)
					(effects
						(font
							(size 1.27 1.27)
							(thickness 0.15)
						)
						(justify left bottom)
					)
				)
				(text ""
					(at 50.8 -31.75 0)
					(effects
						(font
							(size 1.27 1.27)
							(thickness 0.15)
						)
						(justify left bottom)
					)
				)
				(pin power_in line
					(at 0 0 0)
					(length 5.08)
					(name "VCCO_87"
						(effects
							(font
								(size 1.27 1.27)
							)
						)
					)
					(number "E14"
						(effects
							(font
								(size 1.27 1.27)
							)
						)
					)
				)
				(pin passive line
					(at 0 0 0)
					(length 5.08)
					(hide yes)
					(name "VCCO_87"
						(effects
							(font
								(size 1.27 1.27)
							)
						)
					)
					(number "H15"
						(effects
							(font
								(size 1.27 1.27)
							)
						)
					)
				)
				(pin bidirectional line
					(at 0 -5.08 0)
					(length 5.08)
					(name "IO_L1P_AD15P_87"
						(effects
							(font
								(size 1.27 1.27)
							)
						)
					)
					(number "J12"
						(effects
							(font
								(size 1.27 1.27)
							)
						)
					)
				)
				(pin bidirectional line
					(at 0 -7.62 0)
					(length 5.08)
					(name "IO_L1N_AD15N_87"
						(effects
							(font
								(size 1.27 1.27)
							)
						)
					)
					(number "H12"
						(effects
							(font
								(size 1.27 1.27)
							)
						)
					)
				)
				(pin bidirectional line
					(at 0 -10.16 0)
					(length 5.08)
					(name "IO_L2P_AD14P_87"
						(effects
							(font
								(size 1.27 1.27)
							)
						)
					)
					(number "J13"
						(effects
							(font
								(size 1.27 1.27)
							)
						)
					)
				)
				(pin bidirectional line
					(at 0 -12.7 0)
					(length 5.08)
					(name "IO_L2N_AD14N_87"
						(effects
							(font
								(size 1.27 1.27)
							)
						)
					)
					(number "H13"
						(effects
							(font
								(size 1.27 1.27)
							)
						)
					)
				)
				(pin bidirectional line
					(at 0 -15.24 0)
					(length 5.08)
					(name "IO_L3P_AD13P_87"
						(effects
							(font
								(size 1.27 1.27)
							)
						)
					)
					(number "H14"
						(effects
							(font
								(size 1.27 1.27)
							)
						)
					)
				)
				(pin bidirectional line
					(at 0 -17.78 0)
					(length 5.08)
					(name "IO_L3N_AD13N_87"
						(effects
							(font
								(size 1.27 1.27)
							)
						)
					)
					(number "G14"
						(effects
							(font
								(size 1.27 1.27)
							)
						)
					)
				)
				(pin bidirectional line
					(at 0 -20.32 0)
					(length 5.08)
					(name "IO_L4P_AD12P_87"
						(effects
							(font
								(size 1.27 1.27)
							)
						)
					)
					(number "J15"
						(effects
							(font
								(size 1.27 1.27)
							)
						)
					)
				)
				(pin bidirectional line
					(at 0 -22.86 0)
					(length 5.08)
					(name "IO_L4N_AD12N_87"
						(effects
							(font
								(size 1.27 1.27)
							)
						)
					)
					(number "J14"
						(effects
							(font
								(size 1.27 1.27)
							)
						)
					)
				)
				(pin bidirectional line
					(at 0 -25.4 0)
					(length 5.08)
					(name "IO_L5P_HDGC_87"
						(effects
							(font
								(size 1.27 1.27)
							)
						)
					)
					(number "G12"
						(effects
							(font
								(size 1.27 1.27)
							)
						)
					)
				)
				(pin bidirectional line
					(at 0 -27.94 0)
					(length 5.08)
					(name "IO_L5N_HDGC_87"
						(effects
							(font
								(size 1.27 1.27)
							)
						)
					)
					(number "F12"
						(effects
							(font
								(size 1.27 1.27)
							)
						)
					)
				)
				(pin bidirectional line
					(at 0 -30.48 0)
					(length 5.08)
					(name "IO_L6P_HDGC_87"
						(effects
							(font
								(size 1.27 1.27)
							)
						)
					)
					(number "F14"
						(effects
							(font
								(size 1.27 1.27)
							)
						)
					)
				)
				(pin bidirectional line
					(at 0 -33.02 0)
					(length 5.08)
					(name "IO_L6N_HDGC_87"
						(effects
							(font
								(size 1.27 1.27)
							)
						)
					)
					(number "F13"
						(effects
							(font
								(size 1.27 1.27)
							)
						)
					)
				)
				(pin bidirectional line
					(at 0 -35.56 0)
					(length 5.08)
					(name "IO_L7P_HDGC_87"
						(effects
							(font
								(size 1.27 1.27)
							)
						)
					)
					(number "E13"
						(effects
							(font
								(size 1.27 1.27)
							)
						)
					)
				)
				(pin bidirectional line
					(at 0 -38.1 0)
					(length 5.08)
					(name "IO_L7N_HDGC_87"
						(effects
							(font
								(size 1.27 1.27)
							)
						)
					)
					(number "E12"
						(effects
							(font
								(size 1.27 1.27)
							)
						)
					)
				)
				(pin bidirectional line
					(at 0 -40.64 0)
					(length 5.08)
					(name "IO_L8P_HDGC_87"
						(effects
							(font
								(size 1.27 1.27)
							)
						)
					)
					(number "D14"
						(effects
							(font
								(size 1.27 1.27)
							)
						)
					)
				)
				(pin bidirectional line
					(at 0 -43.18 0)
					(length 5.08)
					(name "IO_L8N_HDGC_87"
						(effects
							(font
								(size 1.27 1.27)
							)
						)
					)
					(number "D13"
						(effects
							(font
								(size 1.27 1.27)
							)
						)
					)
				)
				(pin bidirectional line
					(at 0 -45.72 0)
					(length 5.08)
					(name "IO_L9P_AD11P_87"
						(effects
							(font
								(size 1.27 1.27)
							)
						)
					)
					(number "C14"
						(effects
							(font
								(size 1.27 1.27)
							)
						)
					)
				)
				(pin bidirectional line
					(at 0 -48.26 0)
					(length 5.08)
					(name "IO_L9N_AD11N_87"
						(effects
							(font
								(size 1.27 1.27)
							)
						)
					)
					(number "C13"
						(effects
							(font
								(size 1.27 1.27)
							)
						)
					)
				)
				(pin bidirectional line
					(at 0 -50.8 0)
					(length 5.08)
					(name "IO_L10P_AD10P_87"
						(effects
							(font
								(size 1.27 1.27)
							)
						)
					)
					(number "C12"
						(effects
							(font
								(size 1.27 1.27)
							)
						)
					)
				)
				(pin bidirectional line
					(at 0 -53.34 0)
					(length 5.08)
					(name "IO_L10N_AD10N_87"
						(effects
							(font
								(size 1.27 1.27)
							)
						)
					)
					(number "B12"
						(effects
							(font
								(size 1.27 1.27)
							)
						)
					)
				)
				(pin bidirectional line
					(at 0 -55.88 0)
					(length 5.08)
					(name "IO_L11P_AD9P_87"
						(effects
							(font
								(size 1.27 1.27)
							)
						)
					)
					(number "A13"
						(effects
							(font
								(size 1.27 1.27)
							)
						)
					)
				)
				(pin bidirectional line
					(at 0 -58.42 0)
					(length 5.08)
					(name "IO_L11N_AD9N_87"
						(effects
							(font
								(size 1.27 1.27)
							)
						)
					)
					(number "A12"
						(effects
							(font
								(size 1.27 1.27)
							)
						)
					)
				)
				(pin bidirectional line
					(at 0 -60.96 0)
					(length 5.08)
					(name "IO_L12P_AD8P_87"
						(effects
							(font
								(size 1.27 1.27)
							)
						)
					)
					(number "B14"
						(effects
							(font
								(size 1.27 1.27)
							)
						)
					)
				)
				(pin bidirectional line
					(at 0 -63.5 0)
					(length 5.08)
					(name "IO_L12N_AD8N_87"
						(effects
							(font
								(size 1.27 1.27)
							)
						)
					)
					(number "A14"
						(effects
							(font
								(size 1.27 1.27)
							)
						)
					)
				)
			)
			(symbol "XCAU25P-2FFVB676I_2_9_1"
				(rectangle
					(start 5.08 6.35)
					(end 27.94 -58.42)
					(stroke
						(width 0.254)
						(type default)
					)
					(fill
						(type background)
					)
				)
				(polyline
					(pts
						(xy 16.51 2.54) (xy 25.4 2.54) (xy 25.4 -55.88) (xy 16.51 -55.88)
					)
					(stroke
						(width 0.254)
						(type default)
					)
					(fill
						(type background)
					)
				)
				(text "GTX 224"
					(at 6.35 2.54 0)
					(effects
						(font
							(size 1.27 1.27)
							(thickness 0.15)
						)
						(justify left bottom)
					)
				)
				(text ""
					(at 50.8 -31.75 0)
					(effects
						(font
							(size 1.27 1.27)
							(thickness 0.15)
						)
						(justify left bottom)
					)
				)
				(text ""
					(at 50.8 -31.75 0)
					(effects
						(font
							(size 1.27 1.27)
							(thickness 0.15)
						)
						(justify left bottom)
					)
				)
				(pin output line
					(at 0 0 0)
					(length 5.08)
					(name "MGTYTXP0_224"
						(effects
							(font
								(size 1.27 1.27)
							)
						)
					)
					(number "AF7"
						(effects
							(font
								(size 1.27 1.27)
							)
						)
					)
				)
				(pin output line
					(at 0 -2.54 0)
					(length 5.08)
					(name "MGTYTXN0_224"
						(effects
							(font
								(size 1.27 1.27)
							)
						)
					)
					(number "AF6"
						(effects
							(font
								(size 1.27 1.27)
							)
						)
					)
				)
				(pin output line
					(at 0 -5.08 0)
					(length 5.08)
					(name "MGTYTXP1_224"
						(effects
							(font
								(size 1.27 1.27)
							)
						)
					)
					(number "AE9"
						(effects
							(font
								(size 1.27 1.27)
							)
						)
					)
				)
				(pin output line
					(at 0 -7.62 0)
					(length 5.08)
					(name "MGTYTXN1_224"
						(effects
							(font
								(size 1.27 1.27)
							)
						)
					)
					(number "AE8"
						(effects
							(font
								(size 1.27 1.27)
							)
						)
					)
				)
				(pin output line
					(at 0 -10.16 0)
					(length 5.08)
					(name "MGTYTXP2_224"
						(effects
							(font
								(size 1.27 1.27)
							)
						)
					)
					(number "AD7"
						(effects
							(font
								(size 1.27 1.27)
							)
						)
					)
				)
				(pin output line
					(at 0 -12.7 0)
					(length 5.08)
					(name "MGTYTXN2_224"
						(effects
							(font
								(size 1.27 1.27)
							)
						)
					)
					(number "AD6"
						(effects
							(font
								(size 1.27 1.27)
							)
						)
					)
				)
				(pin output line
					(at 0 -15.24 0)
					(length 5.08)
					(name "MGTYTXP3_224"
						(effects
							(font
								(size 1.27 1.27)
							)
						)
					)
					(number "AC5"
						(effects
							(font
								(size 1.27 1.27)
							)
						)
					)
				)
				(pin output line
					(at 0 -17.78 0)
					(length 5.08)
					(name "MGTYTXN3_224"
						(effects
							(font
								(size 1.27 1.27)
							)
						)
					)
					(number "AC4"
						(effects
							(font
								(size 1.27 1.27)
							)
						)
					)
				)
				(pin input line
					(at 0 -22.86 0)
					(length 5.08)
					(name "MGTYRXP0_224"
						(effects
							(font
								(size 1.27 1.27)
							)
						)
					)
					(number "AF2"
						(effects
							(font
								(size 1.27 1.27)
							)
						)
					)
				)
				(pin input line
					(at 0 -25.4 0)
					(length 5.08)
					(name "MGTYRXN0_224"
						(effects
							(font
								(size 1.27 1.27)
							)
						)
					)
					(number "AF1"
						(effects
							(font
								(size 1.27 1.27)
							)
						)
					)
				)
				(pin input line
					(at 0 -27.94 0)
					(length 5.08)
					(name "MGTYRXP1_224"
						(effects
							(font
								(size 1.27 1.27)
							)
						)
					)
					(number "AE4"
						(effects
							(font
								(size 1.27 1.27)
							)
						)
					)
				)
				(pin input line
					(at 0 -30.48 0)
					(length 5.08)
					(name "MGTYRXN1_224"
						(effects
							(font
								(size 1.27 1.27)
							)
						)
					)
					(number "AE3"
						(effects
							(font
								(size 1.27 1.27)
							)
						)
					)
				)
				(pin input line
					(at 0 -33.02 0)
					(length 5.08)
					(name "MGTYRXP2_224"
						(effects
							(font
								(size 1.27 1.27)
							)
						)
					)
					(number "AD2"
						(effects
							(font
								(size 1.27 1.27)
							)
						)
					)
				)
				(pin input line
					(at 0 -35.56 0)
					(length 5.08)
					(name "MGTYRXN2_224"
						(effects
							(font
								(size 1.27 1.27)
							)
						)
					)
					(number "AD1"
						(effects
							(font
								(size 1.27 1.27)
							)
						)
					)
				)
				(pin input line
					(at 0 -38.1 0)
					(length 5.08)
					(name "MGTYRXP3_224"
						(effects
							(font
								(size 1.27 1.27)
							)
						)
					)
					(number "AB2"
						(effects
							(font
								(size 1.27 1.27)
							)
						)
					)
				)
				(pin input line
					(at 0 -40.64 0)
					(length 5.08)
					(name "MGTYRXN3_224"
						(effects
							(font
								(size 1.27 1.27)
							)
						)
					)
					(number "AB1"
						(effects
							(font
								(size 1.27 1.27)
							)
						)
					)
				)
				(pin input line
					(at 0 -45.72 0)
					(length 5.08)
					(name "MGTREFCLK0P_224"
						(effects
							(font
								(size 1.27 1.27)
							)
						)
					)
					(number "AB7"
						(effects
							(font
								(size 1.27 1.27)
							)
						)
					)
				)
				(pin input line
					(at 0 -48.26 0)
					(length 5.08)
					(name "MGTREFCLK0N_224"
						(effects
							(font
								(size 1.27 1.27)
							)
						)
					)
					(number "AB6"
						(effects
							(font
								(size 1.27 1.27)
							)
						)
					)
				)
				(pin input line
					(at 0 -50.8 0)
					(length 5.08)
					(name "MGTREFCLK1P_224"
						(effects
							(font
								(size 1.27 1.27)
							)
						)
					)
					(number "Y7"
						(effects
							(font
								(size 1.27 1.27)
							)
						)
					)
				)
				(pin input line
					(at 0 -53.34 0)
					(length 5.08)
					(name "MGTREFCLK1N_224"
						(effects
							(font
								(size 1.27 1.27)
							)
						)
					)
					(number "Y6"
						(effects
							(font
								(size 1.27 1.27)
							)
						)
					)
				)
			)
			(symbol "XCAU25P-2FFVB676I_2_10_1"
				(rectangle
					(start 5.08 6.35)
					(end 27.94 -58.42)
					(stroke
						(width 0.254)
						(type default)
					)
					(fill
						(type background)
					)
				)
				(polyline
					(pts
						(xy 16.51 2.54) (xy 25.4 2.54) (xy 25.4 -55.88) (xy 16.51 -55.88)
					)
					(stroke
						(width 0.254)
						(type default)
					)
					(fill
						(type background)
					)
				)
				(text "GTX 225"
					(at 6.35 2.54 0)
					(effects
						(font
							(size 1.27 1.27)
							(thickness 0.15)
						)
						(justify left bottom)
					)
				)
				(text ""
					(at 50.8 -31.75 0)
					(effects
						(font
							(size 1.27 1.27)
							(thickness 0.15)
						)
						(justify left bottom)
					)
				)
				(text ""
					(at 50.8 -31.75 0)
					(effects
						(font
							(size 1.27 1.27)
							(thickness 0.15)
						)
						(justify left bottom)
					)
				)
				(pin output line
					(at 0 0 0)
					(length 5.08)
					(name "MGTYTXP0_225"
						(effects
							(font
								(size 1.27 1.27)
							)
						)
					)
					(number "AA5"
						(effects
							(font
								(size 1.27 1.27)
							)
						)
					)
				)
				(pin output line
					(at 0 -2.54 0)
					(length 5.08)
					(name "MGTYTXN0_225"
						(effects
							(font
								(size 1.27 1.27)
							)
						)
					)
					(number "AA4"
						(effects
							(font
								(size 1.27 1.27)
							)
						)
					)
				)
				(pin output line
					(at 0 -5.08 0)
					(length 5.08)
					(name "MGTYTXP1_225"
						(effects
							(font
								(size 1.27 1.27)
							)
						)
					)
					(number "W5"
						(effects
							(font
								(size 1.27 1.27)
							)
						)
					)
				)
				(pin output line
					(at 0 -7.62 0)
					(length 5.08)
					(name "MGTYTXN1_225"
						(effects
							(font
								(size 1.27 1.27)
							)
						)
					)
					(number "W4"
						(effects
							(font
								(size 1.27 1.27)
							)
						)
					)
				)
				(pin output line
					(at 0 -10.16 0)
					(length 5.08)
					(name "MGTYTXP2_225"
						(effects
							(font
								(size 1.27 1.27)
							)
						)
					)
					(number "U5"
						(effects
							(font
								(size 1.27 1.27)
							)
						)
					)
				)
				(pin output line
					(at 0 -12.7 0)
					(length 5.08)
					(name "MGTYTXN2_225"
						(effects
							(font
								(size 1.27 1.27)
							)
						)
					)
					(number "U4"
						(effects
							(font
								(size 1.27 1.27)
							)
						)
					)
				)
				(pin output line
					(at 0 -15.24 0)
					(length 5.08)
					(name "MGTYTXP3_225"
						(effects
							(font
								(size 1.27 1.27)
							)
						)
					)
					(number "R5"
						(effects
							(font
								(size 1.27 1.27)
							)
						)
					)
				)
				(pin output line
					(at 0 -17.78 0)
					(length 5.08)
					(name "MGTYTXN3_225"
						(effects
							(font
								(size 1.27 1.27)
							)
						)
					)
					(number "R4"
						(effects
							(font
								(size 1.27 1.27)
							)
						)
					)
				)
				(pin input line
					(at 0 -22.86 0)
					(length 5.08)
					(name "MGTYRXP0_225"
						(effects
							(font
								(size 1.27 1.27)
							)
						)
					)
					(number "Y2"
						(effects
							(font
								(size 1.27 1.27)
							)
						)
					)
				)
				(pin input line
					(at 0 -25.4 0)
					(length 5.08)
					(name "MGTYRXN0_225"
						(effects
							(font
								(size 1.27 1.27)
							)
						)
					)
					(number "Y1"
						(effects
							(font
								(size 1.27 1.27)
							)
						)
					)
				)
				(pin input line
					(at 0 -27.94 0)
					(length 5.08)
					(name "MGTYRXP1_225"
						(effects
							(font
								(size 1.27 1.27)
							)
						)
					)
					(number "V2"
						(effects
							(font
								(size 1.27 1.27)
							)
						)
					)
				)
				(pin input line
					(at 0 -30.48 0)
					(length 5.08)
					(name "MGTYRXN1_225"
						(effects
							(font
								(size 1.27 1.27)
							)
						)
					)
					(number "V1"
						(effects
							(font
								(size 1.27 1.27)
							)
						)
					)
				)
				(pin input line
					(at 0 -33.02 0)
					(length 5.08)
					(name "MGTYRXP2_225"
						(effects
							(font
								(size 1.27 1.27)
							)
						)
					)
					(number "T2"
						(effects
							(font
								(size 1.27 1.27)
							)
						)
					)
				)
				(pin input line
					(at 0 -35.56 0)
					(length 5.08)
					(name "MGTYRXN2_225"
						(effects
							(font
								(size 1.27 1.27)
							)
						)
					)
					(number "T1"
						(effects
							(font
								(size 1.27 1.27)
							)
						)
					)
				)
				(pin input line
					(at 0 -38.1 0)
					(length 5.08)
					(name "MGTYRXP3_225"
						(effects
							(font
								(size 1.27 1.27)
							)
						)
					)
					(number "P2"
						(effects
							(font
								(size 1.27 1.27)
							)
						)
					)
				)
				(pin input line
					(at 0 -40.64 0)
					(length 5.08)
					(name "MGTYRXN3_225"
						(effects
							(font
								(size 1.27 1.27)
							)
						)
					)
					(number "P1"
						(effects
							(font
								(size 1.27 1.27)
							)
						)
					)
				)
				(pin input line
					(at 0 -45.72 0)
					(length 5.08)
					(name "MGTREFCLK0P_225"
						(effects
							(font
								(size 1.27 1.27)
							)
						)
					)
					(number "V7"
						(effects
							(font
								(size 1.27 1.27)
							)
						)
					)
				)
				(pin input line
					(at 0 -48.26 0)
					(length 5.08)
					(name "MGTREFCLK0N_225"
						(effects
							(font
								(size 1.27 1.27)
							)
						)
					)
					(number "V6"
						(effects
							(font
								(size 1.27 1.27)
							)
						)
					)
				)
				(pin input line
					(at 0 -50.8 0)
					(length 5.08)
					(name "MGTREFCLK1P_225"
						(effects
							(font
								(size 1.27 1.27)
							)
						)
					)
					(number "T7"
						(effects
							(font
								(size 1.27 1.27)
							)
						)
					)
				)
				(pin input line
					(at 0 -53.34 0)
					(length 5.08)
					(name "MGTREFCLK1N_225"
						(effects
							(font
								(size 1.27 1.27)
							)
						)
					)
					(number "T6"
						(effects
							(font
								(size 1.27 1.27)
							)
						)
					)
				)
			)
			(symbol "XCAU25P-2FFVB676I_2_11_1"
				(rectangle
					(start 5.08 6.35)
					(end 27.94 -58.42)
					(stroke
						(width 0.254)
						(type default)
					)
					(fill
						(type background)
					)
				)
				(polyline
					(pts
						(xy 16.51 2.54) (xy 25.4 2.54) (xy 25.4 -55.88) (xy 16.51 -55.88)
					)
					(stroke
						(width 0.254)
						(type default)
					)
					(fill
						(type background)
					)
				)
				(text "GTX 226"
					(at 6.35 2.54 0)
					(effects
						(font
							(size 1.27 1.27)
							(thickness 0.15)
						)
						(justify left bottom)
					)
				)
				(text ""
					(at 50.8 -31.75 0)
					(effects
						(font
							(size 1.27 1.27)
							(thickness 0.15)
						)
						(justify left bottom)
					)
				)
				(text ""
					(at 50.8 -31.75 0)
					(effects
						(font
							(size 1.27 1.27)
							(thickness 0.15)
						)
						(justify left bottom)
					)
				)
				(pin output line
					(at 0 0 0)
					(length 5.08)
					(name "MGTYTXP0_226"
						(effects
							(font
								(size 1.27 1.27)
							)
						)
					)
					(number "N5"
						(effects
							(font
								(size 1.27 1.27)
							)
						)
					)
				)
				(pin output line
					(at 0 -2.54 0)
					(length 5.08)
					(name "MGTYTXN0_226"
						(effects
							(font
								(size 1.27 1.27)
							)
						)
					)
					(number "N4"
						(effects
							(font
								(size 1.27 1.27)
							)
						)
					)
				)
				(pin output line
					(at 0 -5.08 0)
					(length 5.08)
					(name "MGTYTXP1_226"
						(effects
							(font
								(size 1.27 1.27)
							)
						)
					)
					(number "L5"
						(effects
							(font
								(size 1.27 1.27)
							)
						)
					)
				)
				(pin output line
					(at 0 -7.62 0)
					(length 5.08)
					(name "MGTYTXN1_226"
						(effects
							(font
								(size 1.27 1.27)
							)
						)
					)
					(number "L4"
						(effects
							(font
								(size 1.27 1.27)
							)
						)
					)
				)
				(pin output line
					(at 0 -10.16 0)
					(length 5.08)
					(name "MGTYTXP2_226"
						(effects
							(font
								(size 1.27 1.27)
							)
						)
					)
					(number "J5"
						(effects
							(font
								(size 1.27 1.27)
							)
						)
					)
				)
				(pin output line
					(at 0 -12.7 0)
					(length 5.08)
					(name "MGTYTXN2_226"
						(effects
							(font
								(size 1.27 1.27)
							)
						)
					)
					(number "J4"
						(effects
							(font
								(size 1.27 1.27)
							)
						)
					)
				)
				(pin output line
					(at 0 -15.24 0)
					(length 5.08)
					(name "MGTYTXP3_226"
						(effects
							(font
								(size 1.27 1.27)
							)
						)
					)
					(number "G5"
						(effects
							(font
								(size 1.27 1.27)
							)
						)
					)
				)
				(pin output line
					(at 0 -17.78 0)
					(length 5.08)
					(name "MGTYTXN3_226"
						(effects
							(font
								(size 1.27 1.27)
							)
						)
					)
					(number "G4"
						(effects
							(font
								(size 1.27 1.27)
							)
						)
					)
				)
				(pin input line
					(at 0 -22.86 0)
					(length 5.08)
					(name "MGTYRXP0_226"
						(effects
							(font
								(size 1.27 1.27)
							)
						)
					)
					(number "M2"
						(effects
							(font
								(size 1.27 1.27)
							)
						)
					)
				)
				(pin input line
					(at 0 -25.4 0)
					(length 5.08)
					(name "MGTYRXN0_226"
						(effects
							(font
								(size 1.27 1.27)
							)
						)
					)
					(number "M1"
						(effects
							(font
								(size 1.27 1.27)
							)
						)
					)
				)
				(pin input line
					(at 0 -27.94 0)
					(length 5.08)
					(name "MGTYRXP1_226"
						(effects
							(font
								(size 1.27 1.27)
							)
						)
					)
					(number "K2"
						(effects
							(font
								(size 1.27 1.27)
							)
						)
					)
				)
				(pin input line
					(at 0 -30.48 0)
					(length 5.08)
					(name "MGTYRXN1_226"
						(effects
							(font
								(size 1.27 1.27)
							)
						)
					)
					(number "K1"
						(effects
							(font
								(size 1.27 1.27)
							)
						)
					)
				)
				(pin input line
					(at 0 -33.02 0)
					(length 5.08)
					(name "MGTYRXP2_226"
						(effects
							(font
								(size 1.27 1.27)
							)
						)
					)
					(number "H2"
						(effects
							(font
								(size 1.27 1.27)
							)
						)
					)
				)
				(pin input line
					(at 0 -35.56 0)
					(length 5.08)
					(name "MGTYRXN2_226"
						(effects
							(font
								(size 1.27 1.27)
							)
						)
					)
					(number "H1"
						(effects
							(font
								(size 1.27 1.27)
							)
						)
					)
				)
				(pin input line
					(at 0 -38.1 0)
					(length 5.08)
					(name "MGTYRXP3_226"
						(effects
							(font
								(size 1.27 1.27)
							)
						)
					)
					(number "F2"
						(effects
							(font
								(size 1.27 1.27)
							)
						)
					)
				)
				(pin input line
					(at 0 -40.64 0)
					(length 5.08)
					(name "MGTYRXN3_226"
						(effects
							(font
								(size 1.27 1.27)
							)
						)
					)
					(number "F1"
						(effects
							(font
								(size 1.27 1.27)
							)
						)
					)
				)
				(pin input line
					(at 0 -45.72 0)
					(length 5.08)
					(name "MGTREFCLK0P_226"
						(effects
							(font
								(size 1.27 1.27)
							)
						)
					)
					(number "P7"
						(effects
							(font
								(size 1.27 1.27)
							)
						)
					)
				)
				(pin input line
					(at 0 -48.26 0)
					(length 5.08)
					(name "MGTREFCLK0N_226"
						(effects
							(font
								(size 1.27 1.27)
							)
						)
					)
					(number "P6"
						(effects
							(font
								(size 1.27 1.27)
							)
						)
					)
				)
				(pin input line
					(at 0 -50.8 0)
					(length 5.08)
					(name "MGTREFCLK1P_226"
						(effects
							(font
								(size 1.27 1.27)
							)
						)
					)
					(number "M7"
						(effects
							(font
								(size 1.27 1.27)
							)
						)
					)
				)
				(pin input line
					(at 0 -53.34 0)
					(length 5.08)
					(name "MGTREFCLK1N_226"
						(effects
							(font
								(size 1.27 1.27)
							)
						)
					)
					(number "M6"
						(effects
							(font
								(size 1.27 1.27)
							)
						)
					)
				)
			)
			(symbol "XCAU25P-2FFVB676I_2_12_1"
				(rectangle
					(start 5.08 2.54)
					(end 35.56 -27.94)
					(stroke
						(width 0.254)
						(type default)
					)
					(fill
						(type background)
					)
				)
				(text ""
					(at 21.59 -3.175 900)
					(effects
						(font
							(size 1.27 1.27)
							(thickness 0.15)
						)
						(justify right top)
					)
				)
				(text ""
					(at 21.59 -3.175 900)
					(effects
						(font
							(size 1.27 1.27)
							(thickness 0.15)
						)
						(justify right top)
					)
				)
				(pin input line
					(at 0 0 0)
					(length 5.08)
					(name "MGTAVTT_R"
						(effects
							(font
								(size 1.27 1.27)
							)
						)
					)
					(number "A7"
						(effects
							(font
								(size 1.27 1.27)
							)
						)
					)
				)
				(pin passive line
					(at 0 0 0)
					(length 5.08)
					(hide yes)
					(name "MGTAVTT_R"
						(effects
							(font
								(size 1.27 1.27)
							)
						)
					)
					(number "AB5"
						(effects
							(font
								(size 1.27 1.27)
							)
						)
					)
				)
				(pin passive line
					(at 0 0 0)
					(length 5.08)
					(hide yes)
					(name "MGTAVTT_R"
						(effects
							(font
								(size 1.27 1.27)
							)
						)
					)
					(number "AE7"
						(effects
							(font
								(size 1.27 1.27)
							)
						)
					)
				)
				(pin passive line
					(at 0 0 0)
					(length 5.08)
					(hide yes)
					(name "MGTAVTT_R"
						(effects
							(font
								(size 1.27 1.27)
							)
						)
					)
					(number "C7"
						(effects
							(font
								(size 1.27 1.27)
							)
						)
					)
				)
				(pin passive line
					(at 0 0 0)
					(length 5.08)
					(hide yes)
					(name "MGTAVTT_R"
						(effects
							(font
								(size 1.27 1.27)
							)
						)
					)
					(number "E7"
						(effects
							(font
								(size 1.27 1.27)
							)
						)
					)
				)
				(pin passive line
					(at 0 0 0)
					(length 5.08)
					(hide yes)
					(name "MGTAVTT_R"
						(effects
							(font
								(size 1.27 1.27)
							)
						)
					)
					(number "F5"
						(effects
							(font
								(size 1.27 1.27)
							)
						)
					)
				)
				(pin passive line
					(at 0 0 0)
					(length 5.08)
					(hide yes)
					(name "MGTAVTT_R"
						(effects
							(font
								(size 1.27 1.27)
							)
						)
					)
					(number "G7"
						(effects
							(font
								(size 1.27 1.27)
							)
						)
					)
				)
				(pin passive line
					(at 0 0 0)
					(length 5.08)
					(hide yes)
					(name "MGTAVTT_R"
						(effects
							(font
								(size 1.27 1.27)
							)
						)
					)
					(number "H5"
						(effects
							(font
								(size 1.27 1.27)
							)
						)
					)
				)
				(pin passive line
					(at 0 0 0)
					(length 5.08)
					(hide yes)
					(name "MGTAVTT_R"
						(effects
							(font
								(size 1.27 1.27)
							)
						)
					)
					(number "K5"
						(effects
							(font
								(size 1.27 1.27)
							)
						)
					)
				)
				(pin passive line
					(at 0 0 0)
					(length 5.08)
					(hide yes)
					(name "MGTAVTT_R"
						(effects
							(font
								(size 1.27 1.27)
							)
						)
					)
					(number "M5"
						(effects
							(font
								(size 1.27 1.27)
							)
						)
					)
				)
				(pin passive line
					(at 0 0 0)
					(length 5.08)
					(hide yes)
					(name "MGTAVTT_R"
						(effects
							(font
								(size 1.27 1.27)
							)
						)
					)
					(number "P5"
						(effects
							(font
								(size 1.27 1.27)
							)
						)
					)
				)
				(pin passive line
					(at 0 0 0)
					(length 5.08)
					(hide yes)
					(name "MGTAVTT_R"
						(effects
							(font
								(size 1.27 1.27)
							)
						)
					)
					(number "T5"
						(effects
							(font
								(size 1.27 1.27)
							)
						)
					)
				)
				(pin passive line
					(at 0 0 0)
					(length 5.08)
					(hide yes)
					(name "MGTAVTT_R"
						(effects
							(font
								(size 1.27 1.27)
							)
						)
					)
					(number "V5"
						(effects
							(font
								(size 1.27 1.27)
							)
						)
					)
				)
				(pin passive line
					(at 0 0 0)
					(length 5.08)
					(hide yes)
					(name "MGTAVTT_R"
						(effects
							(font
								(size 1.27 1.27)
							)
						)
					)
					(number "Y5"
						(effects
							(font
								(size 1.27 1.27)
							)
						)
					)
				)
				(pin power_in line
					(at 0 -2.54 0)
					(length 5.08)
					(name "MGTAVCC_R"
						(effects
							(font
								(size 1.27 1.27)
							)
						)
					)
					(number "AA7"
						(effects
							(font
								(size 1.27 1.27)
							)
						)
					)
				)
				(pin passive line
					(at 0 -2.54 0)
					(length 5.08)
					(hide yes)
					(name "MGTAVCC_R"
						(effects
							(font
								(size 1.27 1.27)
							)
						)
					)
					(number "AC7"
						(effects
							(font
								(size 1.27 1.27)
							)
						)
					)
				)
				(pin passive line
					(at 0 -2.54 0)
					(length 5.08)
					(hide yes)
					(name "MGTAVCC_R"
						(effects
							(font
								(size 1.27 1.27)
							)
						)
					)
					(number "J7"
						(effects
							(font
								(size 1.27 1.27)
							)
						)
					)
				)
				(pin passive line
					(at 0 -2.54 0)
					(length 5.08)
					(hide yes)
					(name "MGTAVCC_R"
						(effects
							(font
								(size 1.27 1.27)
							)
						)
					)
					(number "L7"
						(effects
							(font
								(size 1.27 1.27)
							)
						)
					)
				)
				(pin passive line
					(at 0 -2.54 0)
					(length 5.08)
					(hide yes)
					(name "MGTAVCC_R"
						(effects
							(font
								(size 1.27 1.27)
							)
						)
					)
					(number "N7"
						(effects
							(font
								(size 1.27 1.27)
							)
						)
					)
				)
				(pin passive line
					(at 0 -2.54 0)
					(length 5.08)
					(hide yes)
					(name "MGTAVCC_R"
						(effects
							(font
								(size 1.27 1.27)
							)
						)
					)
					(number "W7"
						(effects
							(font
								(size 1.27 1.27)
							)
						)
					)
				)
				(pin input line
					(at 0 -5.08 0)
					(length 5.08)
					(name "MGTRREF_R"
						(effects
							(font
								(size 1.27 1.27)
							)
						)
					)
					(number "AD9"
						(effects
							(font
								(size 1.27 1.27)
							)
						)
					)
				)
				(pin power_in line
					(at 0 -7.62 0)
					(length 5.08)
					(name "MGTVCCAUX_R"
						(effects
							(font
								(size 1.27 1.27)
							)
						)
					)
					(number "R7"
						(effects
							(font
								(size 1.27 1.27)
							)
						)
					)
				)
				(pin passive line
					(at 0 -7.62 0)
					(length 5.08)
					(hide yes)
					(name "MGTVCCAUX_R"
						(effects
							(font
								(size 1.27 1.27)
							)
						)
					)
					(number "U7"
						(effects
							(font
								(size 1.27 1.27)
							)
						)
					)
				)
				(pin input line
					(at 0 -10.16 0)
					(length 5.08)
					(name "MGTAVTTRCAL_R"
						(effects
							(font
								(size 1.27 1.27)
							)
						)
					)
					(number "AD8"
						(effects
							(font
								(size 1.27 1.27)
							)
						)
					)
				)
				(pin input line
					(at 0 -20.32 0)
					(length 5.08)
					(name "RSVDGND"
						(effects
							(font
								(size 1.27 1.27)
							)
						)
					)
					(number "W11"
						(effects
							(font
								(size 1.27 1.27)
							)
						)
					)
				)
				(pin input line
					(at 0 -22.86 0)
					(length 5.08)
					(name "GNDADC"
						(effects
							(font
								(size 1.27 1.27)
							)
						)
					)
					(number "N13"
						(effects
							(font
								(size 1.27 1.27)
							)
						)
					)
				)
				(pin power_in line
					(at 0 -25.4 0)
					(length 5.08)
					(name "GND"
						(effects
							(font
								(size 1.27 1.27)
							)
						)
					)
					(number "A1"
						(effects
							(font
								(size 1.27 1.27)
							)
						)
					)
				)
				(pin passive line
					(at 0 -25.4 0)
					(length 5.08)
					(hide yes)
					(name "GND"
						(effects
							(font
								(size 1.27 1.27)
							)
						)
					)
					(number "A11"
						(effects
							(font
								(size 1.27 1.27)
							)
						)
					)
				)
				(pin passive line
					(at 0 -25.4 0)
					(length 5.08)
					(hide yes)
					(name "GND"
						(effects
							(font
								(size 1.27 1.27)
							)
						)
					)
					(number "A16"
						(effects
							(font
								(size 1.27 1.27)
							)
						)
					)
				)
				(pin passive line
					(at 0 -25.4 0)
					(length 5.08)
					(hide yes)
					(name "GND"
						(effects
							(font
								(size 1.27 1.27)
							)
						)
					)
					(number "A2"
						(effects
							(font
								(size 1.27 1.27)
							)
						)
					)
				)
				(pin passive line
					(at 0 -25.4 0)
					(length 5.08)
					(hide yes)
					(name "GND"
						(effects
							(font
								(size 1.27 1.27)
							)
						)
					)
					(number "A21"
						(effects
							(font
								(size 1.27 1.27)
							)
						)
					)
				)
				(pin passive line
					(at 0 -25.4 0)
					(length 5.08)
					(hide yes)
					(name "GND"
						(effects
							(font
								(size 1.27 1.27)
							)
						)
					)
					(number "A26"
						(effects
							(font
								(size 1.27 1.27)
							)
						)
					)
				)
				(pin passive line
					(at 0 -25.4 0)
					(length 5.08)
					(hide yes)
					(name "GND"
						(effects
							(font
								(size 1.27 1.27)
							)
						)
					)
					(number "A5"
						(effects
							(font
								(size 1.27 1.27)
							)
						)
					)
				)
				(pin passive line
					(at 0 -25.4 0)
					(length 5.08)
					(hide yes)
					(name "GND"
						(effects
							(font
								(size 1.27 1.27)
							)
						)
					)
					(number "A6"
						(effects
							(font
								(size 1.27 1.27)
							)
						)
					)
				)
				(pin passive line
					(at 0 -25.4 0)
					(length 5.08)
					(hide yes)
					(name "GND"
						(effects
							(font
								(size 1.27 1.27)
							)
						)
					)
					(number "A8"
						(effects
							(font
								(size 1.27 1.27)
							)
						)
					)
				)
				(pin passive line
					(at 0 -25.4 0)
					(length 5.08)
					(hide yes)
					(name "GND"
						(effects
							(font
								(size 1.27 1.27)
							)
						)
					)
					(number "AA1"
						(effects
							(font
								(size 1.27 1.27)
							)
						)
					)
				)
				(pin passive line
					(at 0 -25.4 0)
					(length 5.08)
					(hide yes)
					(name "GND"
						(effects
							(font
								(size 1.27 1.27)
							)
						)
					)
					(number "AA16"
						(effects
							(font
								(size 1.27 1.27)
							)
						)
					)
				)
				(pin passive line
					(at 0 -25.4 0)
					(length 5.08)
					(hide yes)
					(name "GND"
						(effects
							(font
								(size 1.27 1.27)
							)
						)
					)
					(number "AA2"
						(effects
							(font
								(size 1.27 1.27)
							)
						)
					)
				)
				(pin passive line
					(at 0 -25.4 0)
					(length 5.08)
					(hide yes)
					(name "GND"
						(effects
							(font
								(size 1.27 1.27)
							)
						)
					)
					(number "AA26"
						(effects
							(font
								(size 1.27 1.27)
							)
						)
					)
				)
				(pin passive line
					(at 0 -25.4 0)
					(length 5.08)
					(hide yes)
					(name "GND"
						(effects
							(font
								(size 1.27 1.27)
							)
						)
					)
					(number "AA3"
						(effects
							(font
								(size 1.27 1.27)
							)
						)
					)
				)
				(pin passive line
					(at 0 -25.4 0)
					(length 5.08)
					(hide yes)
					(name "GND"
						(effects
							(font
								(size 1.27 1.27)
							)
						)
					)
					(number "AA6"
						(effects
							(font
								(size 1.27 1.27)
							)
						)
					)
				)
				(pin passive line
					(at 0 -25.4 0)
					(length 5.08)
					(hide yes)
					(name "GND"
						(effects
							(font
								(size 1.27 1.27)
							)
						)
					)
					(number "AA8"
						(effects
							(font
								(size 1.27 1.27)
							)
						)
					)
				)
				(pin passive line
					(at 0 -25.4 0)
					(length 5.08)
					(hide yes)
					(name "GND"
						(effects
							(font
								(size 1.27 1.27)
							)
						)
					)
					(number "AB13"
						(effects
							(font
								(size 1.27 1.27)
							)
						)
					)
				)
				(pin passive line
					(at 0 -25.4 0)
					(length 5.08)
					(hide yes)
					(name "GND"
						(effects
							(font
								(size 1.27 1.27)
							)
						)
					)
					(number "AB23"
						(effects
							(font
								(size 1.27 1.27)
							)
						)
					)
				)
				(pin passive line
					(at 0 -25.4 0)
					(length 5.08)
					(hide yes)
					(name "GND"
						(effects
							(font
								(size 1.27 1.27)
							)
						)
					)
					(number "AB3"
						(effects
							(font
								(size 1.27 1.27)
							)
						)
					)
				)
				(pin passive line
					(at 0 -25.4 0)
					(length 5.08)
					(hide yes)
					(name "GND"
						(effects
							(font
								(size 1.27 1.27)
							)
						)
					)
					(number "AB4"
						(effects
							(font
								(size 1.27 1.27)
							)
						)
					)
				)
				(pin passive line
					(at 0 -25.4 0)
					(length 5.08)
					(hide yes)
					(name "GND"
						(effects
							(font
								(size 1.27 1.27)
							)
						)
					)
					(number "AB8"
						(effects
							(font
								(size 1.27 1.27)
							)
						)
					)
				)
				(pin passive line
					(at 0 -25.4 0)
					(length 5.08)
					(hide yes)
					(name "GND"
						(effects
							(font
								(size 1.27 1.27)
							)
						)
					)
					(number "AC1"
						(effects
							(font
								(size 1.27 1.27)
							)
						)
					)
				)
				(pin passive line
					(at 0 -25.4 0)
					(length 5.08)
					(hide yes)
					(name "GND"
						(effects
							(font
								(size 1.27 1.27)
							)
						)
					)
					(number "AC10"
						(effects
							(font
								(size 1.27 1.27)
							)
						)
					)
				)
				(pin passive line
					(at 0 -25.4 0)
					(length 5.08)
					(hide yes)
					(name "GND"
						(effects
							(font
								(size 1.27 1.27)
							)
						)
					)
					(number "AC2"
						(effects
							(font
								(size 1.27 1.27)
							)
						)
					)
				)
				(pin passive line
					(at 0 -25.4 0)
					(length 5.08)
					(hide yes)
					(name "GND"
						(effects
							(font
								(size 1.27 1.27)
							)
						)
					)
					(number "AC20"
						(effects
							(font
								(size 1.27 1.27)
							)
						)
					)
				)
				(pin passive line
					(at 0 -25.4 0)
					(length 5.08)
					(hide yes)
					(name "GND"
						(effects
							(font
								(size 1.27 1.27)
							)
						)
					)
					(number "AC25"
						(effects
							(font
								(size 1.27 1.27)
							)
						)
					)
				)
				(pin passive line
					(at 0 -25.4 0)
					(length 5.08)
					(hide yes)
					(name "GND"
						(effects
							(font
								(size 1.27 1.27)
							)
						)
					)
					(number "AC3"
						(effects
							(font
								(size 1.27 1.27)
							)
						)
					)
				)
				(pin passive line
					(at 0 -25.4 0)
					(length 5.08)
					(hide yes)
					(name "GND"
						(effects
							(font
								(size 1.27 1.27)
							)
						)
					)
					(number "AC6"
						(effects
							(font
								(size 1.27 1.27)
							)
						)
					)
				)
				(pin passive line
					(at 0 -25.4 0)
					(length 5.08)
					(hide yes)
					(name "GND"
						(effects
							(font
								(size 1.27 1.27)
							)
						)
					)
					(number "AC8"
						(effects
							(font
								(size 1.27 1.27)
							)
						)
					)
				)
				(pin passive line
					(at 0 -25.4 0)
					(length 5.08)
					(hide yes)
					(name "GND"
						(effects
							(font
								(size 1.27 1.27)
							)
						)
					)
					(number "AC9"
						(effects
							(font
								(size 1.27 1.27)
							)
						)
					)
				)
				(pin passive line
					(at 0 -25.4 0)
					(length 5.08)
					(hide yes)
					(name "GND"
						(effects
							(font
								(size 1.27 1.27)
							)
						)
					)
					(number "AD10"
						(effects
							(font
								(size 1.27 1.27)
							)
						)
					)
				)
				(pin passive line
					(at 0 -25.4 0)
					(length 5.08)
					(hide yes)
					(name "GND"
						(effects
							(font
								(size 1.27 1.27)
							)
						)
					)
					(number "AD17"
						(effects
							(font
								(size 1.27 1.27)
							)
						)
					)
				)
				(pin passive line
					(at 0 -25.4 0)
					(length 5.08)
					(hide yes)
					(name "GND"
						(effects
							(font
								(size 1.27 1.27)
							)
						)
					)
					(number "AD3"
						(effects
							(font
								(size 1.27 1.27)
							)
						)
					)
				)
				(pin passive line
					(at 0 -25.4 0)
					(length 5.08)
					(hide yes)
					(name "GND"
						(effects
							(font
								(size 1.27 1.27)
							)
						)
					)
					(number "AD4"
						(effects
							(font
								(size 1.27 1.27)
							)
						)
					)
				)
				(pin passive line
					(at 0 -25.4 0)
					(length 5.08)
					(hide yes)
					(name "GND"
						(effects
							(font
								(size 1.27 1.27)
							)
						)
					)
					(number "AD5"
						(effects
							(font
								(size 1.27 1.27)
							)
						)
					)
				)
				(pin passive line
					(at 0 -25.4 0)
					(length 5.08)
					(hide yes)
					(name "GND"
						(effects
							(font
								(size 1.27 1.27)
							)
						)
					)
					(number "AE1"
						(effects
							(font
								(size 1.27 1.27)
							)
						)
					)
				)
				(pin passive line
					(at 0 -25.4 0)
					(length 5.08)
					(hide yes)
					(name "GND"
						(effects
							(font
								(size 1.27 1.27)
							)
						)
					)
					(number "AE10"
						(effects
							(font
								(size 1.27 1.27)
							)
						)
					)
				)
				(pin passive line
					(at 0 -25.4 0)
					(length 5.08)
					(hide yes)
					(name "GND"
						(effects
							(font
								(size 1.27 1.27)
							)
						)
					)
					(number "AE14"
						(effects
							(font
								(size 1.27 1.27)
							)
						)
					)
				)
				(pin passive line
					(at 0 -25.4 0)
					(length 5.08)
					(hide yes)
					(name "GND"
						(effects
							(font
								(size 1.27 1.27)
							)
						)
					)
					(number "AE19"
						(effects
							(font
								(size 1.27 1.27)
							)
						)
					)
				)
				(pin passive line
					(at 0 -25.4 0)
					(length 5.08)
					(hide yes)
					(name "GND"
						(effects
							(font
								(size 1.27 1.27)
							)
						)
					)
					(number "AE2"
						(effects
							(font
								(size 1.27 1.27)
							)
						)
					)
				)
				(pin passive line
					(at 0 -25.4 0)
					(length 5.08)
					(hide yes)
					(name "GND"
						(effects
							(font
								(size 1.27 1.27)
							)
						)
					)
					(number "AE24"
						(effects
							(font
								(size 1.27 1.27)
							)
						)
					)
				)
				(pin passive line
					(at 0 -25.4 0)
					(length 5.08)
					(hide yes)
					(name "GND"
						(effects
							(font
								(size 1.27 1.27)
							)
						)
					)
					(number "AE5"
						(effects
							(font
								(size 1.27 1.27)
							)
						)
					)
				)
				(pin passive line
					(at 0 -25.4 0)
					(length 5.08)
					(hide yes)
					(name "GND"
						(effects
							(font
								(size 1.27 1.27)
							)
						)
					)
					(number "AE6"
						(effects
							(font
								(size 1.27 1.27)
							)
						)
					)
				)
				(pin passive line
					(at 0 -25.4 0)
					(length 5.08)
					(hide yes)
					(name "GND"
						(effects
							(font
								(size 1.27 1.27)
							)
						)
					)
					(number "AF10"
						(effects
							(font
								(size 1.27 1.27)
							)
						)
					)
				)
				(pin passive line
					(at 0 -25.4 0)
					(length 5.08)
					(hide yes)
					(name "GND"
						(effects
							(font
								(size 1.27 1.27)
							)
						)
					)
					(number "AF11"
						(effects
							(font
								(size 1.27 1.27)
							)
						)
					)
				)
				(pin passive line
					(at 0 -25.4 0)
					(length 5.08)
					(hide yes)
					(name "GND"
						(effects
							(font
								(size 1.27 1.27)
							)
						)
					)
					(number "AF16"
						(effects
							(font
								(size 1.27 1.27)
							)
						)
					)
				)
				(pin passive line
					(at 0 -25.4 0)
					(length 5.08)
					(hide yes)
					(name "GND"
						(effects
							(font
								(size 1.27 1.27)
							)
						)
					)
					(number "AF21"
						(effects
							(font
								(size 1.27 1.27)
							)
						)
					)
				)
				(pin passive line
					(at 0 -25.4 0)
					(length 5.08)
					(hide yes)
					(name "GND"
						(effects
							(font
								(size 1.27 1.27)
							)
						)
					)
					(number "AF26"
						(effects
							(font
								(size 1.27 1.27)
							)
						)
					)
				)
				(pin passive line
					(at 0 -25.4 0)
					(length 5.08)
					(hide yes)
					(name "GND"
						(effects
							(font
								(size 1.27 1.27)
							)
						)
					)
					(number "AF3"
						(effects
							(font
								(size 1.27 1.27)
							)
						)
					)
				)
				(pin passive line
					(at 0 -25.4 0)
					(length 5.08)
					(hide yes)
					(name "GND"
						(effects
							(font
								(size 1.27 1.27)
							)
						)
					)
					(number "AF4"
						(effects
							(font
								(size 1.27 1.27)
							)
						)
					)
				)
				(pin passive line
					(at 0 -25.4 0)
					(length 5.08)
					(hide yes)
					(name "GND"
						(effects
							(font
								(size 1.27 1.27)
							)
						)
					)
					(number "AF5"
						(effects
							(font
								(size 1.27 1.27)
							)
						)
					)
				)
				(pin passive line
					(at 0 -25.4 0)
					(length 5.08)
					(hide yes)
					(name "GND"
						(effects
							(font
								(size 1.27 1.27)
							)
						)
					)
					(number "AF8"
						(effects
							(font
								(size 1.27 1.27)
							)
						)
					)
				)
				(pin passive line
					(at 0 -25.4 0)
					(length 5.08)
					(hide yes)
					(name "GND"
						(effects
							(font
								(size 1.27 1.27)
							)
						)
					)
					(number "AF9"
						(effects
							(font
								(size 1.27 1.27)
							)
						)
					)
				)
				(pin passive line
					(at 0 -25.4 0)
					(length 5.08)
					(hide yes)
					(name "GND"
						(effects
							(font
								(size 1.27 1.27)
							)
						)
					)
					(number "B13"
						(effects
							(font
								(size 1.27 1.27)
							)
						)
					)
				)
				(pin passive line
					(at 0 -25.4 0)
					(length 5.08)
					(hide yes)
					(name "GND"
						(effects
							(font
								(size 1.27 1.27)
							)
						)
					)
					(number "B18"
						(effects
							(font
								(size 1.27 1.27)
							)
						)
					)
				)
				(pin passive line
					(at 0 -25.4 0)
					(length 5.08)
					(hide yes)
					(name "GND"
						(effects
							(font
								(size 1.27 1.27)
							)
						)
					)
					(number "B23"
						(effects
							(font
								(size 1.27 1.27)
							)
						)
					)
				)
				(pin passive line
					(at 0 -25.4 0)
					(length 5.08)
					(hide yes)
					(name "GND"
						(effects
							(font
								(size 1.27 1.27)
							)
						)
					)
					(number "B3"
						(effects
							(font
								(size 1.27 1.27)
							)
						)
					)
				)
				(pin passive line
					(at 0 -25.4 0)
					(length 5.08)
					(hide yes)
					(name "GND"
						(effects
							(font
								(size 1.27 1.27)
							)
						)
					)
					(number "B4"
						(effects
							(font
								(size 1.27 1.27)
							)
						)
					)
				)
				(pin passive line
					(at 0 -25.4 0)
					(length 5.08)
					(hide yes)
					(name "GND"
						(effects
							(font
								(size 1.27 1.27)
							)
						)
					)
					(number "B5"
						(effects
							(font
								(size 1.27 1.27)
							)
						)
					)
				)
				(pin passive line
					(at 0 -25.4 0)
					(length 5.08)
					(hide yes)
					(name "GND"
						(effects
							(font
								(size 1.27 1.27)
							)
						)
					)
					(number "B8"
						(effects
							(font
								(size 1.27 1.27)
							)
						)
					)
				)
				(pin passive line
					(at 0 -25.4 0)
					(length 5.08)
					(hide yes)
					(name "GND"
						(effects
							(font
								(size 1.27 1.27)
							)
						)
					)
					(number "C1"
						(effects
							(font
								(size 1.27 1.27)
							)
						)
					)
				)
				(pin passive line
					(at 0 -25.4 0)
					(length 5.08)
					(hide yes)
					(name "GND"
						(effects
							(font
								(size 1.27 1.27)
							)
						)
					)
					(number "C10"
						(effects
							(font
								(size 1.27 1.27)
							)
						)
					)
				)
				(pin passive line
					(at 0 -25.4 0)
					(length 5.08)
					(hide yes)
					(name "GND"
						(effects
							(font
								(size 1.27 1.27)
							)
						)
					)
					(number "C15"
						(effects
							(font
								(size 1.27 1.27)
							)
						)
					)
				)
				(pin passive line
					(at 0 -25.4 0)
					(length 5.08)
					(hide yes)
					(name "GND"
						(effects
							(font
								(size 1.27 1.27)
							)
						)
					)
					(number "C2"
						(effects
							(font
								(size 1.27 1.27)
							)
						)
					)
				)
				(pin passive line
					(at 0 -25.4 0)
					(length 5.08)
					(hide yes)
					(name "GND"
						(effects
							(font
								(size 1.27 1.27)
							)
						)
					)
					(number "C25"
						(effects
							(font
								(size 1.27 1.27)
							)
						)
					)
				)
				(pin passive line
					(at 0 -25.4 0)
					(length 5.08)
					(hide yes)
					(name "GND"
						(effects
							(font
								(size 1.27 1.27)
							)
						)
					)
					(number "C5"
						(effects
							(font
								(size 1.27 1.27)
							)
						)
					)
				)
				(pin passive line
					(at 0 -25.4 0)
					(length 5.08)
					(hide yes)
					(name "GND"
						(effects
							(font
								(size 1.27 1.27)
							)
						)
					)
					(number "C6"
						(effects
							(font
								(size 1.27 1.27)
							)
						)
					)
				)
				(pin passive line
					(at 0 -25.4 0)
					(length 5.08)
					(hide yes)
					(name "GND"
						(effects
							(font
								(size 1.27 1.27)
							)
						)
					)
					(number "C8"
						(effects
							(font
								(size 1.27 1.27)
							)
						)
					)
				)
				(pin passive line
					(at 0 -25.4 0)
					(length 5.08)
					(hide yes)
					(name "GND"
						(effects
							(font
								(size 1.27 1.27)
							)
						)
					)
					(number "D12"
						(effects
							(font
								(size 1.27 1.27)
							)
						)
					)
				)
				(pin passive line
					(at 0 -25.4 0)
					(length 5.08)
					(hide yes)
					(name "GND"
						(effects
							(font
								(size 1.27 1.27)
							)
						)
					)
					(number "D22"
						(effects
							(font
								(size 1.27 1.27)
							)
						)
					)
				)
				(pin passive line
					(at 0 -25.4 0)
					(length 5.08)
					(hide yes)
					(name "GND"
						(effects
							(font
								(size 1.27 1.27)
							)
						)
					)
					(number "D3"
						(effects
							(font
								(size 1.27 1.27)
							)
						)
					)
				)
				(pin passive line
					(at 0 -25.4 0)
					(length 5.08)
					(hide yes)
					(name "GND"
						(effects
							(font
								(size 1.27 1.27)
							)
						)
					)
					(number "D4"
						(effects
							(font
								(size 1.27 1.27)
							)
						)
					)
				)
				(pin passive line
					(at 0 -25.4 0)
					(length 5.08)
					(hide yes)
					(name "GND"
						(effects
							(font
								(size 1.27 1.27)
							)
						)
					)
					(number "D5"
						(effects
							(font
								(size 1.27 1.27)
							)
						)
					)
				)
				(pin passive line
					(at 0 -25.4 0)
					(length 5.08)
					(hide yes)
					(name "GND"
						(effects
							(font
								(size 1.27 1.27)
							)
						)
					)
					(number "D8"
						(effects
							(font
								(size 1.27 1.27)
							)
						)
					)
				)
				(pin passive line
					(at 0 -25.4 0)
					(length 5.08)
					(hide yes)
					(name "GND"
						(effects
							(font
								(size 1.27 1.27)
							)
						)
					)
					(number "E1"
						(effects
							(font
								(size 1.27 1.27)
							)
						)
					)
				)
				(pin passive line
					(at 0 -25.4 0)
					(length 5.08)
					(hide yes)
					(name "GND"
						(effects
							(font
								(size 1.27 1.27)
							)
						)
					)
					(number "E19"
						(effects
							(font
								(size 1.27 1.27)
							)
						)
					)
				)
				(pin passive line
					(at 0 -25.4 0)
					(length 5.08)
					(hide yes)
					(name "GND"
						(effects
							(font
								(size 1.27 1.27)
							)
						)
					)
					(number "E2"
						(effects
							(font
								(size 1.27 1.27)
							)
						)
					)
				)
				(pin passive line
					(at 0 -25.4 0)
					(length 5.08)
					(hide yes)
					(name "GND"
						(effects
							(font
								(size 1.27 1.27)
							)
						)
					)
					(number "E3"
						(effects
							(font
								(size 1.27 1.27)
							)
						)
					)
				)
				(pin passive line
					(at 0 -25.4 0)
					(length 5.08)
					(hide yes)
					(name "GND"
						(effects
							(font
								(size 1.27 1.27)
							)
						)
					)
					(number "E6"
						(effects
							(font
								(size 1.27 1.27)
							)
						)
					)
				)
				(pin passive line
					(at 0 -25.4 0)
					(length 5.08)
					(hide yes)
					(name "GND"
						(effects
							(font
								(size 1.27 1.27)
							)
						)
					)
					(number "E8"
						(effects
							(font
								(size 1.27 1.27)
							)
						)
					)
				)
				(pin passive line
					(at 0 -25.4 0)
					(length 5.08)
					(hide yes)
					(name "GND"
						(effects
							(font
								(size 1.27 1.27)
							)
						)
					)
					(number "F11"
						(effects
							(font
								(size 1.27 1.27)
							)
						)
					)
				)
				(pin passive line
					(at 0 -25.4 0)
					(length 5.08)
					(hide yes)
					(name "GND"
						(effects
							(font
								(size 1.27 1.27)
							)
						)
					)
					(number "F16"
						(effects
							(font
								(size 1.27 1.27)
							)
						)
					)
				)
				(pin passive line
					(at 0 -25.4 0)
					(length 5.08)
					(hide yes)
					(name "GND"
						(effects
							(font
								(size 1.27 1.27)
							)
						)
					)
					(number "F21"
						(effects
							(font
								(size 1.27 1.27)
							)
						)
					)
				)
				(pin passive line
					(at 0 -25.4 0)
					(length 5.08)
					(hide yes)
					(name "GND"
						(effects
							(font
								(size 1.27 1.27)
							)
						)
					)
					(number "F26"
						(effects
							(font
								(size 1.27 1.27)
							)
						)
					)
				)
				(pin passive line
					(at 0 -25.4 0)
					(length 5.08)
					(hide yes)
					(name "GND"
						(effects
							(font
								(size 1.27 1.27)
							)
						)
					)
					(number "F3"
						(effects
							(font
								(size 1.27 1.27)
							)
						)
					)
				)
				(pin passive line
					(at 0 -25.4 0)
					(length 5.08)
					(hide yes)
					(name "GND"
						(effects
							(font
								(size 1.27 1.27)
							)
						)
					)
					(number "F4"
						(effects
							(font
								(size 1.27 1.27)
							)
						)
					)
				)
				(pin passive line
					(at 0 -25.4 0)
					(length 5.08)
					(hide yes)
					(name "GND"
						(effects
							(font
								(size 1.27 1.27)
							)
						)
					)
					(number "F8"
						(effects
							(font
								(size 1.27 1.27)
							)
						)
					)
				)
				(pin passive line
					(at 0 -25.4 0)
					(length 5.08)
					(hide yes)
					(name "GND"
						(effects
							(font
								(size 1.27 1.27)
							)
						)
					)
					(number "G1"
						(effects
							(font
								(size 1.27 1.27)
							)
						)
					)
				)
				(pin passive line
					(at 0 -25.4 0)
					(length 5.08)
					(hide yes)
					(name "GND"
						(effects
							(font
								(size 1.27 1.27)
							)
						)
					)
					(number "G13"
						(effects
							(font
								(size 1.27 1.27)
							)
						)
					)
				)
				(pin passive line
					(at 0 -25.4 0)
					(length 5.08)
					(hide yes)
					(name "GND"
						(effects
							(font
								(size 1.27 1.27)
							)
						)
					)
					(number "G2"
						(effects
							(font
								(size 1.27 1.27)
							)
						)
					)
				)
				(pin passive line
					(at 0 -25.4 0)
					(length 5.08)
					(hide yes)
					(name "GND"
						(effects
							(font
								(size 1.27 1.27)
							)
						)
					)
					(number "G23"
						(effects
							(font
								(size 1.27 1.27)
							)
						)
					)
				)
				(pin passive line
					(at 0 -25.4 0)
					(length 5.08)
					(hide yes)
					(name "GND"
						(effects
							(font
								(size 1.27 1.27)
							)
						)
					)
					(number "G3"
						(effects
							(font
								(size 1.27 1.27)
							)
						)
					)
				)
				(pin passive line
					(at 0 -25.4 0)
					(length 5.08)
					(hide yes)
					(name "GND"
						(effects
							(font
								(size 1.27 1.27)
							)
						)
					)
					(number "G6"
						(effects
							(font
								(size 1.27 1.27)
							)
						)
					)
				)
				(pin passive line
					(at 0 -25.4 0)
					(length 5.08)
					(hide yes)
					(name "GND"
						(effects
							(font
								(size 1.27 1.27)
							)
						)
					)
					(number "G8"
						(effects
							(font
								(size 1.27 1.27)
							)
						)
					)
				)
				(pin passive line
					(at 0 -25.4 0)
					(length 5.08)
					(hide yes)
					(name "GND"
						(effects
							(font
								(size 1.27 1.27)
							)
						)
					)
					(number "H20"
						(effects
							(font
								(size 1.27 1.27)
							)
						)
					)
				)
				(pin passive line
					(at 0 -25.4 0)
					(length 5.08)
					(hide yes)
					(name "GND"
						(effects
							(font
								(size 1.27 1.27)
							)
						)
					)
					(number "H3"
						(effects
							(font
								(size 1.27 1.27)
							)
						)
					)
				)
				(pin passive line
					(at 0 -25.4 0)
					(length 5.08)
					(hide yes)
					(name "GND"
						(effects
							(font
								(size 1.27 1.27)
							)
						)
					)
					(number "H4"
						(effects
							(font
								(size 1.27 1.27)
							)
						)
					)
				)
				(pin passive line
					(at 0 -25.4 0)
					(length 5.08)
					(hide yes)
					(name "GND"
						(effects
							(font
								(size 1.27 1.27)
							)
						)
					)
					(number "H8"
						(effects
							(font
								(size 1.27 1.27)
							)
						)
					)
				)
				(pin passive line
					(at 0 -25.4 0)
					(length 5.08)
					(hide yes)
					(name "GND"
						(effects
							(font
								(size 1.27 1.27)
							)
						)
					)
					(number "J1"
						(effects
							(font
								(size 1.27 1.27)
							)
						)
					)
				)
				(pin passive line
					(at 0 -25.4 0)
					(length 5.08)
					(hide yes)
					(name "GND"
						(effects
							(font
								(size 1.27 1.27)
							)
						)
					)
					(number "J17"
						(effects
							(font
								(size 1.27 1.27)
							)
						)
					)
				)
				(pin passive line
					(at 0 -25.4 0)
					(length 5.08)
					(hide yes)
					(name "GND"
						(effects
							(font
								(size 1.27 1.27)
							)
						)
					)
					(number "J2"
						(effects
							(font
								(size 1.27 1.27)
							)
						)
					)
				)
				(pin passive line
					(at 0 -25.4 0)
					(length 5.08)
					(hide yes)
					(name "GND"
						(effects
							(font
								(size 1.27 1.27)
							)
						)
					)
					(number "J3"
						(effects
							(font
								(size 1.27 1.27)
							)
						)
					)
				)
				(pin passive line
					(at 0 -25.4 0)
					(length 5.08)
					(hide yes)
					(name "GND"
						(effects
							(font
								(size 1.27 1.27)
							)
						)
					)
					(number "J6"
						(effects
							(font
								(size 1.27 1.27)
							)
						)
					)
				)
				(pin passive line
					(at 0 -25.4 0)
					(length 5.08)
					(hide yes)
					(name "GND"
						(effects
							(font
								(size 1.27 1.27)
							)
						)
					)
					(number "J8"
						(effects
							(font
								(size 1.27 1.27)
							)
						)
					)
				)
				(pin passive line
					(at 0 -25.4 0)
					(length 5.08)
					(hide yes)
					(name "GND"
						(effects
							(font
								(size 1.27 1.27)
							)
						)
					)
					(number "K12"
						(effects
							(font
								(size 1.27 1.27)
							)
						)
					)
				)
				(pin passive line
					(at 0 -25.4 0)
					(length 5.08)
					(hide yes)
					(name "GND"
						(effects
							(font
								(size 1.27 1.27)
							)
						)
					)
					(number "K14"
						(effects
							(font
								(size 1.27 1.27)
							)
						)
					)
				)
				(pin passive line
					(at 0 -25.4 0)
					(length 5.08)
					(hide yes)
					(name "GND"
						(effects
							(font
								(size 1.27 1.27)
							)
						)
					)
					(number "K16"
						(effects
							(font
								(size 1.27 1.27)
							)
						)
					)
				)
				(pin passive line
					(at 0 -25.4 0)
					(length 5.08)
					(hide yes)
					(name "GND"
						(effects
							(font
								(size 1.27 1.27)
							)
						)
					)
					(number "K19"
						(effects
							(font
								(size 1.27 1.27)
							)
						)
					)
				)
				(pin passive line
					(at 0 -25.4 0)
					(length 5.08)
					(hide yes)
					(name "GND"
						(effects
							(font
								(size 1.27 1.27)
							)
						)
					)
					(number "K24"
						(effects
							(font
								(size 1.27 1.27)
							)
						)
					)
				)
				(pin passive line
					(at 0 -25.4 0)
					(length 5.08)
					(hide yes)
					(name "GND"
						(effects
							(font
								(size 1.27 1.27)
							)
						)
					)
					(number "K3"
						(effects
							(font
								(size 1.27 1.27)
							)
						)
					)
				)
				(pin passive line
					(at 0 -25.4 0)
					(length 5.08)
					(hide yes)
					(name "GND"
						(effects
							(font
								(size 1.27 1.27)
							)
						)
					)
					(number "K4"
						(effects
							(font
								(size 1.27 1.27)
							)
						)
					)
				)
				(pin passive line
					(at 0 -25.4 0)
					(length 5.08)
					(hide yes)
					(name "GND"
						(effects
							(font
								(size 1.27 1.27)
							)
						)
					)
					(number "K8"
						(effects
							(font
								(size 1.27 1.27)
							)
						)
					)
				)
				(pin passive line
					(at 0 -25.4 0)
					(length 5.08)
					(hide yes)
					(name "GND"
						(effects
							(font
								(size 1.27 1.27)
							)
						)
					)
					(number "L1"
						(effects
							(font
								(size 1.27 1.27)
							)
						)
					)
				)
				(pin passive line
					(at 0 -25.4 0)
					(length 5.08)
					(hide yes)
					(name "GND"
						(effects
							(font
								(size 1.27 1.27)
							)
						)
					)
					(number "L11"
						(effects
							(font
								(size 1.27 1.27)
							)
						)
					)
				)
				(pin passive line
					(at 0 -25.4 0)
					(length 5.08)
					(hide yes)
					(name "GND"
						(effects
							(font
								(size 1.27 1.27)
							)
						)
					)
					(number "L13"
						(effects
							(font
								(size 1.27 1.27)
							)
						)
					)
				)
				(pin passive line
					(at 0 -25.4 0)
					(length 5.08)
					(hide yes)
					(name "GND"
						(effects
							(font
								(size 1.27 1.27)
							)
						)
					)
					(number "L15"
						(effects
							(font
								(size 1.27 1.27)
							)
						)
					)
				)
				(pin passive line
					(at 0 -25.4 0)
					(length 5.08)
					(hide yes)
					(name "GND"
						(effects
							(font
								(size 1.27 1.27)
							)
						)
					)
					(number "L17"
						(effects
							(font
								(size 1.27 1.27)
							)
						)
					)
				)
				(pin passive line
					(at 0 -25.4 0)
					(length 5.08)
					(hide yes)
					(name "GND"
						(effects
							(font
								(size 1.27 1.27)
							)
						)
					)
					(number "L2"
						(effects
							(font
								(size 1.27 1.27)
							)
						)
					)
				)
				(pin passive line
					(at 0 -25.4 0)
					(length 5.08)
					(hide yes)
					(name "GND"
						(effects
							(font
								(size 1.27 1.27)
							)
						)
					)
					(number "L21"
						(effects
							(font
								(size 1.27 1.27)
							)
						)
					)
				)
				(pin passive line
					(at 0 -25.4 0)
					(length 5.08)
					(hide yes)
					(name "GND"
						(effects
							(font
								(size 1.27 1.27)
							)
						)
					)
					(number "L26"
						(effects
							(font
								(size 1.27 1.27)
							)
						)
					)
				)
				(pin passive line
					(at 0 -25.4 0)
					(length 5.08)
					(hide yes)
					(name "GND"
						(effects
							(font
								(size 1.27 1.27)
							)
						)
					)
					(number "L3"
						(effects
							(font
								(size 1.27 1.27)
							)
						)
					)
				)
				(pin passive line
					(at 0 -25.4 0)
					(length 5.08)
					(hide yes)
					(name "GND"
						(effects
							(font
								(size 1.27 1.27)
							)
						)
					)
					(number "L6"
						(effects
							(font
								(size 1.27 1.27)
							)
						)
					)
				)
				(pin passive line
					(at 0 -25.4 0)
					(length 5.08)
					(hide yes)
					(name "GND"
						(effects
							(font
								(size 1.27 1.27)
							)
						)
					)
					(number "L8"
						(effects
							(font
								(size 1.27 1.27)
							)
						)
					)
				)
				(pin passive line
					(at 0 -25.4 0)
					(length 5.08)
					(hide yes)
					(name "GND"
						(effects
							(font
								(size 1.27 1.27)
							)
						)
					)
					(number "M10"
						(effects
							(font
								(size 1.27 1.27)
							)
						)
					)
				)
				(pin passive line
					(at 0 -25.4 0)
					(length 5.08)
					(hide yes)
					(name "GND"
						(effects
							(font
								(size 1.27 1.27)
							)
						)
					)
					(number "M12"
						(effects
							(font
								(size 1.27 1.27)
							)
						)
					)
				)
				(pin passive line
					(at 0 -25.4 0)
					(length 5.08)
					(hide yes)
					(name "GND"
						(effects
							(font
								(size 1.27 1.27)
							)
						)
					)
					(number "M14"
						(effects
							(font
								(size 1.27 1.27)
							)
						)
					)
				)
				(pin passive line
					(at 0 -25.4 0)
					(length 5.08)
					(hide yes)
					(name "GND"
						(effects
							(font
								(size 1.27 1.27)
							)
						)
					)
					(number "M16"
						(effects
							(font
								(size 1.27 1.27)
							)
						)
					)
				)
				(pin passive line
					(at 0 -25.4 0)
					(length 5.08)
					(hide yes)
					(name "GND"
						(effects
							(font
								(size 1.27 1.27)
							)
						)
					)
					(number "M23"
						(effects
							(font
								(size 1.27 1.27)
							)
						)
					)
				)
				(pin passive line
					(at 0 -25.4 0)
					(length 5.08)
					(hide yes)
					(name "GND"
						(effects
							(font
								(size 1.27 1.27)
							)
						)
					)
					(number "M3"
						(effects
							(font
								(size 1.27 1.27)
							)
						)
					)
				)
				(pin passive line
					(at 0 -25.4 0)
					(length 5.08)
					(hide yes)
					(name "GND"
						(effects
							(font
								(size 1.27 1.27)
							)
						)
					)
					(number "M4"
						(effects
							(font
								(size 1.27 1.27)
							)
						)
					)
				)
				(pin passive line
					(at 0 -25.4 0)
					(length 5.08)
					(hide yes)
					(name "GND"
						(effects
							(font
								(size 1.27 1.27)
							)
						)
					)
					(number "M8"
						(effects
							(font
								(size 1.27 1.27)
							)
						)
					)
				)
				(pin passive line
					(at 0 -25.4 0)
					(length 5.08)
					(hide yes)
					(name "GND"
						(effects
							(font
								(size 1.27 1.27)
							)
						)
					)
					(number "N1"
						(effects
							(font
								(size 1.27 1.27)
							)
						)
					)
				)
				(pin passive line
					(at 0 -25.4 0)
					(length 5.08)
					(hide yes)
					(name "GND"
						(effects
							(font
								(size 1.27 1.27)
							)
						)
					)
					(number "N11"
						(effects
							(font
								(size 1.27 1.27)
							)
						)
					)
				)
				(pin passive line
					(at 0 -25.4 0)
					(length 5.08)
					(hide yes)
					(name "GND"
						(effects
							(font
								(size 1.27 1.27)
							)
						)
					)
					(number "N15"
						(effects
							(font
								(size 1.27 1.27)
							)
						)
					)
				)
				(pin passive line
					(at 0 -25.4 0)
					(length 5.08)
					(hide yes)
					(name "GND"
						(effects
							(font
								(size 1.27 1.27)
							)
						)
					)
					(number "N17"
						(effects
							(font
								(size 1.27 1.27)
							)
						)
					)
				)
				(pin passive line
					(at 0 -25.4 0)
					(length 5.08)
					(hide yes)
					(name "GND"
						(effects
							(font
								(size 1.27 1.27)
							)
						)
					)
					(number "N2"
						(effects
							(font
								(size 1.27 1.27)
							)
						)
					)
				)
				(pin passive line
					(at 0 -25.4 0)
					(length 5.08)
					(hide yes)
					(name "GND"
						(effects
							(font
								(size 1.27 1.27)
							)
						)
					)
					(number "N20"
						(effects
							(font
								(size 1.27 1.27)
							)
						)
					)
				)
				(pin passive line
					(at 0 -25.4 0)
					(length 5.08)
					(hide yes)
					(name "GND"
						(effects
							(font
								(size 1.27 1.27)
							)
						)
					)
					(number "N25"
						(effects
							(font
								(size 1.27 1.27)
							)
						)
					)
				)
				(pin passive line
					(at 0 -25.4 0)
					(length 5.08)
					(hide yes)
					(name "GND"
						(effects
							(font
								(size 1.27 1.27)
							)
						)
					)
					(number "N3"
						(effects
							(font
								(size 1.27 1.27)
							)
						)
					)
				)
				(pin passive line
					(at 0 -25.4 0)
					(length 5.08)
					(hide yes)
					(name "GND"
						(effects
							(font
								(size 1.27 1.27)
							)
						)
					)
					(number "N6"
						(effects
							(font
								(size 1.27 1.27)
							)
						)
					)
				)
				(pin passive line
					(at 0 -25.4 0)
					(length 5.08)
					(hide yes)
					(name "GND"
						(effects
							(font
								(size 1.27 1.27)
							)
						)
					)
					(number "N8"
						(effects
							(font
								(size 1.27 1.27)
							)
						)
					)
				)
				(pin passive line
					(at 0 -25.4 0)
					(length 5.08)
					(hide yes)
					(name "GND"
						(effects
							(font
								(size 1.27 1.27)
							)
						)
					)
					(number "P10"
						(effects
							(font
								(size 1.27 1.27)
							)
						)
					)
				)
				(pin passive line
					(at 0 -25.4 0)
					(length 5.08)
					(hide yes)
					(name "GND"
						(effects
							(font
								(size 1.27 1.27)
							)
						)
					)
					(number "P12"
						(effects
							(font
								(size 1.27 1.27)
							)
						)
					)
				)
				(pin passive line
					(at 0 -25.4 0)
					(length 5.08)
					(hide yes)
					(name "GND"
						(effects
							(font
								(size 1.27 1.27)
							)
						)
					)
					(number "P16"
						(effects
							(font
								(size 1.27 1.27)
							)
						)
					)
				)
				(pin passive line
					(at 0 -25.4 0)
					(length 5.08)
					(hide yes)
					(name "GND"
						(effects
							(font
								(size 1.27 1.27)
							)
						)
					)
					(number "P3"
						(effects
							(font
								(size 1.27 1.27)
							)
						)
					)
				)
				(pin passive line
					(at 0 -25.4 0)
					(length 5.08)
					(hide yes)
					(name "GND"
						(effects
							(font
								(size 1.27 1.27)
							)
						)
					)
					(number "P4"
						(effects
							(font
								(size 1.27 1.27)
							)
						)
					)
				)
				(pin passive line
					(at 0 -25.4 0)
					(length 5.08)
					(hide yes)
					(name "GND"
						(effects
							(font
								(size 1.27 1.27)
							)
						)
					)
					(number "P8"
						(effects
							(font
								(size 1.27 1.27)
							)
						)
					)
				)
				(pin passive line
					(at 0 -25.4 0)
					(length 5.08)
					(hide yes)
					(name "GND"
						(effects
							(font
								(size 1.27 1.27)
							)
						)
					)
					(number "R1"
						(effects
							(font
								(size 1.27 1.27)
							)
						)
					)
				)
				(pin passive line
					(at 0 -25.4 0)
					(length 5.08)
					(hide yes)
					(name "GND"
						(effects
							(font
								(size 1.27 1.27)
							)
						)
					)
					(number "R11"
						(effects
							(font
								(size 1.27 1.27)
							)
						)
					)
				)
				(pin passive line
					(at 0 -25.4 0)
					(length 5.08)
					(hide yes)
					(name "GND"
						(effects
							(font
								(size 1.27 1.27)
							)
						)
					)
					(number "R15"
						(effects
							(font
								(size 1.27 1.27)
							)
						)
					)
				)
				(pin passive line
					(at 0 -25.4 0)
					(length 5.08)
					(hide yes)
					(name "GND"
						(effects
							(font
								(size 1.27 1.27)
							)
						)
					)
					(number "R17"
						(effects
							(font
								(size 1.27 1.27)
							)
						)
					)
				)
				(pin passive line
					(at 0 -25.4 0)
					(length 5.08)
					(hide yes)
					(name "GND"
						(effects
							(font
								(size 1.27 1.27)
							)
						)
					)
					(number "R19"
						(effects
							(font
								(size 1.27 1.27)
							)
						)
					)
				)
				(pin passive line
					(at 0 -25.4 0)
					(length 5.08)
					(hide yes)
					(name "GND"
						(effects
							(font
								(size 1.27 1.27)
							)
						)
					)
					(number "R2"
						(effects
							(font
								(size 1.27 1.27)
							)
						)
					)
				)
				(pin passive line
					(at 0 -25.4 0)
					(length 5.08)
					(hide yes)
					(name "GND"
						(effects
							(font
								(size 1.27 1.27)
							)
						)
					)
					(number "R24"
						(effects
							(font
								(size 1.27 1.27)
							)
						)
					)
				)
				(pin passive line
					(at 0 -25.4 0)
					(length 5.08)
					(hide yes)
					(name "GND"
						(effects
							(font
								(size 1.27 1.27)
							)
						)
					)
					(number "R3"
						(effects
							(font
								(size 1.27 1.27)
							)
						)
					)
				)
				(pin passive line
					(at 0 -25.4 0)
					(length 5.08)
					(hide yes)
					(name "GND"
						(effects
							(font
								(size 1.27 1.27)
							)
						)
					)
					(number "R6"
						(effects
							(font
								(size 1.27 1.27)
							)
						)
					)
				)
				(pin passive line
					(at 0 -25.4 0)
					(length 5.08)
					(hide yes)
					(name "GND"
						(effects
							(font
								(size 1.27 1.27)
							)
						)
					)
					(number "R8"
						(effects
							(font
								(size 1.27 1.27)
							)
						)
					)
				)
				(pin passive line
					(at 0 -25.4 0)
					(length 5.08)
					(hide yes)
					(name "GND"
						(effects
							(font
								(size 1.27 1.27)
							)
						)
					)
					(number "T10"
						(effects
							(font
								(size 1.27 1.27)
							)
						)
					)
				)
				(pin passive line
					(at 0 -25.4 0)
					(length 5.08)
					(hide yes)
					(name "GND"
						(effects
							(font
								(size 1.27 1.27)
							)
						)
					)
					(number "T12"
						(effects
							(font
								(size 1.27 1.27)
							)
						)
					)
				)
				(pin passive line
					(at 0 -25.4 0)
					(length 5.08)
					(hide yes)
					(name "GND"
						(effects
							(font
								(size 1.27 1.27)
							)
						)
					)
					(number "T16"
						(effects
							(font
								(size 1.27 1.27)
							)
						)
					)
				)
				(pin passive line
					(at 0 -25.4 0)
					(length 5.08)
					(hide yes)
					(name "GND"
						(effects
							(font
								(size 1.27 1.27)
							)
						)
					)
					(number "T21"
						(effects
							(font
								(size 1.27 1.27)
							)
						)
					)
				)
				(pin passive line
					(at 0 -25.4 0)
					(length 5.08)
					(hide yes)
					(name "GND"
						(effects
							(font
								(size 1.27 1.27)
							)
						)
					)
					(number "T26"
						(effects
							(font
								(size 1.27 1.27)
							)
						)
					)
				)
				(pin passive line
					(at 0 -25.4 0)
					(length 5.08)
					(hide yes)
					(name "GND"
						(effects
							(font
								(size 1.27 1.27)
							)
						)
					)
					(number "T3"
						(effects
							(font
								(size 1.27 1.27)
							)
						)
					)
				)
				(pin passive line
					(at 0 -25.4 0)
					(length 5.08)
					(hide yes)
					(name "GND"
						(effects
							(font
								(size 1.27 1.27)
							)
						)
					)
					(number "T4"
						(effects
							(font
								(size 1.27 1.27)
							)
						)
					)
				)
				(pin passive line
					(at 0 -25.4 0)
					(length 5.08)
					(hide yes)
					(name "GND"
						(effects
							(font
								(size 1.27 1.27)
							)
						)
					)
					(number "T8"
						(effects
							(font
								(size 1.27 1.27)
							)
						)
					)
				)
				(pin passive line
					(at 0 -25.4 0)
					(length 5.08)
					(hide yes)
					(name "GND"
						(effects
							(font
								(size 1.27 1.27)
							)
						)
					)
					(number "U1"
						(effects
							(font
								(size 1.27 1.27)
							)
						)
					)
				)
				(pin passive line
					(at 0 -25.4 0)
					(length 5.08)
					(hide yes)
					(name "GND"
						(effects
							(font
								(size 1.27 1.27)
							)
						)
					)
					(number "U11"
						(effects
							(font
								(size 1.27 1.27)
							)
						)
					)
				)
				(pin passive line
					(at 0 -25.4 0)
					(length 5.08)
					(hide yes)
					(name "GND"
						(effects
							(font
								(size 1.27 1.27)
							)
						)
					)
					(number "U13"
						(effects
							(font
								(size 1.27 1.27)
							)
						)
					)
				)
				(pin passive line
					(at 0 -25.4 0)
					(length 5.08)
					(hide yes)
					(name "GND"
						(effects
							(font
								(size 1.27 1.27)
							)
						)
					)
					(number "U15"
						(effects
							(font
								(size 1.27 1.27)
							)
						)
					)
				)
				(pin passive line
					(at 0 -25.4 0)
					(length 5.08)
					(hide yes)
					(name "GND"
						(effects
							(font
								(size 1.27 1.27)
							)
						)
					)
					(number "U17"
						(effects
							(font
								(size 1.27 1.27)
							)
						)
					)
				)
				(pin passive line
					(at 0 -25.4 0)
					(length 5.08)
					(hide yes)
					(name "GND"
						(effects
							(font
								(size 1.27 1.27)
							)
						)
					)
					(number "U18"
						(effects
							(font
								(size 1.27 1.27)
							)
						)
					)
				)
				(pin passive line
					(at 0 -25.4 0)
					(length 5.08)
					(hide yes)
					(name "GND"
						(effects
							(font
								(size 1.27 1.27)
							)
						)
					)
					(number "U2"
						(effects
							(font
								(size 1.27 1.27)
							)
						)
					)
				)
				(pin passive line
					(at 0 -25.4 0)
					(length 5.08)
					(hide yes)
					(name "GND"
						(effects
							(font
								(size 1.27 1.27)
							)
						)
					)
					(number "U3"
						(effects
							(font
								(size 1.27 1.27)
							)
						)
					)
				)
				(pin passive line
					(at 0 -25.4 0)
					(length 5.08)
					(hide yes)
					(name "GND"
						(effects
							(font
								(size 1.27 1.27)
							)
						)
					)
					(number "U6"
						(effects
							(font
								(size 1.27 1.27)
							)
						)
					)
				)
				(pin passive line
					(at 0 -25.4 0)
					(length 5.08)
					(hide yes)
					(name "GND"
						(effects
							(font
								(size 1.27 1.27)
							)
						)
					)
					(number "U8"
						(effects
							(font
								(size 1.27 1.27)
							)
						)
					)
				)
				(pin passive line
					(at 0 -25.4 0)
					(length 5.08)
					(hide yes)
					(name "GND"
						(effects
							(font
								(size 1.27 1.27)
							)
						)
					)
					(number "V10"
						(effects
							(font
								(size 1.27 1.27)
							)
						)
					)
				)
				(pin passive line
					(at 0 -25.4 0)
					(length 5.08)
					(hide yes)
					(name "GND"
						(effects
							(font
								(size 1.27 1.27)
							)
						)
					)
					(number "V12"
						(effects
							(font
								(size 1.27 1.27)
							)
						)
					)
				)
				(pin passive line
					(at 0 -25.4 0)
					(length 5.08)
					(hide yes)
					(name "GND"
						(effects
							(font
								(size 1.27 1.27)
							)
						)
					)
					(number "V14"
						(effects
							(font
								(size 1.27 1.27)
							)
						)
					)
				)
				(pin passive line
					(at 0 -25.4 0)
					(length 5.08)
					(hide yes)
					(name "GND"
						(effects
							(font
								(size 1.27 1.27)
							)
						)
					)
					(number "V16"
						(effects
							(font
								(size 1.27 1.27)
							)
						)
					)
				)
				(pin passive line
					(at 0 -25.4 0)
					(length 5.08)
					(hide yes)
					(name "GND"
						(effects
							(font
								(size 1.27 1.27)
							)
						)
					)
					(number "V20"
						(effects
							(font
								(size 1.27 1.27)
							)
						)
					)
				)
				(pin passive line
					(at 0 -25.4 0)
					(length 5.08)
					(hide yes)
					(name "GND"
						(effects
							(font
								(size 1.27 1.27)
							)
						)
					)
					(number "V25"
						(effects
							(font
								(size 1.27 1.27)
							)
						)
					)
				)
				(pin passive line
					(at 0 -25.4 0)
					(length 5.08)
					(hide yes)
					(name "GND"
						(effects
							(font
								(size 1.27 1.27)
							)
						)
					)
					(number "V3"
						(effects
							(font
								(size 1.27 1.27)
							)
						)
					)
				)
				(pin passive line
					(at 0 -25.4 0)
					(length 5.08)
					(hide yes)
					(name "GND"
						(effects
							(font
								(size 1.27 1.27)
							)
						)
					)
					(number "V4"
						(effects
							(font
								(size 1.27 1.27)
							)
						)
					)
				)
				(pin passive line
					(at 0 -25.4 0)
					(length 5.08)
					(hide yes)
					(name "GND"
						(effects
							(font
								(size 1.27 1.27)
							)
						)
					)
					(number "V8"
						(effects
							(font
								(size 1.27 1.27)
							)
						)
					)
				)
				(pin passive line
					(at 0 -25.4 0)
					(length 5.08)
					(hide yes)
					(name "GND"
						(effects
							(font
								(size 1.27 1.27)
							)
						)
					)
					(number "W1"
						(effects
							(font
								(size 1.27 1.27)
							)
						)
					)
				)
				(pin passive line
					(at 0 -25.4 0)
					(length 5.08)
					(hide yes)
					(name "GND"
						(effects
							(font
								(size 1.27 1.27)
							)
						)
					)
					(number "W17"
						(effects
							(font
								(size 1.27 1.27)
							)
						)
					)
				)
				(pin passive line
					(at 0 -25.4 0)
					(length 5.08)
					(hide yes)
					(name "GND"
						(effects
							(font
								(size 1.27 1.27)
							)
						)
					)
					(number "W2"
						(effects
							(font
								(size 1.27 1.27)
							)
						)
					)
				)
				(pin passive line
					(at 0 -25.4 0)
					(length 5.08)
					(hide yes)
					(name "GND"
						(effects
							(font
								(size 1.27 1.27)
							)
						)
					)
					(number "W22"
						(effects
							(font
								(size 1.27 1.27)
							)
						)
					)
				)
				(pin passive line
					(at 0 -25.4 0)
					(length 5.08)
					(hide yes)
					(name "GND"
						(effects
							(font
								(size 1.27 1.27)
							)
						)
					)
					(number "W3"
						(effects
							(font
								(size 1.27 1.27)
							)
						)
					)
				)
				(pin passive line
					(at 0 -25.4 0)
					(length 5.08)
					(hide yes)
					(name "GND"
						(effects
							(font
								(size 1.27 1.27)
							)
						)
					)
					(number "W6"
						(effects
							(font
								(size 1.27 1.27)
							)
						)
					)
				)
				(pin passive line
					(at 0 -25.4 0)
					(length 5.08)
					(hide yes)
					(name "GND"
						(effects
							(font
								(size 1.27 1.27)
							)
						)
					)
					(number "W8"
						(effects
							(font
								(size 1.27 1.27)
							)
						)
					)
				)
				(pin passive line
					(at 0 -25.4 0)
					(length 5.08)
					(hide yes)
					(name "GND"
						(effects
							(font
								(size 1.27 1.27)
							)
						)
					)
					(number "Y19"
						(effects
							(font
								(size 1.27 1.27)
							)
						)
					)
				)
				(pin passive line
					(at 0 -25.4 0)
					(length 5.08)
					(hide yes)
					(name "GND"
						(effects
							(font
								(size 1.27 1.27)
							)
						)
					)
					(number "Y3"
						(effects
							(font
								(size 1.27 1.27)
							)
						)
					)
				)
				(pin passive line
					(at 0 -25.4 0)
					(length 5.08)
					(hide yes)
					(name "GND"
						(effects
							(font
								(size 1.27 1.27)
							)
						)
					)
					(number "Y4"
						(effects
							(font
								(size 1.27 1.27)
							)
						)
					)
				)
				(pin passive line
					(at 0 -25.4 0)
					(length 5.08)
					(hide yes)
					(name "GND"
						(effects
							(font
								(size 1.27 1.27)
							)
						)
					)
					(number "Y8"
						(effects
							(font
								(size 1.27 1.27)
							)
						)
					)
				)
				(pin no_connect line
					(at 7.62 2.54 270)
					(length 5.08)
					(hide yes)
					(name "NC"
						(effects
							(font
								(size 1.27 1.27)
							)
						)
					)
					(number "B2"
						(effects
							(font
								(size 1.27 1.27)
							)
						)
					)
				)
				(pin no_connect line
					(at 10.16 2.54 270)
					(length 5.08)
					(hide yes)
					(name "NC"
						(effects
							(font
								(size 1.27 1.27)
							)
						)
					)
					(number "C4"
						(effects
							(font
								(size 1.27 1.27)
							)
						)
					)
				)
				(pin no_connect line
					(at 10.16 -27.94 90)
					(length 5.08)
					(hide yes)
					(name "NC"
						(effects
							(font
								(size 1.27 1.27)
							)
						)
					)
					(number "A4"
						(effects
							(font
								(size 1.27 1.27)
							)
						)
					)
				)
				(pin no_connect line
					(at 12.7 2.54 270)
					(length 5.08)
					(hide yes)
					(name "NC"
						(effects
							(font
								(size 1.27 1.27)
							)
						)
					)
					(number "D2"
						(effects
							(font
								(size 1.27 1.27)
							)
						)
					)
				)
				(pin no_connect line
					(at 12.7 -27.94 90)
					(length 5.08)
					(hide yes)
					(name "NC"
						(effects
							(font
								(size 1.27 1.27)
							)
						)
					)
					(number "F6"
						(effects
							(font
								(size 1.27 1.27)
							)
						)
					)
				)
				(pin no_connect line
					(at 15.24 2.54 270)
					(length 5.08)
					(hide yes)
					(name "NC"
						(effects
							(font
								(size 1.27 1.27)
							)
						)
					)
					(number "A3"
						(effects
							(font
								(size 1.27 1.27)
							)
						)
					)
				)
				(pin no_connect line
					(at 15.24 -27.94 90)
					(length 5.08)
					(hide yes)
					(name "NC"
						(effects
							(font
								(size 1.27 1.27)
							)
						)
					)
					(number "E4"
						(effects
							(font
								(size 1.27 1.27)
							)
						)
					)
				)
				(pin no_connect line
					(at 17.78 2.54 270)
					(length 5.08)
					(hide yes)
					(name "NC"
						(effects
							(font
								(size 1.27 1.27)
							)
						)
					)
					(number "B1"
						(effects
							(font
								(size 1.27 1.27)
							)
						)
					)
				)
				(pin no_connect line
					(at 17.78 -27.94 90)
					(length 5.08)
					(hide yes)
					(name "NC"
						(effects
							(font
								(size 1.27 1.27)
							)
						)
					)
					(number "D6"
						(effects
							(font
								(size 1.27 1.27)
							)
						)
					)
				)
				(pin no_connect line
					(at 20.32 2.54 270)
					(length 5.08)
					(hide yes)
					(name "NC"
						(effects
							(font
								(size 1.27 1.27)
							)
						)
					)
					(number "C3"
						(effects
							(font
								(size 1.27 1.27)
							)
						)
					)
				)
				(pin no_connect line
					(at 20.32 -27.94 90)
					(length 5.08)
					(hide yes)
					(name "NC"
						(effects
							(font
								(size 1.27 1.27)
							)
						)
					)
					(number "B6"
						(effects
							(font
								(size 1.27 1.27)
							)
						)
					)
				)
				(pin no_connect line
					(at 22.86 2.54 270)
					(length 5.08)
					(hide yes)
					(name "NC"
						(effects
							(font
								(size 1.27 1.27)
							)
						)
					)
					(number "D1"
						(effects
							(font
								(size 1.27 1.27)
							)
						)
					)
				)
				(pin no_connect line
					(at 22.86 -27.94 90)
					(length 5.08)
					(hide yes)
					(name "NC"
						(effects
							(font
								(size 1.27 1.27)
							)
						)
					)
					(number "F7"
						(effects
							(font
								(size 1.27 1.27)
							)
						)
					)
				)
				(pin no_connect line
					(at 25.4 2.54 270)
					(length 5.08)
					(hide yes)
					(name "NC"
						(effects
							(font
								(size 1.27 1.27)
							)
						)
					)
					(number "H7"
						(effects
							(font
								(size 1.27 1.27)
							)
						)
					)
				)
				(pin no_connect line
					(at 25.4 -27.94 90)
					(length 5.08)
					(hide yes)
					(name "NC"
						(effects
							(font
								(size 1.27 1.27)
							)
						)
					)
					(number "E5"
						(effects
							(font
								(size 1.27 1.27)
							)
						)
					)
				)
				(pin no_connect line
					(at 27.94 2.54 270)
					(length 5.08)
					(hide yes)
					(name "NC"
						(effects
							(font
								(size 1.27 1.27)
							)
						)
					)
					(number "H6"
						(effects
							(font
								(size 1.27 1.27)
							)
						)
					)
				)
				(pin no_connect line
					(at 27.94 -27.94 90)
					(length 5.08)
					(hide yes)
					(name "NC"
						(effects
							(font
								(size 1.27 1.27)
							)
						)
					)
					(number "D7"
						(effects
							(font
								(size 1.27 1.27)
							)
						)
					)
				)
				(pin no_connect line
					(at 30.48 2.54 270)
					(length 5.08)
					(hide yes)
					(name "NC"
						(effects
							(font
								(size 1.27 1.27)
							)
						)
					)
					(number "K7"
						(effects
							(font
								(size 1.27 1.27)
							)
						)
					)
				)
				(pin no_connect line
					(at 30.48 -27.94 90)
					(length 5.08)
					(hide yes)
					(name "NC"
						(effects
							(font
								(size 1.27 1.27)
							)
						)
					)
					(number "B7"
						(effects
							(font
								(size 1.27 1.27)
							)
						)
					)
				)
				(pin no_connect line
					(at 33.02 2.54 270)
					(length 5.08)
					(hide yes)
					(name "NC"
						(effects
							(font
								(size 1.27 1.27)
							)
						)
					)
					(number "K6"
						(effects
							(font
								(size 1.27 1.27)
							)
						)
					)
				)
				(pin power_in line
					(at 40.64 0 180)
					(length 5.08)
					(name "VCCINT"
						(effects
							(font
								(size 1.27 1.27)
							)
						)
					)
					(number "K11"
						(effects
							(font
								(size 1.27 1.27)
							)
						)
					)
				)
				(pin passive line
					(at 40.64 0 180)
					(length 5.08)
					(hide yes)
					(name "VCCINT"
						(effects
							(font
								(size 1.27 1.27)
							)
						)
					)
					(number "K13"
						(effects
							(font
								(size 1.27 1.27)
							)
						)
					)
				)
				(pin passive line
					(at 40.64 0 180)
					(length 5.08)
					(hide yes)
					(name "VCCINT"
						(effects
							(font
								(size 1.27 1.27)
							)
						)
					)
					(number "K15"
						(effects
							(font
								(size 1.27 1.27)
							)
						)
					)
				)
				(pin passive line
					(at 40.64 0 180)
					(length 5.08)
					(hide yes)
					(name "VCCINT"
						(effects
							(font
								(size 1.27 1.27)
							)
						)
					)
					(number "K17"
						(effects
							(font
								(size 1.27 1.27)
							)
						)
					)
				)
				(pin passive line
					(at 40.64 0 180)
					(length 5.08)
					(hide yes)
					(name "VCCINT"
						(effects
							(font
								(size 1.27 1.27)
							)
						)
					)
					(number "L10"
						(effects
							(font
								(size 1.27 1.27)
							)
						)
					)
				)
				(pin passive line
					(at 40.64 0 180)
					(length 5.08)
					(hide yes)
					(name "VCCINT"
						(effects
							(font
								(size 1.27 1.27)
							)
						)
					)
					(number "L12"
						(effects
							(font
								(size 1.27 1.27)
							)
						)
					)
				)
				(pin passive line
					(at 40.64 0 180)
					(length 5.08)
					(hide yes)
					(name "VCCINT"
						(effects
							(font
								(size 1.27 1.27)
							)
						)
					)
					(number "L14"
						(effects
							(font
								(size 1.27 1.27)
							)
						)
					)
				)
				(pin passive line
					(at 40.64 0 180)
					(length 5.08)
					(hide yes)
					(name "VCCINT"
						(effects
							(font
								(size 1.27 1.27)
							)
						)
					)
					(number "L16"
						(effects
							(font
								(size 1.27 1.27)
							)
						)
					)
				)
				(pin passive line
					(at 40.64 0 180)
					(length 5.08)
					(hide yes)
					(name "VCCINT"
						(effects
							(font
								(size 1.27 1.27)
							)
						)
					)
					(number "M11"
						(effects
							(font
								(size 1.27 1.27)
							)
						)
					)
				)
				(pin passive line
					(at 40.64 0 180)
					(length 5.08)
					(hide yes)
					(name "VCCINT"
						(effects
							(font
								(size 1.27 1.27)
							)
						)
					)
					(number "M13"
						(effects
							(font
								(size 1.27 1.27)
							)
						)
					)
				)
				(pin passive line
					(at 40.64 0 180)
					(length 5.08)
					(hide yes)
					(name "VCCINT"
						(effects
							(font
								(size 1.27 1.27)
							)
						)
					)
					(number "M15"
						(effects
							(font
								(size 1.27 1.27)
							)
						)
					)
				)
				(pin passive line
					(at 40.64 0 180)
					(length 5.08)
					(hide yes)
					(name "VCCINT"
						(effects
							(font
								(size 1.27 1.27)
							)
						)
					)
					(number "M17"
						(effects
							(font
								(size 1.27 1.27)
							)
						)
					)
				)
				(pin passive line
					(at 40.64 0 180)
					(length 5.08)
					(hide yes)
					(name "VCCINT"
						(effects
							(font
								(size 1.27 1.27)
							)
						)
					)
					(number "N10"
						(effects
							(font
								(size 1.27 1.27)
							)
						)
					)
				)
				(pin passive line
					(at 40.64 0 180)
					(length 5.08)
					(hide yes)
					(name "VCCINT"
						(effects
							(font
								(size 1.27 1.27)
							)
						)
					)
					(number "N12"
						(effects
							(font
								(size 1.27 1.27)
							)
						)
					)
				)
				(pin passive line
					(at 40.64 0 180)
					(length 5.08)
					(hide yes)
					(name "VCCINT"
						(effects
							(font
								(size 1.27 1.27)
							)
						)
					)
					(number "N16"
						(effects
							(font
								(size 1.27 1.27)
							)
						)
					)
				)
				(pin passive line
					(at 40.64 0 180)
					(length 5.08)
					(hide yes)
					(name "VCCINT"
						(effects
							(font
								(size 1.27 1.27)
							)
						)
					)
					(number "P11"
						(effects
							(font
								(size 1.27 1.27)
							)
						)
					)
				)
				(pin passive line
					(at 40.64 0 180)
					(length 5.08)
					(hide yes)
					(name "VCCINT"
						(effects
							(font
								(size 1.27 1.27)
							)
						)
					)
					(number "P15"
						(effects
							(font
								(size 1.27 1.27)
							)
						)
					)
				)
				(pin passive line
					(at 40.64 0 180)
					(length 5.08)
					(hide yes)
					(name "VCCINT"
						(effects
							(font
								(size 1.27 1.27)
							)
						)
					)
					(number "P17"
						(effects
							(font
								(size 1.27 1.27)
							)
						)
					)
				)
				(pin passive line
					(at 40.64 0 180)
					(length 5.08)
					(hide yes)
					(name "VCCINT"
						(effects
							(font
								(size 1.27 1.27)
							)
						)
					)
					(number "R10"
						(effects
							(font
								(size 1.27 1.27)
							)
						)
					)
				)
				(pin passive line
					(at 40.64 0 180)
					(length 5.08)
					(hide yes)
					(name "VCCINT"
						(effects
							(font
								(size 1.27 1.27)
							)
						)
					)
					(number "R12"
						(effects
							(font
								(size 1.27 1.27)
							)
						)
					)
				)
				(pin passive line
					(at 40.64 0 180)
					(length 5.08)
					(hide yes)
					(name "VCCINT"
						(effects
							(font
								(size 1.27 1.27)
							)
						)
					)
					(number "R16"
						(effects
							(font
								(size 1.27 1.27)
							)
						)
					)
				)
				(pin passive line
					(at 40.64 0 180)
					(length 5.08)
					(hide yes)
					(name "VCCINT"
						(effects
							(font
								(size 1.27 1.27)
							)
						)
					)
					(number "T11"
						(effects
							(font
								(size 1.27 1.27)
							)
						)
					)
				)
				(pin passive line
					(at 40.64 0 180)
					(length 5.08)
					(hide yes)
					(name "VCCINT"
						(effects
							(font
								(size 1.27 1.27)
							)
						)
					)
					(number "T15"
						(effects
							(font
								(size 1.27 1.27)
							)
						)
					)
				)
				(pin passive line
					(at 40.64 0 180)
					(length 5.08)
					(hide yes)
					(name "VCCINT"
						(effects
							(font
								(size 1.27 1.27)
							)
						)
					)
					(number "T17"
						(effects
							(font
								(size 1.27 1.27)
							)
						)
					)
				)
				(pin passive line
					(at 40.64 0 180)
					(length 5.08)
					(hide yes)
					(name "VCCINT"
						(effects
							(font
								(size 1.27 1.27)
							)
						)
					)
					(number "U10"
						(effects
							(font
								(size 1.27 1.27)
							)
						)
					)
				)
				(pin passive line
					(at 40.64 0 180)
					(length 5.08)
					(hide yes)
					(name "VCCINT"
						(effects
							(font
								(size 1.27 1.27)
							)
						)
					)
					(number "U12"
						(effects
							(font
								(size 1.27 1.27)
							)
						)
					)
				)
				(pin passive line
					(at 40.64 0 180)
					(length 5.08)
					(hide yes)
					(name "VCCINT"
						(effects
							(font
								(size 1.27 1.27)
							)
						)
					)
					(number "U14"
						(effects
							(font
								(size 1.27 1.27)
							)
						)
					)
				)
				(pin passive line
					(at 40.64 0 180)
					(length 5.08)
					(hide yes)
					(name "VCCINT"
						(effects
							(font
								(size 1.27 1.27)
							)
						)
					)
					(number "U16"
						(effects
							(font
								(size 1.27 1.27)
							)
						)
					)
				)
				(pin passive line
					(at 40.64 0 180)
					(length 5.08)
					(hide yes)
					(name "VCCINT"
						(effects
							(font
								(size 1.27 1.27)
							)
						)
					)
					(number "V11"
						(effects
							(font
								(size 1.27 1.27)
							)
						)
					)
				)
				(pin passive line
					(at 40.64 0 180)
					(length 5.08)
					(hide yes)
					(name "VCCINT"
						(effects
							(font
								(size 1.27 1.27)
							)
						)
					)
					(number "V13"
						(effects
							(font
								(size 1.27 1.27)
							)
						)
					)
				)
				(pin passive line
					(at 40.64 0 180)
					(length 5.08)
					(hide yes)
					(name "VCCINT"
						(effects
							(font
								(size 1.27 1.27)
							)
						)
					)
					(number "V15"
						(effects
							(font
								(size 1.27 1.27)
							)
						)
					)
				)
				(pin passive line
					(at 40.64 0 180)
					(length 5.08)
					(hide yes)
					(name "VCCINT"
						(effects
							(font
								(size 1.27 1.27)
							)
						)
					)
					(number "V17"
						(effects
							(font
								(size 1.27 1.27)
							)
						)
					)
				)
				(pin power_in line
					(at 40.64 -2.54 180)
					(length 5.08)
					(name "VCCINT_IO"
						(effects
							(font
								(size 1.27 1.27)
							)
						)
					)
					(number "L9"
						(effects
							(font
								(size 1.27 1.27)
							)
						)
					)
				)
				(pin passive line
					(at 40.64 -2.54 180)
					(length 5.08)
					(hide yes)
					(name "VCCINT_IO"
						(effects
							(font
								(size 1.27 1.27)
							)
						)
					)
					(number "M9"
						(effects
							(font
								(size 1.27 1.27)
							)
						)
					)
				)
				(pin passive line
					(at 40.64 -2.54 180)
					(length 5.08)
					(hide yes)
					(name "VCCINT_IO"
						(effects
							(font
								(size 1.27 1.27)
							)
						)
					)
					(number "N9"
						(effects
							(font
								(size 1.27 1.27)
							)
						)
					)
				)
				(pin passive line
					(at 40.64 -2.54 180)
					(length 5.08)
					(hide yes)
					(name "VCCINT_IO"
						(effects
							(font
								(size 1.27 1.27)
							)
						)
					)
					(number "P9"
						(effects
							(font
								(size 1.27 1.27)
							)
						)
					)
				)
				(pin power_in line
					(at 40.64 -7.62 180)
					(length 5.08)
					(name "VCCAUX"
						(effects
							(font
								(size 1.27 1.27)
							)
						)
					)
					(number "M18"
						(effects
							(font
								(size 1.27 1.27)
							)
						)
					)
				)
				(pin passive line
					(at 40.64 -7.62 180)
					(length 5.08)
					(hide yes)
					(name "VCCAUX"
						(effects
							(font
								(size 1.27 1.27)
							)
						)
					)
					(number "N18"
						(effects
							(font
								(size 1.27 1.27)
							)
						)
					)
				)
				(pin power_in line
					(at 40.64 -10.16 180)
					(length 5.08)
					(name "VCCAUX_IO"
						(effects
							(font
								(size 1.27 1.27)
							)
						)
					)
					(number "P18"
						(effects
							(font
								(size 1.27 1.27)
							)
						)
					)
				)
				(pin passive line
					(at 40.64 -10.16 180)
					(length 5.08)
					(hide yes)
					(name "VCCAUX_IO"
						(effects
							(font
								(size 1.27 1.27)
							)
						)
					)
					(number "R18"
						(effects
							(font
								(size 1.27 1.27)
							)
						)
					)
				)
				(pin passive line
					(at 40.64 -10.16 180)
					(length 5.08)
					(hide yes)
					(name "VCCAUX_IO"
						(effects
							(font
								(size 1.27 1.27)
							)
						)
					)
					(number "T18"
						(effects
							(font
								(size 1.27 1.27)
							)
						)
					)
				)
				(pin power_in line
					(at 40.64 -15.24 180)
					(length 5.08)
					(name "VCCBRAM"
						(effects
							(font
								(size 1.27 1.27)
							)
						)
					)
					(number "R9"
						(effects
							(font
								(size 1.27 1.27)
							)
						)
					)
				)
				(pin passive line
					(at 40.64 -15.24 180)
					(length 5.08)
					(hide yes)
					(name "VCCBRAM"
						(effects
							(font
								(size 1.27 1.27)
							)
						)
					)
					(number "T9"
						(effects
							(font
								(size 1.27 1.27)
							)
						)
					)
				)
				(pin passive line
					(at 40.64 -15.24 180)
					(length 5.08)
					(hide yes)
					(name "VCCBRAM"
						(effects
							(font
								(size 1.27 1.27)
							)
						)
					)
					(number "U9"
						(effects
							(font
								(size 1.27 1.27)
							)
						)
					)
				)
				(pin passive line
					(at 40.64 -15.24 180)
					(length 5.08)
					(hide yes)
					(name "VCCBRAM"
						(effects
							(font
								(size 1.27 1.27)
							)
						)
					)
					(number "V9"
						(effects
							(font
								(size 1.27 1.27)
							)
						)
					)
				)
				(pin power_in line
					(at 40.64 -20.32 180)
					(length 5.08)
					(name "VCCADC"
						(effects
							(font
								(size 1.27 1.27)
							)
						)
					)
					(number "N14"
						(effects
							(font
								(size 1.27 1.27)
							)
						)
					)
				)
				(pin power_in line
					(at 40.64 -25.4 180)
					(length 5.08)
					(name "VBATT"
						(effects
							(font
								(size 1.27 1.27)
							)
						)
					)
					(number "Y9"
						(effects
							(font
								(size 1.27 1.27)
							)
						)
					)
				)
			)
		)
	(symbol "XCAU25P-2FFVB676I_3"
			(exclude_from_sim no)
			(in_bom yes)
			(on_board yes)
			(property "Reference" "U"
				(at 63.5 0 0)
				(effects
					(font
						(size 1.27 1.27)
						(thickness 0.15)
					)
					(justify left bottom)
				)
			)
			(property "Value" "XCAU25P-2FFVB676I"
				(at 63.5 -5.08 0)
				(effects
					(font
						(size 1.27 1.27)
						(thickness 0.15)
					)
					(justify left bottom)
					(hide yes)
				)
			)
			(property "Footprint" "antmicro-footprints:BGA-676_27x27mm_Layout26x26_P1x1mm_FFVB676"
				(at 63.5 -7.62 0)
				(effects
					(font
						(size 1.27 1.27)
						(thickness 0.15)
					)
					(justify left bottom)
					(hide yes)
				)
			)
			(property "Datasheet" "https://docs.xilinx.com/viewer/book-attachment/2PXOpPtpaABIt0fkzeBLnw/hvbsEUaOT0OxFhln7VEVyA"
				(at 63.5 -10.16 0)
				(effects
					(font
						(size 1.27 1.27)
						(thickness 0.15)
					)
					(justify left bottom)
					(hide yes)
				)
			)
			(property "Description" "Artix UltraScale+ Field Programmable Gate Array"
				(at 0 0 0)
				(effects
					(font
						(size 1.27 1.27)
					)
					(hide yes)
				)
			)
			(property "MPN" "XCAU25P-2FFVB676I"
				(at 63.5 -2.54 0)
				(effects
					(font
						(size 1.27 1.27)
						(thickness 0.15)
					)
					(justify left bottom)
				)
			)
			(property "Manufacturer" "AMD-Xilinx"
				(at 63.5 -12.7 0)
				(effects
					(font
						(size 1.27 1.27)
						(thickness 0.15)
					)
					(justify left bottom)
					(hide yes)
				)
			)
			(property "Author" "Antmicro"
				(at 63.5 -15.24 0)
				(effects
					(font
						(size 1.27 1.27)
						(thickness 0.15)
					)
					(justify left bottom)
					(hide yes)
				)
			)
			(property "License" "Apache-2.0"
				(at 63.5 -17.78 0)
				(effects
					(font
						(size 1.27 1.27)
						(thickness 0.15)
					)
					(justify left bottom)
					(hide yes)
				)
			)
			(property "ki_locked" ""
				(at 0 0 0)
				(effects
					(font
						(size 1.27 1.27)
					)
				)
			)
			(property "ki_keywords" "FPGA, LVDS, MIPI, CMOS, BGA, ETHERNET, VIDEO, DSP, BRIDGE"
				(at 0 0 0)
				(effects
					(font
						(size 1.27 1.27)
					)
					(hide yes)
				)
			)
			(symbol "XCAU25P-2FFVB676I_3_1_1"
				(rectangle
					(start 5.08 2.54)
					(end 25.4 -87.63)
					(stroke
						(width 0.254)
						(type default)
					)
					(fill
						(type background)
					)
				)
				(polyline
					(pts
						(xy 15.24 -3.81) (xy 22.86 -3.81) (xy 22.86 -83.82) (xy 15.24 -83.82)
					)
					(stroke
						(width 0.254)
						(type default)
					)
					(fill
						(type background)
					)
				)
				(text "CFG"
					(at 15.24 -3.81 0)
					(effects
						(font
							(size 1.27 1.27)
							(thickness 0.15)
						)
						(justify left bottom)
					)
				)
				(text ""
					(at 50.8 -31.75 0)
					(effects
						(font
							(size 1.27 1.27)
							(thickness 0.15)
						)
						(justify left bottom)
					)
				)
				(text ""
					(at 50.8 -31.75 0)
					(effects
						(font
							(size 1.27 1.27)
							(thickness 0.15)
						)
						(justify left bottom)
					)
				)
				(pin power_in line
					(at 0 0 0)
					(length 5.08)
					(name "VCCO_0"
						(effects
							(font
								(size 1.27 1.27)
							)
						)
					)
					(number "AA11"
						(effects
							(font
								(size 1.27 1.27)
							)
						)
					)
				)
				(pin passive line
					(at 0 0 0)
					(length 5.08)
					(hide yes)
					(name "VCCO_0"
						(effects
							(font
								(size 1.27 1.27)
							)
						)
					)
					(number "AD12"
						(effects
							(font
								(size 1.27 1.27)
							)
						)
					)
				)
				(pin bidirectional line
					(at 0 -5.08 0)
					(length 5.08)
					(name "DONE_0"
						(effects
							(font
								(size 1.27 1.27)
							)
						)
					)
					(number "AB11"
						(effects
							(font
								(size 1.27 1.27)
							)
						)
					)
				)
				(pin bidirectional line
					(at 0 -7.62 0)
					(length 5.08)
					(name "INIT_B_0"
						(effects
							(font
								(size 1.27 1.27)
							)
						)
					)
					(number "W10"
						(effects
							(font
								(size 1.27 1.27)
							)
						)
					)
				)
				(pin input line
					(at 0 -10.16 0)
					(length 5.08)
					(name "PROGRAM_B_0"
						(effects
							(font
								(size 1.27 1.27)
							)
						)
					)
					(number "AB9"
						(effects
							(font
								(size 1.27 1.27)
							)
						)
					)
				)
				(pin bidirectional line
					(at 0 -12.7 0)
					(length 5.08)
					(name "RDWR_FCS_B_0"
						(effects
							(font
								(size 1.27 1.27)
							)
						)
					)
					(number "AA12"
						(effects
							(font
								(size 1.27 1.27)
							)
						)
					)
				)
				(pin bidirectional line
					(at 0 -17.78 0)
					(length 5.08)
					(name "CCLK_0"
						(effects
							(font
								(size 1.27 1.27)
							)
						)
					)
					(number "Y11"
						(effects
							(font
								(size 1.27 1.27)
							)
						)
					)
				)
				(pin input line
					(at 0 -20.32 0)
					(length 5.08)
					(name "M0_0"
						(effects
							(font
								(size 1.27 1.27)
							)
						)
					)
					(number "AA10"
						(effects
							(font
								(size 1.27 1.27)
							)
						)
					)
				)
				(pin input line
					(at 0 -22.86 0)
					(length 5.08)
					(name "M1_0"
						(effects
							(font
								(size 1.27 1.27)
							)
						)
					)
					(number "AA9"
						(effects
							(font
								(size 1.27 1.27)
							)
						)
					)
				)
				(pin input line
					(at 0 -25.4 0)
					(length 5.08)
					(name "M2_0"
						(effects
							(font
								(size 1.27 1.27)
							)
						)
					)
					(number "AF12"
						(effects
							(font
								(size 1.27 1.27)
							)
						)
					)
				)
				(pin input line
					(at 0 -30.48 0)
					(length 5.08)
					(name "TCK_0"
						(effects
							(font
								(size 1.27 1.27)
							)
						)
					)
					(number "AE12"
						(effects
							(font
								(size 1.27 1.27)
							)
						)
					)
				)
				(pin input line
					(at 0 -33.02 0)
					(length 5.08)
					(name "TDI_0"
						(effects
							(font
								(size 1.27 1.27)
							)
						)
					)
					(number "AB12"
						(effects
							(font
								(size 1.27 1.27)
							)
						)
					)
				)
				(pin output line
					(at 0 -35.56 0)
					(length 5.08)
					(name "TDO_0"
						(effects
							(font
								(size 1.27 1.27)
							)
						)
					)
					(number "Y10"
						(effects
							(font
								(size 1.27 1.27)
							)
						)
					)
				)
				(pin input line
					(at 0 -38.1 0)
					(length 5.08)
					(name "TMS_0"
						(effects
							(font
								(size 1.27 1.27)
							)
						)
					)
					(number "AB10"
						(effects
							(font
								(size 1.27 1.27)
							)
						)
					)
				)
				(pin bidirectional line
					(at 0 -43.18 0)
					(length 5.08)
					(name "D00_MOSI_0"
						(effects
							(font
								(size 1.27 1.27)
							)
						)
					)
					(number "AD11"
						(effects
							(font
								(size 1.27 1.27)
							)
						)
					)
				)
				(pin bidirectional line
					(at 0 -45.72 0)
					(length 5.08)
					(name "D01_DIN_0"
						(effects
							(font
								(size 1.27 1.27)
							)
						)
					)
					(number "AC12"
						(effects
							(font
								(size 1.27 1.27)
							)
						)
					)
				)
				(pin bidirectional line
					(at 0 -48.26 0)
					(length 5.08)
					(name "D02_0"
						(effects
							(font
								(size 1.27 1.27)
							)
						)
					)
					(number "AC11"
						(effects
							(font
								(size 1.27 1.27)
							)
						)
					)
				)
				(pin bidirectional line
					(at 0 -50.8 0)
					(length 5.08)
					(name "D03_0"
						(effects
							(font
								(size 1.27 1.27)
							)
						)
					)
					(number "AE11"
						(effects
							(font
								(size 1.27 1.27)
							)
						)
					)
				)
				(pin input line
					(at 0 -55.88 0)
					(length 5.08)
					(name "VP"
						(effects
							(font
								(size 1.27 1.27)
							)
						)
					)
					(number "P14"
						(effects
							(font
								(size 1.27 1.27)
							)
						)
					)
				)
				(pin input line
					(at 0 -58.42 0)
					(length 5.08)
					(name "VN"
						(effects
							(font
								(size 1.27 1.27)
							)
						)
					)
					(number "R13"
						(effects
							(font
								(size 1.27 1.27)
							)
						)
					)
				)
				(pin input line
					(at 0 -63.5 0)
					(length 5.08)
					(name "VREFP"
						(effects
							(font
								(size 1.27 1.27)
							)
						)
					)
					(number "R14"
						(effects
							(font
								(size 1.27 1.27)
							)
						)
					)
				)
				(pin input line
					(at 0 -66.04 0)
					(length 5.08)
					(name "VREFN"
						(effects
							(font
								(size 1.27 1.27)
							)
						)
					)
					(number "P13"
						(effects
							(font
								(size 1.27 1.27)
							)
						)
					)
				)
				(pin passive line
					(at 0 -71.12 0)
					(length 5.08)
					(name "DXP"
						(effects
							(font
								(size 1.27 1.27)
							)
						)
					)
					(number "T14"
						(effects
							(font
								(size 1.27 1.27)
							)
						)
					)
				)
				(pin passive line
					(at 0 -73.66 0)
					(length 5.08)
					(name "DXN"
						(effects
							(font
								(size 1.27 1.27)
							)
						)
					)
					(number "T13"
						(effects
							(font
								(size 1.27 1.27)
							)
						)
					)
				)
				(pin input line
					(at 0 -78.74 0)
					(length 5.08)
					(name "POR_OVERRIDE"
						(effects
							(font
								(size 1.27 1.27)
							)
						)
					)
					(number "Y12"
						(effects
							(font
								(size 1.27 1.27)
							)
						)
					)
				)
				(pin input line
					(at 0 -81.28 0)
					(length 5.08)
					(name "PUDC_B_0"
						(effects
							(font
								(size 1.27 1.27)
							)
						)
					)
					(number "W9"
						(effects
							(font
								(size 1.27 1.27)
							)
						)
					)
				)
			)
			(symbol "XCAU25P-2FFVB676I_3_2_1"
				(rectangle
					(start 5.08 2.54)
					(end 43.18 -142.24)
					(stroke
						(width 0.254)
						(type default)
					)
					(fill
						(type background)
					)
				)
				(polyline
					(pts
						(xy 30.48 -6.35) (xy 39.37 -6.35) (xy 39.37 -138.43) (xy 31.75 -138.43)
					)
					(stroke
						(width 0.254)
						(type default)
					)
					(fill
						(type background)
					)
				)
				(text "BANK 64"
					(at 30.48 -5.08 0)
					(effects
						(font
							(size 1.27 1.27)
							(thickness 0.15)
						)
						(justify left bottom)
					)
				)
				(text ""
					(at 50.8 -31.75 0)
					(effects
						(font
							(size 1.27 1.27)
							(thickness 0.15)
						)
						(justify left bottom)
					)
				)
				(text ""
					(at 50.8 -31.75 0)
					(effects
						(font
							(size 1.27 1.27)
							(thickness 0.15)
						)
						(justify left bottom)
					)
				)
				(pin power_in line
					(at 0 0 0)
					(length 5.08)
					(name "VCCO_64"
						(effects
							(font
								(size 1.27 1.27)
							)
						)
					)
					(number "AA21"
						(effects
							(font
								(size 1.27 1.27)
							)
						)
					)
				)
				(pin passive line
					(at 0 0 0)
					(length 5.08)
					(hide yes)
					(name "VCCO_64"
						(effects
							(font
								(size 1.27 1.27)
							)
						)
					)
					(number "AB18"
						(effects
							(font
								(size 1.27 1.27)
							)
						)
					)
				)
				(pin passive line
					(at 0 0 0)
					(length 5.08)
					(hide yes)
					(name "VCCO_64"
						(effects
							(font
								(size 1.27 1.27)
							)
						)
					)
					(number "AD22"
						(effects
							(font
								(size 1.27 1.27)
							)
						)
					)
				)
				(pin input line
					(at 0 -2.54 0)
					(length 5.08)
					(name "VREF_64"
						(effects
							(font
								(size 1.27 1.27)
							)
						)
					)
					(number "W18"
						(effects
							(font
								(size 1.27 1.27)
							)
						)
					)
				)
				(pin bidirectional line
					(at 0 -7.62 0)
					(length 5.08)
					(name "IO_L1P_T0L_N0_DBC_64"
						(effects
							(font
								(size 1.27 1.27)
							)
						)
					)
					(number "AE25"
						(effects
							(font
								(size 1.27 1.27)
							)
						)
					)
				)
				(pin bidirectional line
					(at 0 -10.16 0)
					(length 5.08)
					(name "IO_L1N_T0L_N1_DBC_64"
						(effects
							(font
								(size 1.27 1.27)
							)
						)
					)
					(number "AE26"
						(effects
							(font
								(size 1.27 1.27)
							)
						)
					)
				)
				(pin bidirectional line
					(at 0 -12.7 0)
					(length 5.08)
					(name "IO_L2P_T0L_N2_64"
						(effects
							(font
								(size 1.27 1.27)
							)
						)
					)
					(number "AB25"
						(effects
							(font
								(size 1.27 1.27)
							)
						)
					)
				)
				(pin bidirectional line
					(at 0 -15.24 0)
					(length 5.08)
					(name "IO_L2N_T0L_N3_64"
						(effects
							(font
								(size 1.27 1.27)
							)
						)
					)
					(number "AB26"
						(effects
							(font
								(size 1.27 1.27)
							)
						)
					)
				)
				(pin bidirectional line
					(at 0 -17.78 0)
					(length 5.08)
					(name "IO_L3P_T0L_N4_AD15P_64"
						(effects
							(font
								(size 1.27 1.27)
							)
						)
					)
					(number "AF24"
						(effects
							(font
								(size 1.27 1.27)
							)
						)
					)
				)
				(pin bidirectional line
					(at 0 -20.32 0)
					(length 5.08)
					(name "IO_L3N_T0L_N5_AD15N_64"
						(effects
							(font
								(size 1.27 1.27)
							)
						)
					)
					(number "AF25"
						(effects
							(font
								(size 1.27 1.27)
							)
						)
					)
				)
				(pin bidirectional line
					(at 0 -22.86 0)
					(length 5.08)
					(name "IO_L4P_T0U_N6_DBC_AD7P_64"
						(effects
							(font
								(size 1.27 1.27)
							)
						)
					)
					(number "AC26"
						(effects
							(font
								(size 1.27 1.27)
							)
						)
					)
				)
				(pin bidirectional line
					(at 0 -25.4 0)
					(length 5.08)
					(name "IO_L4N_T0U_N7_DBC_AD7N_64"
						(effects
							(font
								(size 1.27 1.27)
							)
						)
					)
					(number "AD26"
						(effects
							(font
								(size 1.27 1.27)
							)
						)
					)
				)
				(pin bidirectional line
					(at 0 -27.94 0)
					(length 5.08)
					(name "IO_L5P_T0U_N8_AD14P_64"
						(effects
							(font
								(size 1.27 1.27)
							)
						)
					)
					(number "AD24"
						(effects
							(font
								(size 1.27 1.27)
							)
						)
					)
				)
				(pin bidirectional line
					(at 0 -30.48 0)
					(length 5.08)
					(name "IO_L5N_T0U_N9_AD14N_64"
						(effects
							(font
								(size 1.27 1.27)
							)
						)
					)
					(number "AD25"
						(effects
							(font
								(size 1.27 1.27)
							)
						)
					)
				)
				(pin bidirectional line
					(at 0 -33.02 0)
					(length 5.08)
					(name "IO_L6P_T0U_N10_AD6P_64"
						(effects
							(font
								(size 1.27 1.27)
							)
						)
					)
					(number "AB24"
						(effects
							(font
								(size 1.27 1.27)
							)
						)
					)
				)
				(pin bidirectional line
					(at 0 -35.56 0)
					(length 5.08)
					(name "IO_L6N_T0U_N11_AD6N_64"
						(effects
							(font
								(size 1.27 1.27)
							)
						)
					)
					(number "AC24"
						(effects
							(font
								(size 1.27 1.27)
							)
						)
					)
				)
				(pin bidirectional line
					(at 0 -38.1 0)
					(length 5.08)
					(name "IO_T0U_N12_VRP_64"
						(effects
							(font
								(size 1.27 1.27)
							)
						)
					)
					(number "AF23"
						(effects
							(font
								(size 1.27 1.27)
							)
						)
					)
				)
				(pin bidirectional line
					(at 0 -40.64 0)
					(length 5.08)
					(name "IO_L7P_T1L_N0_QBC_AD13P_64"
						(effects
							(font
								(size 1.27 1.27)
							)
						)
					)
					(number "AE22"
						(effects
							(font
								(size 1.27 1.27)
							)
						)
					)
				)
				(pin bidirectional line
					(at 0 -43.18 0)
					(length 5.08)
					(name "IO_L7N_T1L_N1_QBC_AD13N_64"
						(effects
							(font
								(size 1.27 1.27)
							)
						)
					)
					(number "AF22"
						(effects
							(font
								(size 1.27 1.27)
							)
						)
					)
				)
				(pin bidirectional line
					(at 0 -45.72 0)
					(length 5.08)
					(name "IO_L8P_T1L_N2_AD5P_64"
						(effects
							(font
								(size 1.27 1.27)
							)
						)
					)
					(number "AD23"
						(effects
							(font
								(size 1.27 1.27)
							)
						)
					)
				)
				(pin bidirectional line
					(at 0 -48.26 0)
					(length 5.08)
					(name "IO_L8N_T1L_N3_AD5N_64"
						(effects
							(font
								(size 1.27 1.27)
							)
						)
					)
					(number "AE23"
						(effects
							(font
								(size 1.27 1.27)
							)
						)
					)
				)
				(pin bidirectional line
					(at 0 -50.8 0)
					(length 5.08)
					(name "IO_L9P_T1L_N4_AD12P_64"
						(effects
							(font
								(size 1.27 1.27)
							)
						)
					)
					(number "AC22"
						(effects
							(font
								(size 1.27 1.27)
							)
						)
					)
				)
				(pin bidirectional line
					(at 0 -53.34 0)
					(length 5.08)
					(name "IO_L9N_T1L_N5_AD12N_64"
						(effects
							(font
								(size 1.27 1.27)
							)
						)
					)
					(number "AC23"
						(effects
							(font
								(size 1.27 1.27)
							)
						)
					)
				)
				(pin bidirectional line
					(at 0 -55.88 0)
					(length 5.08)
					(name "IO_L10P_T1U_N6_QBC_AD4P_64"
						(effects
							(font
								(size 1.27 1.27)
							)
						)
					)
					(number "AA22"
						(effects
							(font
								(size 1.27 1.27)
							)
						)
					)
				)
				(pin bidirectional line
					(at 0 -58.42 0)
					(length 5.08)
					(name "IO_L10N_T1U_N7_QBC_AD4N_64"
						(effects
							(font
								(size 1.27 1.27)
							)
						)
					)
					(number "AB22"
						(effects
							(font
								(size 1.27 1.27)
							)
						)
					)
				)
				(pin bidirectional line
					(at 0 -60.96 0)
					(length 5.08)
					(name "IO_L11P_T1U_N8_GC_64"
						(effects
							(font
								(size 1.27 1.27)
							)
						)
					)
					(number "AD21"
						(effects
							(font
								(size 1.27 1.27)
							)
						)
					)
				)
				(pin bidirectional line
					(at 0 -63.5 0)
					(length 5.08)
					(name "IO_L11N_T1U_N9_GC_64"
						(effects
							(font
								(size 1.27 1.27)
							)
						)
					)
					(number "AE21"
						(effects
							(font
								(size 1.27 1.27)
							)
						)
					)
				)
				(pin bidirectional line
					(at 0 -66.04 0)
					(length 5.08)
					(name "IO_L12P_T1U_N10_GC_64"
						(effects
							(font
								(size 1.27 1.27)
							)
						)
					)
					(number "AB21"
						(effects
							(font
								(size 1.27 1.27)
							)
						)
					)
				)
				(pin bidirectional line
					(at 0 -68.58 0)
					(length 5.08)
					(name "IO_L12N_T1U_N11_GC_64"
						(effects
							(font
								(size 1.27 1.27)
							)
						)
					)
					(number "AC21"
						(effects
							(font
								(size 1.27 1.27)
							)
						)
					)
				)
				(pin bidirectional line
					(at 0 -71.12 0)
					(length 5.08)
					(name "IO_T1U_N12_64"
						(effects
							(font
								(size 1.27 1.27)
							)
						)
					)
					(number "AF20"
						(effects
							(font
								(size 1.27 1.27)
							)
						)
					)
				)
				(pin bidirectional line
					(at 0 -73.66 0)
					(length 5.08)
					(name "IO_L13P_T2L_N0_GC_QBC_64"
						(effects
							(font
								(size 1.27 1.27)
							)
						)
					)
					(number "AD20"
						(effects
							(font
								(size 1.27 1.27)
							)
						)
					)
				)
				(pin bidirectional line
					(at 0 -76.2 0)
					(length 5.08)
					(name "IO_L13N_T2L_N1_GC_QBC_64"
						(effects
							(font
								(size 1.27 1.27)
							)
						)
					)
					(number "AE20"
						(effects
							(font
								(size 1.27 1.27)
							)
						)
					)
				)
				(pin bidirectional line
					(at 0 -78.74 0)
					(length 5.08)
					(name "IO_L14P_T2L_N2_GC_64"
						(effects
							(font
								(size 1.27 1.27)
							)
						)
					)
					(number "AC19"
						(effects
							(font
								(size 1.27 1.27)
							)
						)
					)
				)
				(pin bidirectional line
					(at 0 -81.28 0)
					(length 5.08)
					(name "IO_L14N_T2L_N3_GC_64"
						(effects
							(font
								(size 1.27 1.27)
							)
						)
					)
					(number "AD19"
						(effects
							(font
								(size 1.27 1.27)
							)
						)
					)
				)
				(pin bidirectional line
					(at 0 -83.82 0)
					(length 5.08)
					(name "IO_L15P_T2L_N4_AD11P_64"
						(effects
							(font
								(size 1.27 1.27)
							)
						)
					)
					(number "AF18"
						(effects
							(font
								(size 1.27 1.27)
							)
						)
					)
				)
				(pin bidirectional line
					(at 0 -86.36 0)
					(length 5.08)
					(name "IO_L15N_T2L_N5_AD11N_64"
						(effects
							(font
								(size 1.27 1.27)
							)
						)
					)
					(number "AF19"
						(effects
							(font
								(size 1.27 1.27)
							)
						)
					)
				)
				(pin bidirectional line
					(at 0 -88.9 0)
					(length 5.08)
					(name "IO_L16P_T2U_N6_QBC_AD3P_64"
						(effects
							(font
								(size 1.27 1.27)
							)
						)
					)
					(number "AC18"
						(effects
							(font
								(size 1.27 1.27)
							)
						)
					)
				)
				(pin bidirectional line
					(at 0 -91.44 0)
					(length 5.08)
					(name "IO_L16N_T2U_N7_QBC_AD3N_64"
						(effects
							(font
								(size 1.27 1.27)
							)
						)
					)
					(number "AD18"
						(effects
							(font
								(size 1.27 1.27)
							)
						)
					)
				)
				(pin bidirectional line
					(at 0 -93.98 0)
					(length 5.08)
					(name "IO_L17P_T2U_N8_AD10P_64"
						(effects
							(font
								(size 1.27 1.27)
							)
						)
					)
					(number "AE17"
						(effects
							(font
								(size 1.27 1.27)
							)
						)
					)
				)
				(pin bidirectional line
					(at 0 -96.52 0)
					(length 5.08)
					(name "IO_L17N_T2U_N9_AD10N_64"
						(effects
							(font
								(size 1.27 1.27)
							)
						)
					)
					(number "AF17"
						(effects
							(font
								(size 1.27 1.27)
							)
						)
					)
				)
				(pin bidirectional line
					(at 0 -99.06 0)
					(length 5.08)
					(name "IO_L18P_T2U_N10_AD2P_64"
						(effects
							(font
								(size 1.27 1.27)
							)
						)
					)
					(number "AD16"
						(effects
							(font
								(size 1.27 1.27)
							)
						)
					)
				)
				(pin bidirectional line
					(at 0 -101.6 0)
					(length 5.08)
					(name "IO_L18N_T2U_N11_AD2N_64"
						(effects
							(font
								(size 1.27 1.27)
							)
						)
					)
					(number "AE16"
						(effects
							(font
								(size 1.27 1.27)
							)
						)
					)
				)
				(pin bidirectional line
					(at 0 -104.14 0)
					(length 5.08)
					(name "IO_T2U_N12_64"
						(effects
							(font
								(size 1.27 1.27)
							)
						)
					)
					(number "AE18"
						(effects
							(font
								(size 1.27 1.27)
							)
						)
					)
				)
				(pin bidirectional line
					(at 0 -106.68 0)
					(length 5.08)
					(name "IO_L19P_T3L_N0_DBC_AD9P_64"
						(effects
							(font
								(size 1.27 1.27)
							)
						)
					)
					(number "Y20"
						(effects
							(font
								(size 1.27 1.27)
							)
						)
					)
				)
				(pin bidirectional line
					(at 0 -109.22 0)
					(length 5.08)
					(name "IO_L19N_T3L_N1_DBC_AD9N_64"
						(effects
							(font
								(size 1.27 1.27)
							)
						)
					)
					(number "Y21"
						(effects
							(font
								(size 1.27 1.27)
							)
						)
					)
				)
				(pin bidirectional line
					(at 0 -111.76 0)
					(length 5.08)
					(name "IO_L20P_T3L_N2_AD1P_64"
						(effects
							(font
								(size 1.27 1.27)
							)
						)
					)
					(number "AA19"
						(effects
							(font
								(size 1.27 1.27)
							)
						)
					)
				)
				(pin bidirectional line
					(at 0 -114.3 0)
					(length 5.08)
					(name "IO_L20N_T3L_N3_AD1N_64"
						(effects
							(font
								(size 1.27 1.27)
							)
						)
					)
					(number "AB19"
						(effects
							(font
								(size 1.27 1.27)
							)
						)
					)
				)
				(pin bidirectional line
					(at 0 -116.84 0)
					(length 5.08)
					(name "IO_L21P_T3L_N4_AD8P_64"
						(effects
							(font
								(size 1.27 1.27)
							)
						)
					)
					(number "AA20"
						(effects
							(font
								(size 1.27 1.27)
							)
						)
					)
				)
				(pin bidirectional line
					(at 0 -119.38 0)
					(length 5.08)
					(name "IO_L21N_T3L_N5_AD8N_64"
						(effects
							(font
								(size 1.27 1.27)
							)
						)
					)
					(number "AB20"
						(effects
							(font
								(size 1.27 1.27)
							)
						)
					)
				)
				(pin bidirectional line
					(at 0 -121.92 0)
					(length 5.08)
					(name "IO_L22P_T3U_N6_DBC_AD0P_64"
						(effects
							(font
								(size 1.27 1.27)
							)
						)
					)
					(number "AB17"
						(effects
							(font
								(size 1.27 1.27)
							)
						)
					)
				)
				(pin bidirectional line
					(at 0 -124.46 0)
					(length 5.08)
					(name "IO_L22N_T3U_N7_DBC_AD0N_64"
						(effects
							(font
								(size 1.27 1.27)
							)
						)
					)
					(number "AC17"
						(effects
							(font
								(size 1.27 1.27)
							)
						)
					)
				)
				(pin bidirectional line
					(at 0 -127 0)
					(length 5.08)
					(name "IO_L23P_T3U_N8_64"
						(effects
							(font
								(size 1.27 1.27)
							)
						)
					)
					(number "Y17"
						(effects
							(font
								(size 1.27 1.27)
							)
						)
					)
				)
				(pin bidirectional line
					(at 0 -129.54 0)
					(length 5.08)
					(name "IO_L23N_T3U_N9_64"
						(effects
							(font
								(size 1.27 1.27)
							)
						)
					)
					(number "AA17"
						(effects
							(font
								(size 1.27 1.27)
							)
						)
					)
				)
				(pin bidirectional line
					(at 0 -132.08 0)
					(length 5.08)
					(name "IO_L24P_T3U_N10_64"
						(effects
							(font
								(size 1.27 1.27)
							)
						)
					)
					(number "Y18"
						(effects
							(font
								(size 1.27 1.27)
							)
						)
					)
				)
				(pin bidirectional line
					(at 0 -134.62 0)
					(length 5.08)
					(name "IO_L24N_T3U_N11_64"
						(effects
							(font
								(size 1.27 1.27)
							)
						)
					)
					(number "AA18"
						(effects
							(font
								(size 1.27 1.27)
							)
						)
					)
				)
				(pin bidirectional line
					(at 0 -137.16 0)
					(length 5.08)
					(name "IO_T3U_N12_64"
						(effects
							(font
								(size 1.27 1.27)
							)
						)
					)
					(number "AC16"
						(effects
							(font
								(size 1.27 1.27)
							)
						)
					)
				)
			)
			(symbol "XCAU25P-2FFVB676I_3_3_1"
				(rectangle
					(start 5.08 2.54)
					(end 50.8 -142.24)
					(stroke
						(width 0.254)
						(type default)
					)
					(fill
						(type background)
					)
				)
				(polyline
					(pts
						(xy 36.83 -5.08) (xy 44.45 -5.08) (xy 44.45 -138.43) (xy 36.83 -138.43)
					)
					(stroke
						(width 0.254)
						(type default)
					)
					(fill
						(type background)
					)
				)
				(text "BANK 65"
					(at 36.83 -3.81 0)
					(effects
						(font
							(size 1.27 1.27)
							(thickness 0.15)
						)
						(justify left bottom)
					)
				)
				(text ""
					(at 50.8 -31.75 0)
					(effects
						(font
							(size 1.27 1.27)
							(thickness 0.15)
						)
						(justify left bottom)
					)
				)
				(text ""
					(at 50.8 -31.75 0)
					(effects
						(font
							(size 1.27 1.27)
							(thickness 0.15)
						)
						(justify left bottom)
					)
				)
				(pin power_in line
					(at 0 0 0)
					(length 5.08)
					(name "VCCO_65"
						(effects
							(font
								(size 1.27 1.27)
							)
						)
					)
					(number "P22"
						(effects
							(font
								(size 1.27 1.27)
							)
						)
					)
				)
				(pin passive line
					(at 0 0 0)
					(length 5.08)
					(hide yes)
					(name "VCCO_65"
						(effects
							(font
								(size 1.27 1.27)
							)
						)
					)
					(number "U23"
						(effects
							(font
								(size 1.27 1.27)
							)
						)
					)
				)
				(pin passive line
					(at 0 0 0)
					(length 5.08)
					(hide yes)
					(name "VCCO_65"
						(effects
							(font
								(size 1.27 1.27)
							)
						)
					)
					(number "Y24"
						(effects
							(font
								(size 1.27 1.27)
							)
						)
					)
				)
				(pin input line
					(at 0 -2.54 0)
					(length 5.08)
					(name "VREF_65"
						(effects
							(font
								(size 1.27 1.27)
							)
						)
					)
					(number "V18"
						(effects
							(font
								(size 1.27 1.27)
							)
						)
					)
				)
				(pin bidirectional line
					(at 0 -7.62 0)
					(length 5.08)
					(name "IO_L1P_T0L_N0_DBC_RS0_65"
						(effects
							(font
								(size 1.27 1.27)
							)
						)
					)
					(number "U19"
						(effects
							(font
								(size 1.27 1.27)
							)
						)
					)
				)
				(pin bidirectional line
					(at 0 -10.16 0)
					(length 5.08)
					(name "IO_L1N_T0L_N1_DBC_RS1_65"
						(effects
							(font
								(size 1.27 1.27)
							)
						)
					)
					(number "V19"
						(effects
							(font
								(size 1.27 1.27)
							)
						)
					)
				)
				(pin bidirectional line
					(at 0 -12.7 0)
					(length 5.08)
					(name "IO_L2P_T0L_N2_FOE_B_65"
						(effects
							(font
								(size 1.27 1.27)
							)
						)
					)
					(number "U21"
						(effects
							(font
								(size 1.27 1.27)
							)
						)
					)
				)
				(pin bidirectional line
					(at 0 -15.24 0)
					(length 5.08)
					(name "IO_L2N_T0L_N3_FWE_FCS2_B_65"
						(effects
							(font
								(size 1.27 1.27)
							)
						)
					)
					(number "U22"
						(effects
							(font
								(size 1.27 1.27)
							)
						)
					)
				)
				(pin bidirectional line
					(at 0 -17.78 0)
					(length 5.08)
					(name "IO_L3P_T0L_N4_AD15P_A26_65"
						(effects
							(font
								(size 1.27 1.27)
							)
						)
					)
					(number "T20"
						(effects
							(font
								(size 1.27 1.27)
							)
						)
					)
				)
				(pin bidirectional line
					(at 0 -20.32 0)
					(length 5.08)
					(name "IO_L3N_T0L_N5_AD15N_A27_65"
						(effects
							(font
								(size 1.27 1.27)
							)
						)
					)
					(number "U20"
						(effects
							(font
								(size 1.27 1.27)
							)
						)
					)
				)
				(pin bidirectional line
					(at 0 -22.86 0)
					(length 5.08)
					(name "IO_L4P_T0U_N6_DBC_AD7P_A24_65"
						(effects
							(font
								(size 1.27 1.27)
							)
						)
					)
					(number "V21"
						(effects
							(font
								(size 1.27 1.27)
							)
						)
					)
				)
				(pin bidirectional line
					(at 0 -25.4 0)
					(length 5.08)
					(name "IO_L4N_T0U_N7_DBC_AD7N_A25_65"
						(effects
							(font
								(size 1.27 1.27)
							)
						)
					)
					(number "V22"
						(effects
							(font
								(size 1.27 1.27)
							)
						)
					)
				)
				(pin bidirectional line
					(at 0 -27.94 0)
					(length 5.08)
					(name "IO_L5P_T0U_N8_AD14P_A22_65"
						(effects
							(font
								(size 1.27 1.27)
							)
						)
					)
					(number "T22"
						(effects
							(font
								(size 1.27 1.27)
							)
						)
					)
				)
				(pin bidirectional line
					(at 0 -30.48 0)
					(length 5.08)
					(name "IO_L5N_T0U_N9_AD14N_A23_65"
						(effects
							(font
								(size 1.27 1.27)
							)
						)
					)
					(number "T23"
						(effects
							(font
								(size 1.27 1.27)
							)
						)
					)
				)
				(pin bidirectional line
					(at 0 -33.02 0)
					(length 5.08)
					(name "IO_L6P_T0U_N10_AD6P_A20_65"
						(effects
							(font
								(size 1.27 1.27)
							)
						)
					)
					(number "W19"
						(effects
							(font
								(size 1.27 1.27)
							)
						)
					)
				)
				(pin bidirectional line
					(at 0 -35.56 0)
					(length 5.08)
					(name "IO_L6N_T0U_N11_AD6N_A21_65"
						(effects
							(font
								(size 1.27 1.27)
							)
						)
					)
					(number "W20"
						(effects
							(font
								(size 1.27 1.27)
							)
						)
					)
				)
				(pin bidirectional line
					(at 0 -38.1 0)
					(length 5.08)
					(name "IO_T0U_N12_VRP_A28_65"
						(effects
							(font
								(size 1.27 1.27)
							)
						)
					)
					(number "W21"
						(effects
							(font
								(size 1.27 1.27)
							)
						)
					)
				)
				(pin bidirectional line
					(at 0 -40.64 0)
					(length 5.08)
					(name "IO_L7P_T1L_N0_QBC_AD13P_A18_65"
						(effects
							(font
								(size 1.27 1.27)
							)
						)
					)
					(number "Y22"
						(effects
							(font
								(size 1.27 1.27)
							)
						)
					)
				)
				(pin bidirectional line
					(at 0 -43.18 0)
					(length 5.08)
					(name "IO_L7N_T1L_N1_QBC_AD13N_A19_65"
						(effects
							(font
								(size 1.27 1.27)
							)
						)
					)
					(number "Y23"
						(effects
							(font
								(size 1.27 1.27)
							)
						)
					)
				)
				(pin bidirectional line
					(at 0 -45.72 0)
					(length 5.08)
					(name "IO_L8P_T1L_N2_AD5P_A16_65"
						(effects
							(font
								(size 1.27 1.27)
							)
						)
					)
					(number "Y25"
						(effects
							(font
								(size 1.27 1.27)
							)
						)
					)
				)
				(pin bidirectional line
					(at 0 -48.26 0)
					(length 5.08)
					(name "IO_L8N_T1L_N3_AD5N_A17_65"
						(effects
							(font
								(size 1.27 1.27)
							)
						)
					)
					(number "Y26"
						(effects
							(font
								(size 1.27 1.27)
							)
						)
					)
				)
				(pin bidirectional line
					(at 0 -50.8 0)
					(length 5.08)
					(name "IO_L9P_T1L_N4_AD12P_A14_D30_65"
						(effects
							(font
								(size 1.27 1.27)
							)
						)
					)
					(number "AA24"
						(effects
							(font
								(size 1.27 1.27)
							)
						)
					)
				)
				(pin bidirectional line
					(at 0 -53.34 0)
					(length 5.08)
					(name "IO_L9N_T1L_N5_AD12N_A15_D31_65"
						(effects
							(font
								(size 1.27 1.27)
							)
						)
					)
					(number "AA25"
						(effects
							(font
								(size 1.27 1.27)
							)
						)
					)
				)
				(pin bidirectional line
					(at 0 -55.88 0)
					(length 5.08)
					(name "IO_L10P_T1U_N6_QBC_AD4P_A12_D28_65"
						(effects
							(font
								(size 1.27 1.27)
							)
						)
					)
					(number "W25"
						(effects
							(font
								(size 1.27 1.27)
							)
						)
					)
				)
				(pin bidirectional line
					(at 0 -58.42 0)
					(length 5.08)
					(name "IO_L10N_T1U_N7_QBC_AD4N_A13_D29_65"
						(effects
							(font
								(size 1.27 1.27)
							)
						)
					)
					(number "W26"
						(effects
							(font
								(size 1.27 1.27)
							)
						)
					)
				)
				(pin bidirectional line
					(at 0 -60.96 0)
					(length 5.08)
					(name "IO_L11P_T1U_N8_GC_A10_D26_65"
						(effects
							(font
								(size 1.27 1.27)
							)
						)
					)
					(number "V23"
						(effects
							(font
								(size 1.27 1.27)
							)
						)
					)
				)
				(pin bidirectional line
					(at 0 -63.5 0)
					(length 5.08)
					(name "IO_L11N_T1U_N9_GC_A11_D27_65"
						(effects
							(font
								(size 1.27 1.27)
							)
						)
					)
					(number "W23"
						(effects
							(font
								(size 1.27 1.27)
							)
						)
					)
				)
				(pin bidirectional line
					(at 0 -66.04 0)
					(length 5.08)
					(name "IO_L12P_T1U_N10_GC_A08_D24_65"
						(effects
							(font
								(size 1.27 1.27)
							)
						)
					)
					(number "V24"
						(effects
							(font
								(size 1.27 1.27)
							)
						)
					)
				)
				(pin bidirectional line
					(at 0 -68.58 0)
					(length 5.08)
					(name "IO_L12N_T1U_N11_GC_A09_D25_65"
						(effects
							(font
								(size 1.27 1.27)
							)
						)
					)
					(number "W24"
						(effects
							(font
								(size 1.27 1.27)
							)
						)
					)
				)
				(pin bidirectional line
					(at 0 -71.12 0)
					(length 5.08)
					(name "IO_T1U_N12_SMBALERT_65"
						(effects
							(font
								(size 1.27 1.27)
							)
						)
					)
					(number "AA23"
						(effects
							(font
								(size 1.27 1.27)
							)
						)
					)
				)
				(pin bidirectional line
					(at 0 -73.66 0)
					(length 5.08)
					(name "IO_L13P_T2L_N0_GC_QBC_A06_D22_65"
						(effects
							(font
								(size 1.27 1.27)
							)
						)
					)
					(number "T24"
						(effects
							(font
								(size 1.27 1.27)
							)
						)
					)
				)
				(pin bidirectional line
					(at 0 -76.2 0)
					(length 5.08)
					(name "IO_L13N_T2L_N1_GC_QBC_A07_D23_65"
						(effects
							(font
								(size 1.27 1.27)
							)
						)
					)
					(number "U24"
						(effects
							(font
								(size 1.27 1.27)
							)
						)
					)
				)
				(pin bidirectional line
					(at 0 -78.74 0)
					(length 5.08)
					(name "IO_L14P_T2L_N2_GC_A04_D20_65"
						(effects
							(font
								(size 1.27 1.27)
							)
						)
					)
					(number "T25"
						(effects
							(font
								(size 1.27 1.27)
							)
						)
					)
				)
				(pin bidirectional line
					(at 0 -81.28 0)
					(length 5.08)
					(name "IO_L14N_T2L_N3_GC_A05_D21_65"
						(effects
							(font
								(size 1.27 1.27)
							)
						)
					)
					(number "U25"
						(effects
							(font
								(size 1.27 1.27)
							)
						)
					)
				)
				(pin bidirectional line
					(at 0 -83.82 0)
					(length 5.08)
					(name "IO_L15P_T2L_N4_AD11P_A02_D18_65"
						(effects
							(font
								(size 1.27 1.27)
							)
						)
					)
					(number "N24"
						(effects
							(font
								(size 1.27 1.27)
							)
						)
					)
				)
				(pin bidirectional line
					(at 0 -86.36 0)
					(length 5.08)
					(name "IO_L15N_T2L_N5_AD11N_A03_D19_65"
						(effects
							(font
								(size 1.27 1.27)
							)
						)
					)
					(number "P24"
						(effects
							(font
								(size 1.27 1.27)
							)
						)
					)
				)
				(pin bidirectional line
					(at 0 -88.9 0)
					(length 5.08)
					(name "IO_L16P_T2U_N6_QBC_AD3P_A00_D16_65"
						(effects
							(font
								(size 1.27 1.27)
							)
						)
					)
					(number "U26"
						(effects
							(font
								(size 1.27 1.27)
							)
						)
					)
				)
				(pin bidirectional line
					(at 0 -91.44 0)
					(length 5.08)
					(name "IO_L16N_T2U_N7_QBC_AD3N_A01_D17_65"
						(effects
							(font
								(size 1.27 1.27)
							)
						)
					)
					(number "V26"
						(effects
							(font
								(size 1.27 1.27)
							)
						)
					)
				)
				(pin bidirectional line
					(at 0 -93.98 0)
					(length 5.08)
					(name "IO_L17P_T2U_N8_AD10P_D14_65"
						(effects
							(font
								(size 1.27 1.27)
							)
						)
					)
					(number "P25"
						(effects
							(font
								(size 1.27 1.27)
							)
						)
					)
				)
				(pin bidirectional line
					(at 0 -96.52 0)
					(length 5.08)
					(name "IO_L17N_T2U_N9_AD10N_D15_65"
						(effects
							(font
								(size 1.27 1.27)
							)
						)
					)
					(number "P26"
						(effects
							(font
								(size 1.27 1.27)
							)
						)
					)
				)
				(pin bidirectional line
					(at 0 -99.06 0)
					(length 5.08)
					(name "IO_L18P_T2U_N10_AD2P_D12_65"
						(effects
							(font
								(size 1.27 1.27)
							)
						)
					)
					(number "R25"
						(effects
							(font
								(size 1.27 1.27)
							)
						)
					)
				)
				(pin bidirectional line
					(at 0 -101.6 0)
					(length 5.08)
					(name "IO_L18N_T2U_N11_AD2N_D13_65"
						(effects
							(font
								(size 1.27 1.27)
							)
						)
					)
					(number "R26"
						(effects
							(font
								(size 1.27 1.27)
							)
						)
					)
				)
				(pin bidirectional line
					(at 0 -104.14 0)
					(length 5.08)
					(name "IO_T2U_N12_CSI_ADV_B_65"
						(effects
							(font
								(size 1.27 1.27)
							)
						)
					)
					(number "N26"
						(effects
							(font
								(size 1.27 1.27)
							)
						)
					)
				)
				(pin bidirectional line
					(at 0 -106.68 0)
					(length 5.08)
					(name "IO_L19P_T3L_N0_DBC_AD9P_D10_65"
						(effects
							(font
								(size 1.27 1.27)
							)
						)
					)
					(number "R22"
						(effects
							(font
								(size 1.27 1.27)
							)
						)
					)
				)
				(pin bidirectional line
					(at 0 -109.22 0)
					(length 5.08)
					(name "IO_L19N_T3L_N1_DBC_AD9N_D11_65"
						(effects
							(font
								(size 1.27 1.27)
							)
						)
					)
					(number "R23"
						(effects
							(font
								(size 1.27 1.27)
							)
						)
					)
				)
				(pin bidirectional line
					(at 0 -111.76 0)
					(length 5.08)
					(name "IO_L20P_T3L_N2_AD1P_D08_65"
						(effects
							(font
								(size 1.27 1.27)
							)
						)
					)
					(number "P20"
						(effects
							(font
								(size 1.27 1.27)
							)
						)
					)
				)
				(pin bidirectional line
					(at 0 -114.3 0)
					(length 5.08)
					(name "IO_L20N_T3L_N3_AD1N_D09_65"
						(effects
							(font
								(size 1.27 1.27)
							)
						)
					)
					(number "P21"
						(effects
							(font
								(size 1.27 1.27)
							)
						)
					)
				)
				(pin bidirectional line
					(at 0 -116.84 0)
					(length 5.08)
					(name "IO_L21P_T3L_N4_AD8P_D06_65"
						(effects
							(font
								(size 1.27 1.27)
							)
						)
					)
					(number "R20"
						(effects
							(font
								(size 1.27 1.27)
							)
						)
					)
				)
				(pin bidirectional line
					(at 0 -119.38 0)
					(length 5.08)
					(name "IO_L21N_T3L_N5_AD8N_D07_65"
						(effects
							(font
								(size 1.27 1.27)
							)
						)
					)
					(number "R21"
						(effects
							(font
								(size 1.27 1.27)
							)
						)
					)
				)
				(pin bidirectional line
					(at 0 -121.92 0)
					(length 5.08)
					(name "IO_L22P_T3U_N6_DBC_AD0P_D04_65"
						(effects
							(font
								(size 1.27 1.27)
							)
						)
					)
					(number "N23"
						(effects
							(font
								(size 1.27 1.27)
							)
						)
					)
				)
				(pin bidirectional line
					(at 0 -124.46 0)
					(length 5.08)
					(name "IO_L22N_T3U_N7_DBC_AD0N_D05_65"
						(effects
							(font
								(size 1.27 1.27)
							)
						)
					)
					(number "P23"
						(effects
							(font
								(size 1.27 1.27)
							)
						)
					)
				)
				(pin bidirectional line
					(at 0 -127 0)
					(length 5.08)
					(name "IO_L23P_T3U_N8_I2C_SCLK_65"
						(effects
							(font
								(size 1.27 1.27)
							)
						)
					)
					(number "N19"
						(effects
							(font
								(size 1.27 1.27)
							)
						)
					)
				)
				(pin bidirectional line
					(at 0 -129.54 0)
					(length 5.08)
					(name "IO_L23N_T3U_N9_PERSTN1_I2C_SDA_65"
						(effects
							(font
								(size 1.27 1.27)
							)
						)
					)
					(number "P19"
						(effects
							(font
								(size 1.27 1.27)
							)
						)
					)
				)
				(pin bidirectional line
					(at 0 -132.08 0)
					(length 5.08)
					(name "IO_L24P_T3U_N10_EMCCLK_65"
						(effects
							(font
								(size 1.27 1.27)
							)
						)
					)
					(number "N21"
						(effects
							(font
								(size 1.27 1.27)
							)
						)
					)
				)
				(pin bidirectional line
					(at 0 -134.62 0)
					(length 5.08)
					(name "IO_L24N_T3U_N11_DOUT_CSO_B_65"
						(effects
							(font
								(size 1.27 1.27)
							)
						)
					)
					(number "N22"
						(effects
							(font
								(size 1.27 1.27)
							)
						)
					)
				)
				(pin bidirectional line
					(at 0 -137.16 0)
					(length 5.08)
					(name "IO_T3U_N12_PERSTN0_65"
						(effects
							(font
								(size 1.27 1.27)
							)
						)
					)
					(number "T19"
						(effects
							(font
								(size 1.27 1.27)
							)
						)
					)
				)
			)
			(symbol "XCAU25P-2FFVB676I_3_4_1"
				(rectangle
					(start 5.08 2.54)
					(end 43.18 -142.24)
					(stroke
						(width 0.254)
						(type default)
					)
					(fill
						(type background)
					)
				)
				(polyline
					(pts
						(xy 30.48 -6.35) (xy 39.37 -6.35) (xy 39.37 -138.43) (xy 31.75 -138.43)
					)
					(stroke
						(width 0.254)
						(type default)
					)
					(fill
						(type background)
					)
				)
				(text "BANK 66"
					(at 30.48 -5.08 0)
					(effects
						(font
							(size 1.27 1.27)
							(thickness 0.15)
						)
						(justify left bottom)
					)
				)
				(text ""
					(at 50.8 -31.75 0)
					(effects
						(font
							(size 1.27 1.27)
							(thickness 0.15)
						)
						(justify left bottom)
					)
				)
				(text ""
					(at 50.8 -31.75 0)
					(effects
						(font
							(size 1.27 1.27)
							(thickness 0.15)
						)
						(justify left bottom)
					)
				)
				(pin power_in line
					(at 0 0 0)
					(length 5.08)
					(name "VCCO_66"
						(effects
							(font
								(size 1.27 1.27)
							)
						)
					)
					(number "E24"
						(effects
							(font
								(size 1.27 1.27)
							)
						)
					)
				)
				(pin passive line
					(at 0 0 0)
					(length 5.08)
					(hide yes)
					(name "VCCO_66"
						(effects
							(font
								(size 1.27 1.27)
							)
						)
					)
					(number "H25"
						(effects
							(font
								(size 1.27 1.27)
							)
						)
					)
				)
				(pin passive line
					(at 0 0 0)
					(length 5.08)
					(hide yes)
					(name "VCCO_66"
						(effects
							(font
								(size 1.27 1.27)
							)
						)
					)
					(number "J22"
						(effects
							(font
								(size 1.27 1.27)
							)
						)
					)
				)
				(pin input line
					(at 0 -2.54 0)
					(length 5.08)
					(name "VREF_66"
						(effects
							(font
								(size 1.27 1.27)
							)
						)
					)
					(number "J18"
						(effects
							(font
								(size 1.27 1.27)
							)
						)
					)
				)
				(pin bidirectional line
					(at 0 -7.62 0)
					(length 5.08)
					(name "IO_L1P_T0L_N0_DBC_66"
						(effects
							(font
								(size 1.27 1.27)
							)
						)
					)
					(number "L18"
						(effects
							(font
								(size 1.27 1.27)
							)
						)
					)
				)
				(pin bidirectional line
					(at 0 -10.16 0)
					(length 5.08)
					(name "IO_L1N_T0L_N1_DBC_66"
						(effects
							(font
								(size 1.27 1.27)
							)
						)
					)
					(number "K18"
						(effects
							(font
								(size 1.27 1.27)
							)
						)
					)
				)
				(pin bidirectional line
					(at 0 -12.7 0)
					(length 5.08)
					(name "IO_L2P_T0L_N2_66"
						(effects
							(font
								(size 1.27 1.27)
							)
						)
					)
					(number "M20"
						(effects
							(font
								(size 1.27 1.27)
							)
						)
					)
				)
				(pin bidirectional line
					(at 0 -15.24 0)
					(length 5.08)
					(name "IO_L2N_T0L_N3_66"
						(effects
							(font
								(size 1.27 1.27)
							)
						)
					)
					(number "M21"
						(effects
							(font
								(size 1.27 1.27)
							)
						)
					)
				)
				(pin bidirectional line
					(at 0 -17.78 0)
					(length 5.08)
					(name "IO_L3P_T0L_N4_AD15P_66"
						(effects
							(font
								(size 1.27 1.27)
							)
						)
					)
					(number "J19"
						(effects
							(font
								(size 1.27 1.27)
							)
						)
					)
				)
				(pin bidirectional line
					(at 0 -20.32 0)
					(length 5.08)
					(name "IO_L3N_T0L_N5_AD15N_66"
						(effects
							(font
								(size 1.27 1.27)
							)
						)
					)
					(number "J20"
						(effects
							(font
								(size 1.27 1.27)
							)
						)
					)
				)
				(pin bidirectional line
					(at 0 -22.86 0)
					(length 5.08)
					(name "IO_L4P_T0U_N6_DBC_AD7P_66"
						(effects
							(font
								(size 1.27 1.27)
							)
						)
					)
					(number "M19"
						(effects
							(font
								(size 1.27 1.27)
							)
						)
					)
				)
				(pin bidirectional line
					(at 0 -25.4 0)
					(length 5.08)
					(name "IO_L4N_T0U_N7_DBC_AD7N_66"
						(effects
							(font
								(size 1.27 1.27)
							)
						)
					)
					(number "L19"
						(effects
							(font
								(size 1.27 1.27)
							)
						)
					)
				)
				(pin bidirectional line
					(at 0 -27.94 0)
					(length 5.08)
					(name "IO_L5P_T0U_N8_AD14P_66"
						(effects
							(font
								(size 1.27 1.27)
							)
						)
					)
					(number "K21"
						(effects
							(font
								(size 1.27 1.27)
							)
						)
					)
				)
				(pin bidirectional line
					(at 0 -30.48 0)
					(length 5.08)
					(name "IO_L5N_T0U_N9_AD14N_66"
						(effects
							(font
								(size 1.27 1.27)
							)
						)
					)
					(number "J21"
						(effects
							(font
								(size 1.27 1.27)
							)
						)
					)
				)
				(pin bidirectional line
					(at 0 -33.02 0)
					(length 5.08)
					(name "IO_L6P_T0U_N10_AD6P_66"
						(effects
							(font
								(size 1.27 1.27)
							)
						)
					)
					(number "L20"
						(effects
							(font
								(size 1.27 1.27)
							)
						)
					)
				)
				(pin bidirectional line
					(at 0 -35.56 0)
					(length 5.08)
					(name "IO_L6N_T0U_N11_AD6N_66"
						(effects
							(font
								(size 1.27 1.27)
							)
						)
					)
					(number "K20"
						(effects
							(font
								(size 1.27 1.27)
							)
						)
					)
				)
				(pin bidirectional line
					(at 0 -38.1 0)
					(length 5.08)
					(name "IO_T0U_N12_VRP_66"
						(effects
							(font
								(size 1.27 1.27)
							)
						)
					)
					(number "M22"
						(effects
							(font
								(size 1.27 1.27)
							)
						)
					)
				)
				(pin bidirectional line
					(at 0 -40.64 0)
					(length 5.08)
					(name "IO_L7P_T1L_N0_QBC_AD13P_66"
						(effects
							(font
								(size 1.27 1.27)
							)
						)
					)
					(number "L22"
						(effects
							(font
								(size 1.27 1.27)
							)
						)
					)
				)
				(pin bidirectional line
					(at 0 -43.18 0)
					(length 5.08)
					(name "IO_L7N_T1L_N1_QBC_AD13N_66"
						(effects
							(font
								(size 1.27 1.27)
							)
						)
					)
					(number "L23"
						(effects
							(font
								(size 1.27 1.27)
							)
						)
					)
				)
				(pin bidirectional line
					(at 0 -45.72 0)
					(length 5.08)
					(name "IO_L8P_T1L_N2_AD5P_66"
						(effects
							(font
								(size 1.27 1.27)
							)
						)
					)
					(number "M25"
						(effects
							(font
								(size 1.27 1.27)
							)
						)
					)
				)
				(pin bidirectional line
					(at 0 -48.26 0)
					(length 5.08)
					(name "IO_L8N_T1L_N3_AD5N_66"
						(effects
							(font
								(size 1.27 1.27)
							)
						)
					)
					(number "M26"
						(effects
							(font
								(size 1.27 1.27)
							)
						)
					)
				)
				(pin bidirectional line
					(at 0 -50.8 0)
					(length 5.08)
					(name "IO_L9P_T1L_N4_AD12P_66"
						(effects
							(font
								(size 1.27 1.27)
							)
						)
					)
					(number "K25"
						(effects
							(font
								(size 1.27 1.27)
							)
						)
					)
				)
				(pin bidirectional line
					(at 0 -53.34 0)
					(length 5.08)
					(name "IO_L9N_T1L_N5_AD12N_66"
						(effects
							(font
								(size 1.27 1.27)
							)
						)
					)
					(number "K26"
						(effects
							(font
								(size 1.27 1.27)
							)
						)
					)
				)
				(pin bidirectional line
					(at 0 -55.88 0)
					(length 5.08)
					(name "IO_L10P_T1U_N6_QBC_AD4P_66"
						(effects
							(font
								(size 1.27 1.27)
							)
						)
					)
					(number "L24"
						(effects
							(font
								(size 1.27 1.27)
							)
						)
					)
				)
				(pin bidirectional line
					(at 0 -58.42 0)
					(length 5.08)
					(name "IO_L10N_T1U_N7_QBC_AD4N_66"
						(effects
							(font
								(size 1.27 1.27)
							)
						)
					)
					(number "L25"
						(effects
							(font
								(size 1.27 1.27)
							)
						)
					)
				)
				(pin bidirectional line
					(at 0 -60.96 0)
					(length 5.08)
					(name "IO_L11P_T1U_N8_GC_66"
						(effects
							(font
								(size 1.27 1.27)
							)
						)
					)
					(number "K22"
						(effects
							(font
								(size 1.27 1.27)
							)
						)
					)
				)
				(pin bidirectional line
					(at 0 -63.5 0)
					(length 5.08)
					(name "IO_L11N_T1U_N9_GC_66"
						(effects
							(font
								(size 1.27 1.27)
							)
						)
					)
					(number "K23"
						(effects
							(font
								(size 1.27 1.27)
							)
						)
					)
				)
				(pin bidirectional line
					(at 0 -66.04 0)
					(length 5.08)
					(name "IO_L12P_T1U_N10_GC_66"
						(effects
							(font
								(size 1.27 1.27)
							)
						)
					)
					(number "J23"
						(effects
							(font
								(size 1.27 1.27)
							)
						)
					)
				)
				(pin bidirectional line
					(at 0 -68.58 0)
					(length 5.08)
					(name "IO_L12N_T1U_N11_GC_66"
						(effects
							(font
								(size 1.27 1.27)
							)
						)
					)
					(number "J24"
						(effects
							(font
								(size 1.27 1.27)
							)
						)
					)
				)
				(pin bidirectional line
					(at 0 -71.12 0)
					(length 5.08)
					(name "IO_T1U_N12_66"
						(effects
							(font
								(size 1.27 1.27)
							)
						)
					)
					(number "M24"
						(effects
							(font
								(size 1.27 1.27)
							)
						)
					)
				)
				(pin bidirectional line
					(at 0 -73.66 0)
					(length 5.08)
					(name "IO_L13P_T2L_N0_GC_QBC_66"
						(effects
							(font
								(size 1.27 1.27)
							)
						)
					)
					(number "G24"
						(effects
							(font
								(size 1.27 1.27)
							)
						)
					)
				)
				(pin bidirectional line
					(at 0 -76.2 0)
					(length 5.08)
					(name "IO_L13N_T2L_N1_GC_QBC_66"
						(effects
							(font
								(size 1.27 1.27)
							)
						)
					)
					(number "G25"
						(effects
							(font
								(size 1.27 1.27)
							)
						)
					)
				)
				(pin bidirectional line
					(at 0 -78.74 0)
					(length 5.08)
					(name "IO_L14P_T2L_N2_GC_66"
						(effects
							(font
								(size 1.27 1.27)
							)
						)
					)
					(number "H23"
						(effects
							(font
								(size 1.27 1.27)
							)
						)
					)
				)
				(pin bidirectional line
					(at 0 -81.28 0)
					(length 5.08)
					(name "IO_L14N_T2L_N3_GC_66"
						(effects
							(font
								(size 1.27 1.27)
							)
						)
					)
					(number "H24"
						(effects
							(font
								(size 1.27 1.27)
							)
						)
					)
				)
				(pin bidirectional line
					(at 0 -83.82 0)
					(length 5.08)
					(name "IO_L15P_T2L_N4_AD11P_66"
						(effects
							(font
								(size 1.27 1.27)
							)
						)
					)
					(number "J25"
						(effects
							(font
								(size 1.27 1.27)
							)
						)
					)
				)
				(pin bidirectional line
					(at 0 -86.36 0)
					(length 5.08)
					(name "IO_L15N_T2L_N5_AD11N_66"
						(effects
							(font
								(size 1.27 1.27)
							)
						)
					)
					(number "J26"
						(effects
							(font
								(size 1.27 1.27)
							)
						)
					)
				)
				(pin bidirectional line
					(at 0 -88.9 0)
					(length 5.08)
					(name "IO_L16P_T2U_N6_QBC_AD3P_66"
						(effects
							(font
								(size 1.27 1.27)
							)
						)
					)
					(number "F24"
						(effects
							(font
								(size 1.27 1.27)
							)
						)
					)
				)
				(pin bidirectional line
					(at 0 -91.44 0)
					(length 5.08)
					(name "IO_L16N_T2U_N7_QBC_AD3N_66"
						(effects
							(font
								(size 1.27 1.27)
							)
						)
					)
					(number "F25"
						(effects
							(font
								(size 1.27 1.27)
							)
						)
					)
				)
				(pin bidirectional line
					(at 0 -93.98 0)
					(length 5.08)
					(name "IO_L17P_T2U_N8_AD10P_66"
						(effects
							(font
								(size 1.27 1.27)
							)
						)
					)
					(number "H26"
						(effects
							(font
								(size 1.27 1.27)
							)
						)
					)
				)
				(pin bidirectional line
					(at 0 -96.52 0)
					(length 5.08)
					(name "IO_L17N_T2U_N9_AD10N_66"
						(effects
							(font
								(size 1.27 1.27)
							)
						)
					)
					(number "G26"
						(effects
							(font
								(size 1.27 1.27)
							)
						)
					)
				)
				(pin bidirectional line
					(at 0 -99.06 0)
					(length 5.08)
					(name "IO_L18P_T2U_N10_AD2P_66"
						(effects
							(font
								(size 1.27 1.27)
							)
						)
					)
					(number "H21"
						(effects
							(font
								(size 1.27 1.27)
							)
						)
					)
				)
				(pin bidirectional line
					(at 0 -101.6 0)
					(length 5.08)
					(name "IO_L18N_T2U_N11_AD2N_66"
						(effects
							(font
								(size 1.27 1.27)
							)
						)
					)
					(number "H22"
						(effects
							(font
								(size 1.27 1.27)
							)
						)
					)
				)
				(pin bidirectional line
					(at 0 -104.14 0)
					(length 5.08)
					(name "IO_T2U_N12_66"
						(effects
							(font
								(size 1.27 1.27)
							)
						)
					)
					(number "G22"
						(effects
							(font
								(size 1.27 1.27)
							)
						)
					)
				)
				(pin bidirectional line
					(at 0 -106.68 0)
					(length 5.08)
					(name "IO_L19P_T3L_N0_DBC_AD9P_66"
						(effects
							(font
								(size 1.27 1.27)
							)
						)
					)
					(number "E25"
						(effects
							(font
								(size 1.27 1.27)
							)
						)
					)
				)
				(pin bidirectional line
					(at 0 -109.22 0)
					(length 5.08)
					(name "IO_L19N_T3L_N1_DBC_AD9N_66"
						(effects
							(font
								(size 1.27 1.27)
							)
						)
					)
					(number "E26"
						(effects
							(font
								(size 1.27 1.27)
							)
						)
					)
				)
				(pin bidirectional line
					(at 0 -111.76 0)
					(length 5.08)
					(name "IO_L20P_T3L_N2_AD1P_66"
						(effects
							(font
								(size 1.27 1.27)
							)
						)
					)
					(number "F23"
						(effects
							(font
								(size 1.27 1.27)
							)
						)
					)
				)
				(pin bidirectional line
					(at 0 -114.3 0)
					(length 5.08)
					(name "IO_L20N_T3L_N3_AD1N_66"
						(effects
							(font
								(size 1.27 1.27)
							)
						)
					)
					(number "E23"
						(effects
							(font
								(size 1.27 1.27)
							)
						)
					)
				)
				(pin bidirectional line
					(at 0 -116.84 0)
					(length 5.08)
					(name "IO_L21P_T3L_N4_AD8P_66"
						(effects
							(font
								(size 1.27 1.27)
							)
						)
					)
					(number "D24"
						(effects
							(font
								(size 1.27 1.27)
							)
						)
					)
				)
				(pin bidirectional line
					(at 0 -119.38 0)
					(length 5.08)
					(name "IO_L21N_T3L_N5_AD8N_66"
						(effects
							(font
								(size 1.27 1.27)
							)
						)
					)
					(number "D25"
						(effects
							(font
								(size 1.27 1.27)
							)
						)
					)
				)
				(pin bidirectional line
					(at 0 -121.92 0)
					(length 5.08)
					(name "IO_L22P_T3U_N6_DBC_AD0P_66"
						(effects
							(font
								(size 1.27 1.27)
							)
						)
					)
					(number "D23"
						(effects
							(font
								(size 1.27 1.27)
							)
						)
					)
				)
				(pin bidirectional line
					(at 0 -124.46 0)
					(length 5.08)
					(name "IO_L22N_T3U_N7_DBC_AD0N_66"
						(effects
							(font
								(size 1.27 1.27)
							)
						)
					)
					(number "C24"
						(effects
							(font
								(size 1.27 1.27)
							)
						)
					)
				)
				(pin bidirectional line
					(at 0 -127 0)
					(length 5.08)
					(name "IO_L23P_T3U_N8_66"
						(effects
							(font
								(size 1.27 1.27)
							)
						)
					)
					(number "D26"
						(effects
							(font
								(size 1.27 1.27)
							)
						)
					)
				)
				(pin bidirectional line
					(at 0 -129.54 0)
					(length 5.08)
					(name "IO_L23N_T3U_N9_66"
						(effects
							(font
								(size 1.27 1.27)
							)
						)
					)
					(number "C26"
						(effects
							(font
								(size 1.27 1.27)
							)
						)
					)
				)
				(pin bidirectional line
					(at 0 -132.08 0)
					(length 5.08)
					(name "IO_L24P_T3U_N10_66"
						(effects
							(font
								(size 1.27 1.27)
							)
						)
					)
					(number "B25"
						(effects
							(font
								(size 1.27 1.27)
							)
						)
					)
				)
				(pin bidirectional line
					(at 0 -134.62 0)
					(length 5.08)
					(name "IO_L24N_T3U_N11_66"
						(effects
							(font
								(size 1.27 1.27)
							)
						)
					)
					(number "B26"
						(effects
							(font
								(size 1.27 1.27)
							)
						)
					)
				)
				(pin bidirectional line
					(at 0 -137.16 0)
					(length 5.08)
					(name "IO_T3U_N12_66"
						(effects
							(font
								(size 1.27 1.27)
							)
						)
					)
					(number "F22"
						(effects
							(font
								(size 1.27 1.27)
							)
						)
					)
				)
			)
			(symbol "XCAU25P-2FFVB676I_3_5_1"
				(rectangle
					(start 5.08 2.54)
					(end 43.18 -142.24)
					(stroke
						(width 0.254)
						(type default)
					)
					(fill
						(type background)
					)
				)
				(polyline
					(pts
						(xy 30.48 -6.35) (xy 39.37 -6.35) (xy 39.37 -138.43) (xy 31.75 -138.43)
					)
					(stroke
						(width 0.254)
						(type default)
					)
					(fill
						(type background)
					)
				)
				(text "BANK 67"
					(at 30.48 -5.08 0)
					(effects
						(font
							(size 1.27 1.27)
							(thickness 0.15)
						)
						(justify left bottom)
					)
				)
				(text ""
					(at 50.8 -31.75 0)
					(effects
						(font
							(size 1.27 1.27)
							(thickness 0.15)
						)
						(justify left bottom)
					)
				)
				(text ""
					(at 50.8 -31.75 0)
					(effects
						(font
							(size 1.27 1.27)
							(thickness 0.15)
						)
						(justify left bottom)
					)
				)
				(pin power_in line
					(at 0 0 0)
					(length 5.08)
					(name "VCCO_67"
						(effects
							(font
								(size 1.27 1.27)
							)
						)
					)
					(number "C20"
						(effects
							(font
								(size 1.27 1.27)
							)
						)
					)
				)
				(pin passive line
					(at 0 0 0)
					(length 5.08)
					(hide yes)
					(name "VCCO_67"
						(effects
							(font
								(size 1.27 1.27)
							)
						)
					)
					(number "D17"
						(effects
							(font
								(size 1.27 1.27)
							)
						)
					)
				)
				(pin passive line
					(at 0 0 0)
					(length 5.08)
					(hide yes)
					(name "VCCO_67"
						(effects
							(font
								(size 1.27 1.27)
							)
						)
					)
					(number "G18"
						(effects
							(font
								(size 1.27 1.27)
							)
						)
					)
				)
				(pin input line
					(at 0 -2.54 0)
					(length 5.08)
					(name "VREF_67"
						(effects
							(font
								(size 1.27 1.27)
							)
						)
					)
					(number "J16"
						(effects
							(font
								(size 1.27 1.27)
							)
						)
					)
				)
				(pin bidirectional line
					(at 0 -7.62 0)
					(length 5.08)
					(name "IO_L1P_T0L_N0_DBC_67"
						(effects
							(font
								(size 1.27 1.27)
							)
						)
					)
					(number "G15"
						(effects
							(font
								(size 1.27 1.27)
							)
						)
					)
				)
				(pin bidirectional line
					(at 0 -10.16 0)
					(length 5.08)
					(name "IO_L1N_T0L_N1_DBC_67"
						(effects
							(font
								(size 1.27 1.27)
							)
						)
					)
					(number "F15"
						(effects
							(font
								(size 1.27 1.27)
							)
						)
					)
				)
				(pin bidirectional line
					(at 0 -12.7 0)
					(length 5.08)
					(name "IO_L2P_T0L_N2_67"
						(effects
							(font
								(size 1.27 1.27)
							)
						)
					)
					(number "H17"
						(effects
							(font
								(size 1.27 1.27)
							)
						)
					)
				)
				(pin bidirectional line
					(at 0 -15.24 0)
					(length 5.08)
					(name "IO_L2N_T0L_N3_67"
						(effects
							(font
								(size 1.27 1.27)
							)
						)
					)
					(number "G17"
						(effects
							(font
								(size 1.27 1.27)
							)
						)
					)
				)
				(pin bidirectional line
					(at 0 -17.78 0)
					(length 5.08)
					(name "IO_L3P_T0L_N4_AD15P_67"
						(effects
							(font
								(size 1.27 1.27)
							)
						)
					)
					(number "E15"
						(effects
							(font
								(size 1.27 1.27)
							)
						)
					)
				)
				(pin bidirectional line
					(at 0 -20.32 0)
					(length 5.08)
					(name "IO_L3N_T0L_N5_AD15N_67"
						(effects
							(font
								(size 1.27 1.27)
							)
						)
					)
					(number "D15"
						(effects
							(font
								(size 1.27 1.27)
							)
						)
					)
				)
				(pin bidirectional line
					(at 0 -22.86 0)
					(length 5.08)
					(name "IO_L4P_T0U_N6_DBC_AD7P_67"
						(effects
							(font
								(size 1.27 1.27)
							)
						)
					)
					(number "E16"
						(effects
							(font
								(size 1.27 1.27)
							)
						)
					)
				)
				(pin bidirectional line
					(at 0 -25.4 0)
					(length 5.08)
					(name "IO_L4N_T0U_N7_DBC_AD7N_67"
						(effects
							(font
								(size 1.27 1.27)
							)
						)
					)
					(number "E17"
						(effects
							(font
								(size 1.27 1.27)
							)
						)
					)
				)
				(pin bidirectional line
					(at 0 -27.94 0)
					(length 5.08)
					(name "IO_L5P_T0U_N8_AD14P_67"
						(effects
							(font
								(size 1.27 1.27)
							)
						)
					)
					(number "H16"
						(effects
							(font
								(size 1.27 1.27)
							)
						)
					)
				)
				(pin bidirectional line
					(at 0 -30.48 0)
					(length 5.08)
					(name "IO_L5N_T0U_N9_AD14N_67"
						(effects
							(font
								(size 1.27 1.27)
							)
						)
					)
					(number "G16"
						(effects
							(font
								(size 1.27 1.27)
							)
						)
					)
				)
				(pin bidirectional line
					(at 0 -33.02 0)
					(length 5.08)
					(name "IO_L6P_T0U_N10_AD6P_67"
						(effects
							(font
								(size 1.27 1.27)
							)
						)
					)
					(number "D16"
						(effects
							(font
								(size 1.27 1.27)
							)
						)
					)
				)
				(pin bidirectional line
					(at 0 -35.56 0)
					(length 5.08)
					(name "IO_L6N_T0U_N11_AD6N_67"
						(effects
							(font
								(size 1.27 1.27)
							)
						)
					)
					(number "C16"
						(effects
							(font
								(size 1.27 1.27)
							)
						)
					)
				)
				(pin bidirectional line
					(at 0 -38.1 0)
					(length 5.08)
					(name "IO_T0U_N12_VRP_67"
						(effects
							(font
								(size 1.27 1.27)
							)
						)
					)
					(number "F17"
						(effects
							(font
								(size 1.27 1.27)
							)
						)
					)
				)
				(pin bidirectional line
					(at 0 -40.64 0)
					(length 5.08)
					(name "IO_L7P_T1L_N0_QBC_AD13P_67"
						(effects
							(font
								(size 1.27 1.27)
							)
						)
					)
					(number "H18"
						(effects
							(font
								(size 1.27 1.27)
							)
						)
					)
				)
				(pin bidirectional line
					(at 0 -43.18 0)
					(length 5.08)
					(name "IO_L7N_T1L_N1_QBC_AD13N_67"
						(effects
							(font
								(size 1.27 1.27)
							)
						)
					)
					(number "H19"
						(effects
							(font
								(size 1.27 1.27)
							)
						)
					)
				)
				(pin bidirectional line
					(at 0 -45.72 0)
					(length 5.08)
					(name "IO_L8P_T1L_N2_AD5P_67"
						(effects
							(font
								(size 1.27 1.27)
							)
						)
					)
					(number "F18"
						(effects
							(font
								(size 1.27 1.27)
							)
						)
					)
				)
				(pin bidirectional line
					(at 0 -48.26 0)
					(length 5.08)
					(name "IO_L8N_T1L_N3_AD5N_67"
						(effects
							(font
								(size 1.27 1.27)
							)
						)
					)
					(number "F19"
						(effects
							(font
								(size 1.27 1.27)
							)
						)
					)
				)
				(pin bidirectional line
					(at 0 -50.8 0)
					(length 5.08)
					(name "IO_L9P_T1L_N4_AD12P_67"
						(effects
							(font
								(size 1.27 1.27)
							)
						)
					)
					(number "G20"
						(effects
							(font
								(size 1.27 1.27)
							)
						)
					)
				)
				(pin bidirectional line
					(at 0 -53.34 0)
					(length 5.08)
					(name "IO_L9N_T1L_N5_AD12N_67"
						(effects
							(font
								(size 1.27 1.27)
							)
						)
					)
					(number "G21"
						(effects
							(font
								(size 1.27 1.27)
							)
						)
					)
				)
				(pin bidirectional line
					(at 0 -55.88 0)
					(length 5.08)
					(name "IO_L10P_T1U_N6_QBC_AD4P_67"
						(effects
							(font
								(size 1.27 1.27)
							)
						)
					)
					(number "F20"
						(effects
							(font
								(size 1.27 1.27)
							)
						)
					)
				)
				(pin bidirectional line
					(at 0 -58.42 0)
					(length 5.08)
					(name "IO_L10N_T1U_N7_QBC_AD4N_67"
						(effects
							(font
								(size 1.27 1.27)
							)
						)
					)
					(number "E20"
						(effects
							(font
								(size 1.27 1.27)
							)
						)
					)
				)
				(pin bidirectional line
					(at 0 -60.96 0)
					(length 5.08)
					(name "IO_L11P_T1U_N8_GC_67"
						(effects
							(font
								(size 1.27 1.27)
							)
						)
					)
					(number "E18"
						(effects
							(font
								(size 1.27 1.27)
							)
						)
					)
				)
				(pin bidirectional line
					(at 0 -63.5 0)
					(length 5.08)
					(name "IO_L11N_T1U_N9_GC_67"
						(effects
							(font
								(size 1.27 1.27)
							)
						)
					)
					(number "D18"
						(effects
							(font
								(size 1.27 1.27)
							)
						)
					)
				)
				(pin bidirectional line
					(at 0 -66.04 0)
					(length 5.08)
					(name "IO_L12P_T1U_N10_GC_67"
						(effects
							(font
								(size 1.27 1.27)
							)
						)
					)
					(number "D19"
						(effects
							(font
								(size 1.27 1.27)
							)
						)
					)
				)
				(pin bidirectional line
					(at 0 -68.58 0)
					(length 5.08)
					(name "IO_L12N_T1U_N11_GC_67"
						(effects
							(font
								(size 1.27 1.27)
							)
						)
					)
					(number "D20"
						(effects
							(font
								(size 1.27 1.27)
							)
						)
					)
				)
				(pin bidirectional line
					(at 0 -71.12 0)
					(length 5.08)
					(name "IO_T1U_N12_67"
						(effects
							(font
								(size 1.27 1.27)
							)
						)
					)
					(number "G19"
						(effects
							(font
								(size 1.27 1.27)
							)
						)
					)
				)
				(pin bidirectional line
					(at 0 -73.66 0)
					(length 5.08)
					(name "IO_L13P_T2L_N0_GC_QBC_67"
						(effects
							(font
								(size 1.27 1.27)
							)
						)
					)
					(number "C18"
						(effects
							(font
								(size 1.27 1.27)
							)
						)
					)
				)
				(pin bidirectional line
					(at 0 -76.2 0)
					(length 5.08)
					(name "IO_L13N_T2L_N1_GC_QBC_67"
						(effects
							(font
								(size 1.27 1.27)
							)
						)
					)
					(number "C19"
						(effects
							(font
								(size 1.27 1.27)
							)
						)
					)
				)
				(pin bidirectional line
					(at 0 -78.74 0)
					(length 5.08)
					(name "IO_L14P_T2L_N2_GC_67"
						(effects
							(font
								(size 1.27 1.27)
							)
						)
					)
					(number "B19"
						(effects
							(font
								(size 1.27 1.27)
							)
						)
					)
				)
				(pin bidirectional line
					(at 0 -81.28 0)
					(length 5.08)
					(name "IO_L14N_T2L_N3_GC_67"
						(effects
							(font
								(size 1.27 1.27)
							)
						)
					)
					(number "B20"
						(effects
							(font
								(size 1.27 1.27)
							)
						)
					)
				)
				(pin bidirectional line
					(at 0 -83.82 0)
					(length 5.08)
					(name "IO_L15P_T2L_N4_AD11P_67"
						(effects
							(font
								(size 1.27 1.27)
							)
						)
					)
					(number "C17"
						(effects
							(font
								(size 1.27 1.27)
							)
						)
					)
				)
				(pin bidirectional line
					(at 0 -86.36 0)
					(length 5.08)
					(name "IO_L15N_T2L_N5_AD11N_67"
						(effects
							(font
								(size 1.27 1.27)
							)
						)
					)
					(number "B17"
						(effects
							(font
								(size 1.27 1.27)
							)
						)
					)
				)
				(pin bidirectional line
					(at 0 -88.9 0)
					(length 5.08)
					(name "IO_L16P_T2U_N6_QBC_AD3P_67"
						(effects
							(font
								(size 1.27 1.27)
							)
						)
					)
					(number "A17"
						(effects
							(font
								(size 1.27 1.27)
							)
						)
					)
				)
				(pin bidirectional line
					(at 0 -91.44 0)
					(length 5.08)
					(name "IO_L16N_T2U_N7_QBC_AD3N_67"
						(effects
							(font
								(size 1.27 1.27)
							)
						)
					)
					(number "A18"
						(effects
							(font
								(size 1.27 1.27)
							)
						)
					)
				)
				(pin bidirectional line
					(at 0 -93.98 0)
					(length 5.08)
					(name "IO_L17P_T2U_N8_AD10P_67"
						(effects
							(font
								(size 1.27 1.27)
							)
						)
					)
					(number "B15"
						(effects
							(font
								(size 1.27 1.27)
							)
						)
					)
				)
				(pin bidirectional line
					(at 0 -96.52 0)
					(length 5.08)
					(name "IO_L17N_T2U_N9_AD10N_67"
						(effects
							(font
								(size 1.27 1.27)
							)
						)
					)
					(number "A15"
						(effects
							(font
								(size 1.27 1.27)
							)
						)
					)
				)
				(pin bidirectional line
					(at 0 -99.06 0)
					(length 5.08)
					(name "IO_L18P_T2U_N10_AD2P_67"
						(effects
							(font
								(size 1.27 1.27)
							)
						)
					)
					(number "A19"
						(effects
							(font
								(size 1.27 1.27)
							)
						)
					)
				)
				(pin bidirectional line
					(at 0 -101.6 0)
					(length 5.08)
					(name "IO_L18N_T2U_N11_AD2N_67"
						(effects
							(font
								(size 1.27 1.27)
							)
						)
					)
					(number "A20"
						(effects
							(font
								(size 1.27 1.27)
							)
						)
					)
				)
				(pin bidirectional line
					(at 0 -104.14 0)
					(length 5.08)
					(name "IO_T2U_N12_67"
						(effects
							(font
								(size 1.27 1.27)
							)
						)
					)
					(number "B16"
						(effects
							(font
								(size 1.27 1.27)
							)
						)
					)
				)
				(pin bidirectional line
					(at 0 -106.68 0)
					(length 5.08)
					(name "IO_L19P_T3L_N0_DBC_AD9P_67"
						(effects
							(font
								(size 1.27 1.27)
							)
						)
					)
					(number "A22"
						(effects
							(font
								(size 1.27 1.27)
							)
						)
					)
				)
				(pin bidirectional line
					(at 0 -109.22 0)
					(length 5.08)
					(name "IO_L19N_T3L_N1_DBC_AD9N_67"
						(effects
							(font
								(size 1.27 1.27)
							)
						)
					)
					(number "A23"
						(effects
							(font
								(size 1.27 1.27)
							)
						)
					)
				)
				(pin bidirectional line
					(at 0 -111.76 0)
					(length 5.08)
					(name "IO_L20P_T3L_N2_AD1P_67"
						(effects
							(font
								(size 1.27 1.27)
							)
						)
					)
					(number "E21"
						(effects
							(font
								(size 1.27 1.27)
							)
						)
					)
				)
				(pin bidirectional line
					(at 0 -114.3 0)
					(length 5.08)
					(name "IO_L20N_T3L_N3_AD1N_67"
						(effects
							(font
								(size 1.27 1.27)
							)
						)
					)
					(number "D21"
						(effects
							(font
								(size 1.27 1.27)
							)
						)
					)
				)
				(pin bidirectional line
					(at 0 -116.84 0)
					(length 5.08)
					(name "IO_L21P_T3L_N4_AD8P_67"
						(effects
							(font
								(size 1.27 1.27)
							)
						)
					)
					(number "C23"
						(effects
							(font
								(size 1.27 1.27)
							)
						)
					)
				)
				(pin bidirectional line
					(at 0 -119.38 0)
					(length 5.08)
					(name "IO_L21N_T3L_N5_AD8N_67"
						(effects
							(font
								(size 1.27 1.27)
							)
						)
					)
					(number "B24"
						(effects
							(font
								(size 1.27 1.27)
							)
						)
					)
				)
				(pin bidirectional line
					(at 0 -121.92 0)
					(length 5.08)
					(name "IO_L22P_T3U_N6_DBC_AD0P_67"
						(effects
							(font
								(size 1.27 1.27)
							)
						)
					)
					(number "C21"
						(effects
							(font
								(size 1.27 1.27)
							)
						)
					)
				)
				(pin bidirectional line
					(at 0 -124.46 0)
					(length 5.08)
					(name "IO_L22N_T3U_N7_DBC_AD0N_67"
						(effects
							(font
								(size 1.27 1.27)
							)
						)
					)
					(number "B21"
						(effects
							(font
								(size 1.27 1.27)
							)
						)
					)
				)
				(pin bidirectional line
					(at 0 -127 0)
					(length 5.08)
					(name "IO_L23P_T3U_N8_67"
						(effects
							(font
								(size 1.27 1.27)
							)
						)
					)
					(number "A24"
						(effects
							(font
								(size 1.27 1.27)
							)
						)
					)
				)
				(pin bidirectional line
					(at 0 -129.54 0)
					(length 5.08)
					(name "IO_L23N_T3U_N9_67"
						(effects
							(font
								(size 1.27 1.27)
							)
						)
					)
					(number "A25"
						(effects
							(font
								(size 1.27 1.27)
							)
						)
					)
				)
				(pin bidirectional line
					(at 0 -132.08 0)
					(length 5.08)
					(name "IO_L24P_T3U_N10_67"
						(effects
							(font
								(size 1.27 1.27)
							)
						)
					)
					(number "C22"
						(effects
							(font
								(size 1.27 1.27)
							)
						)
					)
				)
				(pin bidirectional line
					(at 0 -134.62 0)
					(length 5.08)
					(name "IO_L24N_T3U_N11_67"
						(effects
							(font
								(size 1.27 1.27)
							)
						)
					)
					(number "B22"
						(effects
							(font
								(size 1.27 1.27)
							)
						)
					)
				)
				(pin bidirectional line
					(at 0 -137.16 0)
					(length 5.08)
					(name "IO_T3U_N12_67"
						(effects
							(font
								(size 1.27 1.27)
							)
						)
					)
					(number "E22"
						(effects
							(font
								(size 1.27 1.27)
							)
						)
					)
				)
			)
			(symbol "XCAU25P-2FFVB676I_3_6_1"
				(rectangle
					(start 5.08 2.54)
					(end 33.02 -68.58)
					(stroke
						(width 0.254)
						(type default)
					)
					(fill
						(type background)
					)
				)
				(polyline
					(pts
						(xy 22.86 -3.81) (xy 30.48 -3.81) (xy 30.48 -64.77) (xy 22.86 -64.77)
					)
					(stroke
						(width 0.254)
						(type default)
					)
					(fill
						(type background)
					)
				)
				(text "BANK 84"
					(at 22.86 -2.54 0)
					(effects
						(font
							(size 1.27 1.27)
							(thickness 0.15)
						)
						(justify left bottom)
					)
				)
				(text ""
					(at 50.8 -31.75 0)
					(effects
						(font
							(size 1.27 1.27)
							(thickness 0.15)
						)
						(justify left bottom)
					)
				)
				(text ""
					(at 50.8 -31.75 0)
					(effects
						(font
							(size 1.27 1.27)
							(thickness 0.15)
						)
						(justify left bottom)
					)
				)
				(pin power_in line
					(at 0 0 0)
					(length 5.08)
					(name "VCCO_84"
						(effects
							(font
								(size 1.27 1.27)
							)
						)
					)
					(number "AC15"
						(effects
							(font
								(size 1.27 1.27)
							)
						)
					)
				)
				(pin passive line
					(at 0 0 0)
					(length 5.08)
					(hide yes)
					(name "VCCO_84"
						(effects
							(font
								(size 1.27 1.27)
							)
						)
					)
					(number "Y14"
						(effects
							(font
								(size 1.27 1.27)
							)
						)
					)
				)
				(pin bidirectional line
					(at 0 -5.08 0)
					(length 5.08)
					(name "IO_L1P_AD11P_84"
						(effects
							(font
								(size 1.27 1.27)
							)
						)
					)
					(number "AF14"
						(effects
							(font
								(size 1.27 1.27)
							)
						)
					)
				)
				(pin bidirectional line
					(at 0 -7.62 0)
					(length 5.08)
					(name "IO_L1N_AD11N_84"
						(effects
							(font
								(size 1.27 1.27)
							)
						)
					)
					(number "AF15"
						(effects
							(font
								(size 1.27 1.27)
							)
						)
					)
				)
				(pin bidirectional line
					(at 0 -10.16 0)
					(length 5.08)
					(name "IO_L2P_AD10P_84"
						(effects
							(font
								(size 1.27 1.27)
							)
						)
					)
					(number "AE13"
						(effects
							(font
								(size 1.27 1.27)
							)
						)
					)
				)
				(pin bidirectional line
					(at 0 -12.7 0)
					(length 5.08)
					(name "IO_L2N_AD10N_84"
						(effects
							(font
								(size 1.27 1.27)
							)
						)
					)
					(number "AF13"
						(effects
							(font
								(size 1.27 1.27)
							)
						)
					)
				)
				(pin bidirectional line
					(at 0 -15.24 0)
					(length 5.08)
					(name "IO_L3P_AD9P_84"
						(effects
							(font
								(size 1.27 1.27)
							)
						)
					)
					(number "AD15"
						(effects
							(font
								(size 1.27 1.27)
							)
						)
					)
				)
				(pin bidirectional line
					(at 0 -17.78 0)
					(length 5.08)
					(name "IO_L3N_AD9N_84"
						(effects
							(font
								(size 1.27 1.27)
							)
						)
					)
					(number "AE15"
						(effects
							(font
								(size 1.27 1.27)
							)
						)
					)
				)
				(pin bidirectional line
					(at 0 -20.32 0)
					(length 5.08)
					(name "IO_L4P_AD8P_84"
						(effects
							(font
								(size 1.27 1.27)
							)
						)
					)
					(number "AD13"
						(effects
							(font
								(size 1.27 1.27)
							)
						)
					)
				)
				(pin bidirectional line
					(at 0 -22.86 0)
					(length 5.08)
					(name "IO_L4N_AD8N_84"
						(effects
							(font
								(size 1.27 1.27)
							)
						)
					)
					(number "AD14"
						(effects
							(font
								(size 1.27 1.27)
							)
						)
					)
				)
				(pin bidirectional line
					(at 0 -25.4 0)
					(length 5.08)
					(name "IO_L5P_HDGC_AD7P_84"
						(effects
							(font
								(size 1.27 1.27)
							)
						)
					)
					(number "AC13"
						(effects
							(font
								(size 1.27 1.27)
							)
						)
					)
				)
				(pin bidirectional line
					(at 0 -27.94 0)
					(length 5.08)
					(name "IO_L5N_HDGC_AD7N_84"
						(effects
							(font
								(size 1.27 1.27)
							)
						)
					)
					(number "AC14"
						(effects
							(font
								(size 1.27 1.27)
							)
						)
					)
				)
				(pin bidirectional line
					(at 0 -30.48 0)
					(length 5.08)
					(name "IO_L6P_HDGC_AD6P_84"
						(effects
							(font
								(size 1.27 1.27)
							)
						)
					)
					(number "AB15"
						(effects
							(font
								(size 1.27 1.27)
							)
						)
					)
				)
				(pin bidirectional line
					(at 0 -33.02 0)
					(length 5.08)
					(name "IO_L6N_HDGC_AD6N_84"
						(effects
							(font
								(size 1.27 1.27)
							)
						)
					)
					(number "AB16"
						(effects
							(font
								(size 1.27 1.27)
							)
						)
					)
				)
				(pin bidirectional line
					(at 0 -35.56 0)
					(length 5.08)
					(name "IO_L7P_HDGC_AD5P_84"
						(effects
							(font
								(size 1.27 1.27)
							)
						)
					)
					(number "Y15"
						(effects
							(font
								(size 1.27 1.27)
							)
						)
					)
				)
				(pin bidirectional line
					(at 0 -38.1 0)
					(length 5.08)
					(name "IO_L7N_HDGC_AD5N_84"
						(effects
							(font
								(size 1.27 1.27)
							)
						)
					)
					(number "AA15"
						(effects
							(font
								(size 1.27 1.27)
							)
						)
					)
				)
				(pin bidirectional line
					(at 0 -40.64 0)
					(length 5.08)
					(name "IO_L8P_HDGC_AD4P_84"
						(effects
							(font
								(size 1.27 1.27)
							)
						)
					)
					(number "AA14"
						(effects
							(font
								(size 1.27 1.27)
							)
						)
					)
				)
				(pin bidirectional line
					(at 0 -43.18 0)
					(length 5.08)
					(name "IO_L8N_HDGC_AD4N_84"
						(effects
							(font
								(size 1.27 1.27)
							)
						)
					)
					(number "AB14"
						(effects
							(font
								(size 1.27 1.27)
							)
						)
					)
				)
				(pin bidirectional line
					(at 0 -45.72 0)
					(length 5.08)
					(name "IO_L9P_AD3P_84"
						(effects
							(font
								(size 1.27 1.27)
							)
						)
					)
					(number "W16"
						(effects
							(font
								(size 1.27 1.27)
							)
						)
					)
				)
				(pin bidirectional line
					(at 0 -48.26 0)
					(length 5.08)
					(name "IO_L9N_AD3N_84"
						(effects
							(font
								(size 1.27 1.27)
							)
						)
					)
					(number "Y16"
						(effects
							(font
								(size 1.27 1.27)
							)
						)
					)
				)
				(pin bidirectional line
					(at 0 -50.8 0)
					(length 5.08)
					(name "IO_L10P_AD2P_84"
						(effects
							(font
								(size 1.27 1.27)
							)
						)
					)
					(number "W14"
						(effects
							(font
								(size 1.27 1.27)
							)
						)
					)
				)
				(pin bidirectional line
					(at 0 -53.34 0)
					(length 5.08)
					(name "IO_L10N_AD2N_84"
						(effects
							(font
								(size 1.27 1.27)
							)
						)
					)
					(number "W15"
						(effects
							(font
								(size 1.27 1.27)
							)
						)
					)
				)
				(pin bidirectional line
					(at 0 -55.88 0)
					(length 5.08)
					(name "IO_L11P_AD1P_84"
						(effects
							(font
								(size 1.27 1.27)
							)
						)
					)
					(number "Y13"
						(effects
							(font
								(size 1.27 1.27)
							)
						)
					)
				)
				(pin bidirectional line
					(at 0 -58.42 0)
					(length 5.08)
					(name "IO_L11N_AD1N_84"
						(effects
							(font
								(size 1.27 1.27)
							)
						)
					)
					(number "AA13"
						(effects
							(font
								(size 1.27 1.27)
							)
						)
					)
				)
				(pin bidirectional line
					(at 0 -60.96 0)
					(length 5.08)
					(name "IO_L12P_AD0P_84"
						(effects
							(font
								(size 1.27 1.27)
							)
						)
					)
					(number "W12"
						(effects
							(font
								(size 1.27 1.27)
							)
						)
					)
				)
				(pin bidirectional line
					(at 0 -63.5 0)
					(length 5.08)
					(name "IO_L12N_AD0N_84"
						(effects
							(font
								(size 1.27 1.27)
							)
						)
					)
					(number "W13"
						(effects
							(font
								(size 1.27 1.27)
							)
						)
					)
				)
			)
			(symbol "XCAU25P-2FFVB676I_3_7_1"
				(rectangle
					(start 5.08 2.54)
					(end 33.02 -68.58)
					(stroke
						(width 0.254)
						(type default)
					)
					(fill
						(type background)
					)
				)
				(polyline
					(pts
						(xy 22.86 -3.81) (xy 30.48 -3.81) (xy 30.48 -64.77) (xy 22.86 -64.77)
					)
					(stroke
						(width 0.254)
						(type default)
					)
					(fill
						(type background)
					)
				)
				(text "BANK 86"
					(at 22.86 -2.54 0)
					(effects
						(font
							(size 1.27 1.27)
							(thickness 0.15)
						)
						(justify left bottom)
					)
				)
				(text ""
					(at 50.8 -31.75 0)
					(effects
						(font
							(size 1.27 1.27)
							(thickness 0.15)
						)
						(justify left bottom)
					)
				)
				(text ""
					(at 50.8 -31.75 0)
					(effects
						(font
							(size 1.27 1.27)
							(thickness 0.15)
						)
						(justify left bottom)
					)
				)
				(pin power_in line
					(at 0 0 0)
					(length 5.08)
					(name "VCCO_86"
						(effects
							(font
								(size 1.27 1.27)
							)
						)
					)
					(number "E9"
						(effects
							(font
								(size 1.27 1.27)
							)
						)
					)
				)
				(pin passive line
					(at 0 0 0)
					(length 5.08)
					(hide yes)
					(name "VCCO_86"
						(effects
							(font
								(size 1.27 1.27)
							)
						)
					)
					(number "H10"
						(effects
							(font
								(size 1.27 1.27)
							)
						)
					)
				)
				(pin bidirectional line
					(at 0 -5.08 0)
					(length 5.08)
					(name "IO_L1P_AD11P_86"
						(effects
							(font
								(size 1.27 1.27)
							)
						)
					)
					(number "K10"
						(effects
							(font
								(size 1.27 1.27)
							)
						)
					)
				)
				(pin bidirectional line
					(at 0 -7.62 0)
					(length 5.08)
					(name "IO_L1N_AD11N_86"
						(effects
							(font
								(size 1.27 1.27)
							)
						)
					)
					(number "K9"
						(effects
							(font
								(size 1.27 1.27)
							)
						)
					)
				)
				(pin bidirectional line
					(at 0 -10.16 0)
					(length 5.08)
					(name "IO_L2P_AD10P_86"
						(effects
							(font
								(size 1.27 1.27)
							)
						)
					)
					(number "J11"
						(effects
							(font
								(size 1.27 1.27)
							)
						)
					)
				)
				(pin bidirectional line
					(at 0 -12.7 0)
					(length 5.08)
					(name "IO_L2N_AD10N_86"
						(effects
							(font
								(size 1.27 1.27)
							)
						)
					)
					(number "J10"
						(effects
							(font
								(size 1.27 1.27)
							)
						)
					)
				)
				(pin bidirectional line
					(at 0 -15.24 0)
					(length 5.08)
					(name "IO_L3P_AD9P_86"
						(effects
							(font
								(size 1.27 1.27)
							)
						)
					)
					(number "J9"
						(effects
							(font
								(size 1.27 1.27)
							)
						)
					)
				)
				(pin bidirectional line
					(at 0 -17.78 0)
					(length 5.08)
					(name "IO_L3N_AD9N_86"
						(effects
							(font
								(size 1.27 1.27)
							)
						)
					)
					(number "H9"
						(effects
							(font
								(size 1.27 1.27)
							)
						)
					)
				)
				(pin bidirectional line
					(at 0 -20.32 0)
					(length 5.08)
					(name "IO_L4P_AD8P_86"
						(effects
							(font
								(size 1.27 1.27)
							)
						)
					)
					(number "H11"
						(effects
							(font
								(size 1.27 1.27)
							)
						)
					)
				)
				(pin bidirectional line
					(at 0 -22.86 0)
					(length 5.08)
					(name "IO_L4N_AD8N_86"
						(effects
							(font
								(size 1.27 1.27)
							)
						)
					)
					(number "G11"
						(effects
							(font
								(size 1.27 1.27)
							)
						)
					)
				)
				(pin bidirectional line
					(at 0 -25.4 0)
					(length 5.08)
					(name "IO_L5P_HDGC_AD7P_86"
						(effects
							(font
								(size 1.27 1.27)
							)
						)
					)
					(number "G10"
						(effects
							(font
								(size 1.27 1.27)
							)
						)
					)
				)
				(pin bidirectional line
					(at 0 -27.94 0)
					(length 5.08)
					(name "IO_L5N_HDGC_AD7N_86"
						(effects
							(font
								(size 1.27 1.27)
							)
						)
					)
					(number "G9"
						(effects
							(font
								(size 1.27 1.27)
							)
						)
					)
				)
				(pin bidirectional line
					(at 0 -30.48 0)
					(length 5.08)
					(name "IO_L6P_HDGC_AD6P_86"
						(effects
							(font
								(size 1.27 1.27)
							)
						)
					)
					(number "F10"
						(effects
							(font
								(size 1.27 1.27)
							)
						)
					)
				)
				(pin bidirectional line
					(at 0 -33.02 0)
					(length 5.08)
					(name "IO_L6N_HDGC_AD6N_86"
						(effects
							(font
								(size 1.27 1.27)
							)
						)
					)
					(number "F9"
						(effects
							(font
								(size 1.27 1.27)
							)
						)
					)
				)
				(pin bidirectional line
					(at 0 -35.56 0)
					(length 5.08)
					(name "IO_L7P_HDGC_AD5P_86"
						(effects
							(font
								(size 1.27 1.27)
							)
						)
					)
					(number "E11"
						(effects
							(font
								(size 1.27 1.27)
							)
						)
					)
				)
				(pin bidirectional line
					(at 0 -38.1 0)
					(length 5.08)
					(name "IO_L7N_HDGC_AD5N_86"
						(effects
							(font
								(size 1.27 1.27)
							)
						)
					)
					(number "E10"
						(effects
							(font
								(size 1.27 1.27)
							)
						)
					)
				)
				(pin bidirectional line
					(at 0 -40.64 0)
					(length 5.08)
					(name "IO_L8P_HDGC_AD4P_86"
						(effects
							(font
								(size 1.27 1.27)
							)
						)
					)
					(number "D11"
						(effects
							(font
								(size 1.27 1.27)
							)
						)
					)
				)
				(pin bidirectional line
					(at 0 -43.18 0)
					(length 5.08)
					(name "IO_L8N_HDGC_AD4N_86"
						(effects
							(font
								(size 1.27 1.27)
							)
						)
					)
					(number "D10"
						(effects
							(font
								(size 1.27 1.27)
							)
						)
					)
				)
				(pin bidirectional line
					(at 0 -45.72 0)
					(length 5.08)
					(name "IO_L9P_AD3P_86"
						(effects
							(font
								(size 1.27 1.27)
							)
						)
					)
					(number "D9"
						(effects
							(font
								(size 1.27 1.27)
							)
						)
					)
				)
				(pin bidirectional line
					(at 0 -48.26 0)
					(length 5.08)
					(name "IO_L9N_AD3N_86"
						(effects
							(font
								(size 1.27 1.27)
							)
						)
					)
					(number "C9"
						(effects
							(font
								(size 1.27 1.27)
							)
						)
					)
				)
				(pin bidirectional line
					(at 0 -50.8 0)
					(length 5.08)
					(name "IO_L10P_AD2P_86"
						(effects
							(font
								(size 1.27 1.27)
							)
						)
					)
					(number "B9"
						(effects
							(font
								(size 1.27 1.27)
							)
						)
					)
				)
				(pin bidirectional line
					(at 0 -53.34 0)
					(length 5.08)
					(name "IO_L10N_AD2N_86"
						(effects
							(font
								(size 1.27 1.27)
							)
						)
					)
					(number "A9"
						(effects
							(font
								(size 1.27 1.27)
							)
						)
					)
				)
				(pin bidirectional line
					(at 0 -55.88 0)
					(length 5.08)
					(name "IO_L11P_AD1P_86"
						(effects
							(font
								(size 1.27 1.27)
							)
						)
					)
					(number "B10"
						(effects
							(font
								(size 1.27 1.27)
							)
						)
					)
				)
				(pin bidirectional line
					(at 0 -58.42 0)
					(length 5.08)
					(name "IO_L11N_AD1N_86"
						(effects
							(font
								(size 1.27 1.27)
							)
						)
					)
					(number "A10"
						(effects
							(font
								(size 1.27 1.27)
							)
						)
					)
				)
				(pin bidirectional line
					(at 0 -60.96 0)
					(length 5.08)
					(name "IO_L12P_AD0P_86"
						(effects
							(font
								(size 1.27 1.27)
							)
						)
					)
					(number "C11"
						(effects
							(font
								(size 1.27 1.27)
							)
						)
					)
				)
				(pin bidirectional line
					(at 0 -63.5 0)
					(length 5.08)
					(name "IO_L12N_AD0N_86"
						(effects
							(font
								(size 1.27 1.27)
							)
						)
					)
					(number "B11"
						(effects
							(font
								(size 1.27 1.27)
							)
						)
					)
				)
			)
			(symbol "XCAU25P-2FFVB676I_3_8_1"
				(rectangle
					(start 5.08 2.54)
					(end 33.02 -67.31)
					(stroke
						(width 0.254)
						(type default)
					)
					(fill
						(type background)
					)
				)
				(polyline
					(pts
						(xy 22.86 -3.81) (xy 30.48 -3.81) (xy 30.48 -64.77) (xy 22.86 -64.77)
					)
					(stroke
						(width 0.254)
						(type default)
					)
					(fill
						(type background)
					)
				)
				(text "BANK 87"
					(at 22.86 -2.54 0)
					(effects
						(font
							(size 1.27 1.27)
							(thickness 0.15)
						)
						(justify left bottom)
					)
				)
				(text ""
					(at 50.8 -31.75 0)
					(effects
						(font
							(size 1.27 1.27)
							(thickness 0.15)
						)
						(justify left bottom)
					)
				)
				(text ""
					(at 50.8 -31.75 0)
					(effects
						(font
							(size 1.27 1.27)
							(thickness 0.15)
						)
						(justify left bottom)
					)
				)
				(pin power_in line
					(at 0 0 0)
					(length 5.08)
					(name "VCCO_87"
						(effects
							(font
								(size 1.27 1.27)
							)
						)
					)
					(number "E14"
						(effects
							(font
								(size 1.27 1.27)
							)
						)
					)
				)
				(pin passive line
					(at 0 0 0)
					(length 5.08)
					(hide yes)
					(name "VCCO_87"
						(effects
							(font
								(size 1.27 1.27)
							)
						)
					)
					(number "H15"
						(effects
							(font
								(size 1.27 1.27)
							)
						)
					)
				)
				(pin bidirectional line
					(at 0 -5.08 0)
					(length 5.08)
					(name "IO_L1P_AD15P_87"
						(effects
							(font
								(size 1.27 1.27)
							)
						)
					)
					(number "J12"
						(effects
							(font
								(size 1.27 1.27)
							)
						)
					)
				)
				(pin bidirectional line
					(at 0 -7.62 0)
					(length 5.08)
					(name "IO_L1N_AD15N_87"
						(effects
							(font
								(size 1.27 1.27)
							)
						)
					)
					(number "H12"
						(effects
							(font
								(size 1.27 1.27)
							)
						)
					)
				)
				(pin bidirectional line
					(at 0 -10.16 0)
					(length 5.08)
					(name "IO_L2P_AD14P_87"
						(effects
							(font
								(size 1.27 1.27)
							)
						)
					)
					(number "J13"
						(effects
							(font
								(size 1.27 1.27)
							)
						)
					)
				)
				(pin bidirectional line
					(at 0 -12.7 0)
					(length 5.08)
					(name "IO_L2N_AD14N_87"
						(effects
							(font
								(size 1.27 1.27)
							)
						)
					)
					(number "H13"
						(effects
							(font
								(size 1.27 1.27)
							)
						)
					)
				)
				(pin bidirectional line
					(at 0 -15.24 0)
					(length 5.08)
					(name "IO_L3P_AD13P_87"
						(effects
							(font
								(size 1.27 1.27)
							)
						)
					)
					(number "H14"
						(effects
							(font
								(size 1.27 1.27)
							)
						)
					)
				)
				(pin bidirectional line
					(at 0 -17.78 0)
					(length 5.08)
					(name "IO_L3N_AD13N_87"
						(effects
							(font
								(size 1.27 1.27)
							)
						)
					)
					(number "G14"
						(effects
							(font
								(size 1.27 1.27)
							)
						)
					)
				)
				(pin bidirectional line
					(at 0 -20.32 0)
					(length 5.08)
					(name "IO_L4P_AD12P_87"
						(effects
							(font
								(size 1.27 1.27)
							)
						)
					)
					(number "J15"
						(effects
							(font
								(size 1.27 1.27)
							)
						)
					)
				)
				(pin bidirectional line
					(at 0 -22.86 0)
					(length 5.08)
					(name "IO_L4N_AD12N_87"
						(effects
							(font
								(size 1.27 1.27)
							)
						)
					)
					(number "J14"
						(effects
							(font
								(size 1.27 1.27)
							)
						)
					)
				)
				(pin bidirectional line
					(at 0 -25.4 0)
					(length 5.08)
					(name "IO_L5P_HDGC_87"
						(effects
							(font
								(size 1.27 1.27)
							)
						)
					)
					(number "G12"
						(effects
							(font
								(size 1.27 1.27)
							)
						)
					)
				)
				(pin bidirectional line
					(at 0 -27.94 0)
					(length 5.08)
					(name "IO_L5N_HDGC_87"
						(effects
							(font
								(size 1.27 1.27)
							)
						)
					)
					(number "F12"
						(effects
							(font
								(size 1.27 1.27)
							)
						)
					)
				)
				(pin bidirectional line
					(at 0 -30.48 0)
					(length 5.08)
					(name "IO_L6P_HDGC_87"
						(effects
							(font
								(size 1.27 1.27)
							)
						)
					)
					(number "F14"
						(effects
							(font
								(size 1.27 1.27)
							)
						)
					)
				)
				(pin bidirectional line
					(at 0 -33.02 0)
					(length 5.08)
					(name "IO_L6N_HDGC_87"
						(effects
							(font
								(size 1.27 1.27)
							)
						)
					)
					(number "F13"
						(effects
							(font
								(size 1.27 1.27)
							)
						)
					)
				)
				(pin bidirectional line
					(at 0 -35.56 0)
					(length 5.08)
					(name "IO_L7P_HDGC_87"
						(effects
							(font
								(size 1.27 1.27)
							)
						)
					)
					(number "E13"
						(effects
							(font
								(size 1.27 1.27)
							)
						)
					)
				)
				(pin bidirectional line
					(at 0 -38.1 0)
					(length 5.08)
					(name "IO_L7N_HDGC_87"
						(effects
							(font
								(size 1.27 1.27)
							)
						)
					)
					(number "E12"
						(effects
							(font
								(size 1.27 1.27)
							)
						)
					)
				)
				(pin bidirectional line
					(at 0 -40.64 0)
					(length 5.08)
					(name "IO_L8P_HDGC_87"
						(effects
							(font
								(size 1.27 1.27)
							)
						)
					)
					(number "D14"
						(effects
							(font
								(size 1.27 1.27)
							)
						)
					)
				)
				(pin bidirectional line
					(at 0 -43.18 0)
					(length 5.08)
					(name "IO_L8N_HDGC_87"
						(effects
							(font
								(size 1.27 1.27)
							)
						)
					)
					(number "D13"
						(effects
							(font
								(size 1.27 1.27)
							)
						)
					)
				)
				(pin bidirectional line
					(at 0 -45.72 0)
					(length 5.08)
					(name "IO_L9P_AD11P_87"
						(effects
							(font
								(size 1.27 1.27)
							)
						)
					)
					(number "C14"
						(effects
							(font
								(size 1.27 1.27)
							)
						)
					)
				)
				(pin bidirectional line
					(at 0 -48.26 0)
					(length 5.08)
					(name "IO_L9N_AD11N_87"
						(effects
							(font
								(size 1.27 1.27)
							)
						)
					)
					(number "C13"
						(effects
							(font
								(size 1.27 1.27)
							)
						)
					)
				)
				(pin bidirectional line
					(at 0 -50.8 0)
					(length 5.08)
					(name "IO_L10P_AD10P_87"
						(effects
							(font
								(size 1.27 1.27)
							)
						)
					)
					(number "C12"
						(effects
							(font
								(size 1.27 1.27)
							)
						)
					)
				)
				(pin bidirectional line
					(at 0 -53.34 0)
					(length 5.08)
					(name "IO_L10N_AD10N_87"
						(effects
							(font
								(size 1.27 1.27)
							)
						)
					)
					(number "B12"
						(effects
							(font
								(size 1.27 1.27)
							)
						)
					)
				)
				(pin bidirectional line
					(at 0 -55.88 0)
					(length 5.08)
					(name "IO_L11P_AD9P_87"
						(effects
							(font
								(size 1.27 1.27)
							)
						)
					)
					(number "A13"
						(effects
							(font
								(size 1.27 1.27)
							)
						)
					)
				)
				(pin bidirectional line
					(at 0 -58.42 0)
					(length 5.08)
					(name "IO_L11N_AD9N_87"
						(effects
							(font
								(size 1.27 1.27)
							)
						)
					)
					(number "A12"
						(effects
							(font
								(size 1.27 1.27)
							)
						)
					)
				)
				(pin bidirectional line
					(at 0 -60.96 0)
					(length 5.08)
					(name "IO_L12P_AD8P_87"
						(effects
							(font
								(size 1.27 1.27)
							)
						)
					)
					(number "B14"
						(effects
							(font
								(size 1.27 1.27)
							)
						)
					)
				)
				(pin bidirectional line
					(at 0 -63.5 0)
					(length 5.08)
					(name "IO_L12N_AD8N_87"
						(effects
							(font
								(size 1.27 1.27)
							)
						)
					)
					(number "A14"
						(effects
							(font
								(size 1.27 1.27)
							)
						)
					)
				)
			)
			(symbol "XCAU25P-2FFVB676I_3_9_1"
				(rectangle
					(start 5.08 6.35)
					(end 27.94 -58.42)
					(stroke
						(width 0.254)
						(type default)
					)
					(fill
						(type background)
					)
				)
				(polyline
					(pts
						(xy 16.51 2.54) (xy 25.4 2.54) (xy 25.4 -55.88) (xy 16.51 -55.88)
					)
					(stroke
						(width 0.254)
						(type default)
					)
					(fill
						(type background)
					)
				)
				(text "GTX 224"
					(at 6.35 2.54 0)
					(effects
						(font
							(size 1.27 1.27)
							(thickness 0.15)
						)
						(justify left bottom)
					)
				)
				(text ""
					(at 50.8 -31.75 0)
					(effects
						(font
							(size 1.27 1.27)
							(thickness 0.15)
						)
						(justify left bottom)
					)
				)
				(text ""
					(at 50.8 -31.75 0)
					(effects
						(font
							(size 1.27 1.27)
							(thickness 0.15)
						)
						(justify left bottom)
					)
				)
				(pin output line
					(at 0 0 0)
					(length 5.08)
					(name "MGTYTXP0_224"
						(effects
							(font
								(size 1.27 1.27)
							)
						)
					)
					(number "AF7"
						(effects
							(font
								(size 1.27 1.27)
							)
						)
					)
				)
				(pin output line
					(at 0 -2.54 0)
					(length 5.08)
					(name "MGTYTXN0_224"
						(effects
							(font
								(size 1.27 1.27)
							)
						)
					)
					(number "AF6"
						(effects
							(font
								(size 1.27 1.27)
							)
						)
					)
				)
				(pin output line
					(at 0 -5.08 0)
					(length 5.08)
					(name "MGTYTXP1_224"
						(effects
							(font
								(size 1.27 1.27)
							)
						)
					)
					(number "AE9"
						(effects
							(font
								(size 1.27 1.27)
							)
						)
					)
				)
				(pin output line
					(at 0 -7.62 0)
					(length 5.08)
					(name "MGTYTXN1_224"
						(effects
							(font
								(size 1.27 1.27)
							)
						)
					)
					(number "AE8"
						(effects
							(font
								(size 1.27 1.27)
							)
						)
					)
				)
				(pin output line
					(at 0 -10.16 0)
					(length 5.08)
					(name "MGTYTXP2_224"
						(effects
							(font
								(size 1.27 1.27)
							)
						)
					)
					(number "AD7"
						(effects
							(font
								(size 1.27 1.27)
							)
						)
					)
				)
				(pin output line
					(at 0 -12.7 0)
					(length 5.08)
					(name "MGTYTXN2_224"
						(effects
							(font
								(size 1.27 1.27)
							)
						)
					)
					(number "AD6"
						(effects
							(font
								(size 1.27 1.27)
							)
						)
					)
				)
				(pin output line
					(at 0 -15.24 0)
					(length 5.08)
					(name "MGTYTXP3_224"
						(effects
							(font
								(size 1.27 1.27)
							)
						)
					)
					(number "AC5"
						(effects
							(font
								(size 1.27 1.27)
							)
						)
					)
				)
				(pin output line
					(at 0 -17.78 0)
					(length 5.08)
					(name "MGTYTXN3_224"
						(effects
							(font
								(size 1.27 1.27)
							)
						)
					)
					(number "AC4"
						(effects
							(font
								(size 1.27 1.27)
							)
						)
					)
				)
				(pin input line
					(at 0 -22.86 0)
					(length 5.08)
					(name "MGTYRXP0_224"
						(effects
							(font
								(size 1.27 1.27)
							)
						)
					)
					(number "AF2"
						(effects
							(font
								(size 1.27 1.27)
							)
						)
					)
				)
				(pin input line
					(at 0 -25.4 0)
					(length 5.08)
					(name "MGTYRXN0_224"
						(effects
							(font
								(size 1.27 1.27)
							)
						)
					)
					(number "AF1"
						(effects
							(font
								(size 1.27 1.27)
							)
						)
					)
				)
				(pin input line
					(at 0 -27.94 0)
					(length 5.08)
					(name "MGTYRXP1_224"
						(effects
							(font
								(size 1.27 1.27)
							)
						)
					)
					(number "AE4"
						(effects
							(font
								(size 1.27 1.27)
							)
						)
					)
				)
				(pin input line
					(at 0 -30.48 0)
					(length 5.08)
					(name "MGTYRXN1_224"
						(effects
							(font
								(size 1.27 1.27)
							)
						)
					)
					(number "AE3"
						(effects
							(font
								(size 1.27 1.27)
							)
						)
					)
				)
				(pin input line
					(at 0 -33.02 0)
					(length 5.08)
					(name "MGTYRXP2_224"
						(effects
							(font
								(size 1.27 1.27)
							)
						)
					)
					(number "AD2"
						(effects
							(font
								(size 1.27 1.27)
							)
						)
					)
				)
				(pin input line
					(at 0 -35.56 0)
					(length 5.08)
					(name "MGTYRXN2_224"
						(effects
							(font
								(size 1.27 1.27)
							)
						)
					)
					(number "AD1"
						(effects
							(font
								(size 1.27 1.27)
							)
						)
					)
				)
				(pin input line
					(at 0 -38.1 0)
					(length 5.08)
					(name "MGTYRXP3_224"
						(effects
							(font
								(size 1.27 1.27)
							)
						)
					)
					(number "AB2"
						(effects
							(font
								(size 1.27 1.27)
							)
						)
					)
				)
				(pin input line
					(at 0 -40.64 0)
					(length 5.08)
					(name "MGTYRXN3_224"
						(effects
							(font
								(size 1.27 1.27)
							)
						)
					)
					(number "AB1"
						(effects
							(font
								(size 1.27 1.27)
							)
						)
					)
				)
				(pin input line
					(at 0 -45.72 0)
					(length 5.08)
					(name "MGTREFCLK0P_224"
						(effects
							(font
								(size 1.27 1.27)
							)
						)
					)
					(number "AB7"
						(effects
							(font
								(size 1.27 1.27)
							)
						)
					)
				)
				(pin input line
					(at 0 -48.26 0)
					(length 5.08)
					(name "MGTREFCLK0N_224"
						(effects
							(font
								(size 1.27 1.27)
							)
						)
					)
					(number "AB6"
						(effects
							(font
								(size 1.27 1.27)
							)
						)
					)
				)
				(pin input line
					(at 0 -50.8 0)
					(length 5.08)
					(name "MGTREFCLK1P_224"
						(effects
							(font
								(size 1.27 1.27)
							)
						)
					)
					(number "Y7"
						(effects
							(font
								(size 1.27 1.27)
							)
						)
					)
				)
				(pin input line
					(at 0 -53.34 0)
					(length 5.08)
					(name "MGTREFCLK1N_224"
						(effects
							(font
								(size 1.27 1.27)
							)
						)
					)
					(number "Y6"
						(effects
							(font
								(size 1.27 1.27)
							)
						)
					)
				)
			)
			(symbol "XCAU25P-2FFVB676I_3_10_1"
				(rectangle
					(start 5.08 6.35)
					(end 27.94 -58.42)
					(stroke
						(width 0.254)
						(type default)
					)
					(fill
						(type background)
					)
				)
				(polyline
					(pts
						(xy 16.51 2.54) (xy 25.4 2.54) (xy 25.4 -55.88) (xy 16.51 -55.88)
					)
					(stroke
						(width 0.254)
						(type default)
					)
					(fill
						(type background)
					)
				)
				(text "GTX 225"
					(at 6.35 2.54 0)
					(effects
						(font
							(size 1.27 1.27)
							(thickness 0.15)
						)
						(justify left bottom)
					)
				)
				(text ""
					(at 50.8 -31.75 0)
					(effects
						(font
							(size 1.27 1.27)
							(thickness 0.15)
						)
						(justify left bottom)
					)
				)
				(text ""
					(at 50.8 -31.75 0)
					(effects
						(font
							(size 1.27 1.27)
							(thickness 0.15)
						)
						(justify left bottom)
					)
				)
				(pin output line
					(at 0 0 0)
					(length 5.08)
					(name "MGTYTXP0_225"
						(effects
							(font
								(size 1.27 1.27)
							)
						)
					)
					(number "AA5"
						(effects
							(font
								(size 1.27 1.27)
							)
						)
					)
				)
				(pin output line
					(at 0 -2.54 0)
					(length 5.08)
					(name "MGTYTXN0_225"
						(effects
							(font
								(size 1.27 1.27)
							)
						)
					)
					(number "AA4"
						(effects
							(font
								(size 1.27 1.27)
							)
						)
					)
				)
				(pin output line
					(at 0 -5.08 0)
					(length 5.08)
					(name "MGTYTXP1_225"
						(effects
							(font
								(size 1.27 1.27)
							)
						)
					)
					(number "W5"
						(effects
							(font
								(size 1.27 1.27)
							)
						)
					)
				)
				(pin output line
					(at 0 -7.62 0)
					(length 5.08)
					(name "MGTYTXN1_225"
						(effects
							(font
								(size 1.27 1.27)
							)
						)
					)
					(number "W4"
						(effects
							(font
								(size 1.27 1.27)
							)
						)
					)
				)
				(pin output line
					(at 0 -10.16 0)
					(length 5.08)
					(name "MGTYTXP2_225"
						(effects
							(font
								(size 1.27 1.27)
							)
						)
					)
					(number "U5"
						(effects
							(font
								(size 1.27 1.27)
							)
						)
					)
				)
				(pin output line
					(at 0 -12.7 0)
					(length 5.08)
					(name "MGTYTXN2_225"
						(effects
							(font
								(size 1.27 1.27)
							)
						)
					)
					(number "U4"
						(effects
							(font
								(size 1.27 1.27)
							)
						)
					)
				)
				(pin output line
					(at 0 -15.24 0)
					(length 5.08)
					(name "MGTYTXP3_225"
						(effects
							(font
								(size 1.27 1.27)
							)
						)
					)
					(number "R5"
						(effects
							(font
								(size 1.27 1.27)
							)
						)
					)
				)
				(pin output line
					(at 0 -17.78 0)
					(length 5.08)
					(name "MGTYTXN3_225"
						(effects
							(font
								(size 1.27 1.27)
							)
						)
					)
					(number "R4"
						(effects
							(font
								(size 1.27 1.27)
							)
						)
					)
				)
				(pin input line
					(at 0 -22.86 0)
					(length 5.08)
					(name "MGTYRXP0_225"
						(effects
							(font
								(size 1.27 1.27)
							)
						)
					)
					(number "Y2"
						(effects
							(font
								(size 1.27 1.27)
							)
						)
					)
				)
				(pin input line
					(at 0 -25.4 0)
					(length 5.08)
					(name "MGTYRXN0_225"
						(effects
							(font
								(size 1.27 1.27)
							)
						)
					)
					(number "Y1"
						(effects
							(font
								(size 1.27 1.27)
							)
						)
					)
				)
				(pin input line
					(at 0 -27.94 0)
					(length 5.08)
					(name "MGTYRXP1_225"
						(effects
							(font
								(size 1.27 1.27)
							)
						)
					)
					(number "V2"
						(effects
							(font
								(size 1.27 1.27)
							)
						)
					)
				)
				(pin input line
					(at 0 -30.48 0)
					(length 5.08)
					(name "MGTYRXN1_225"
						(effects
							(font
								(size 1.27 1.27)
							)
						)
					)
					(number "V1"
						(effects
							(font
								(size 1.27 1.27)
							)
						)
					)
				)
				(pin input line
					(at 0 -33.02 0)
					(length 5.08)
					(name "MGTYRXP2_225"
						(effects
							(font
								(size 1.27 1.27)
							)
						)
					)
					(number "T2"
						(effects
							(font
								(size 1.27 1.27)
							)
						)
					)
				)
				(pin input line
					(at 0 -35.56 0)
					(length 5.08)
					(name "MGTYRXN2_225"
						(effects
							(font
								(size 1.27 1.27)
							)
						)
					)
					(number "T1"
						(effects
							(font
								(size 1.27 1.27)
							)
						)
					)
				)
				(pin input line
					(at 0 -38.1 0)
					(length 5.08)
					(name "MGTYRXP3_225"
						(effects
							(font
								(size 1.27 1.27)
							)
						)
					)
					(number "P2"
						(effects
							(font
								(size 1.27 1.27)
							)
						)
					)
				)
				(pin input line
					(at 0 -40.64 0)
					(length 5.08)
					(name "MGTYRXN3_225"
						(effects
							(font
								(size 1.27 1.27)
							)
						)
					)
					(number "P1"
						(effects
							(font
								(size 1.27 1.27)
							)
						)
					)
				)
				(pin input line
					(at 0 -45.72 0)
					(length 5.08)
					(name "MGTREFCLK0P_225"
						(effects
							(font
								(size 1.27 1.27)
							)
						)
					)
					(number "V7"
						(effects
							(font
								(size 1.27 1.27)
							)
						)
					)
				)
				(pin input line
					(at 0 -48.26 0)
					(length 5.08)
					(name "MGTREFCLK0N_225"
						(effects
							(font
								(size 1.27 1.27)
							)
						)
					)
					(number "V6"
						(effects
							(font
								(size 1.27 1.27)
							)
						)
					)
				)
				(pin input line
					(at 0 -50.8 0)
					(length 5.08)
					(name "MGTREFCLK1P_225"
						(effects
							(font
								(size 1.27 1.27)
							)
						)
					)
					(number "T7"
						(effects
							(font
								(size 1.27 1.27)
							)
						)
					)
				)
				(pin input line
					(at 0 -53.34 0)
					(length 5.08)
					(name "MGTREFCLK1N_225"
						(effects
							(font
								(size 1.27 1.27)
							)
						)
					)
					(number "T6"
						(effects
							(font
								(size 1.27 1.27)
							)
						)
					)
				)
			)
			(symbol "XCAU25P-2FFVB676I_3_11_1"
				(rectangle
					(start 5.08 6.35)
					(end 27.94 -58.42)
					(stroke
						(width 0.254)
						(type default)
					)
					(fill
						(type background)
					)
				)
				(polyline
					(pts
						(xy 16.51 2.54) (xy 25.4 2.54) (xy 25.4 -55.88) (xy 16.51 -55.88)
					)
					(stroke
						(width 0.254)
						(type default)
					)
					(fill
						(type background)
					)
				)
				(text "GTX 226"
					(at 6.35 2.54 0)
					(effects
						(font
							(size 1.27 1.27)
							(thickness 0.15)
						)
						(justify left bottom)
					)
				)
				(text ""
					(at 50.8 -31.75 0)
					(effects
						(font
							(size 1.27 1.27)
							(thickness 0.15)
						)
						(justify left bottom)
					)
				)
				(text ""
					(at 50.8 -31.75 0)
					(effects
						(font
							(size 1.27 1.27)
							(thickness 0.15)
						)
						(justify left bottom)
					)
				)
				(pin output line
					(at 0 0 0)
					(length 5.08)
					(name "MGTYTXP0_226"
						(effects
							(font
								(size 1.27 1.27)
							)
						)
					)
					(number "N5"
						(effects
							(font
								(size 1.27 1.27)
							)
						)
					)
				)
				(pin output line
					(at 0 -2.54 0)
					(length 5.08)
					(name "MGTYTXN0_226"
						(effects
							(font
								(size 1.27 1.27)
							)
						)
					)
					(number "N4"
						(effects
							(font
								(size 1.27 1.27)
							)
						)
					)
				)
				(pin output line
					(at 0 -5.08 0)
					(length 5.08)
					(name "MGTYTXP1_226"
						(effects
							(font
								(size 1.27 1.27)
							)
						)
					)
					(number "L5"
						(effects
							(font
								(size 1.27 1.27)
							)
						)
					)
				)
				(pin output line
					(at 0 -7.62 0)
					(length 5.08)
					(name "MGTYTXN1_226"
						(effects
							(font
								(size 1.27 1.27)
							)
						)
					)
					(number "L4"
						(effects
							(font
								(size 1.27 1.27)
							)
						)
					)
				)
				(pin output line
					(at 0 -10.16 0)
					(length 5.08)
					(name "MGTYTXP2_226"
						(effects
							(font
								(size 1.27 1.27)
							)
						)
					)
					(number "J5"
						(effects
							(font
								(size 1.27 1.27)
							)
						)
					)
				)
				(pin output line
					(at 0 -12.7 0)
					(length 5.08)
					(name "MGTYTXN2_226"
						(effects
							(font
								(size 1.27 1.27)
							)
						)
					)
					(number "J4"
						(effects
							(font
								(size 1.27 1.27)
							)
						)
					)
				)
				(pin output line
					(at 0 -15.24 0)
					(length 5.08)
					(name "MGTYTXP3_226"
						(effects
							(font
								(size 1.27 1.27)
							)
						)
					)
					(number "G5"
						(effects
							(font
								(size 1.27 1.27)
							)
						)
					)
				)
				(pin output line
					(at 0 -17.78 0)
					(length 5.08)
					(name "MGTYTXN3_226"
						(effects
							(font
								(size 1.27 1.27)
							)
						)
					)
					(number "G4"
						(effects
							(font
								(size 1.27 1.27)
							)
						)
					)
				)
				(pin input line
					(at 0 -22.86 0)
					(length 5.08)
					(name "MGTYRXP0_226"
						(effects
							(font
								(size 1.27 1.27)
							)
						)
					)
					(number "M2"
						(effects
							(font
								(size 1.27 1.27)
							)
						)
					)
				)
				(pin input line
					(at 0 -25.4 0)
					(length 5.08)
					(name "MGTYRXN0_226"
						(effects
							(font
								(size 1.27 1.27)
							)
						)
					)
					(number "M1"
						(effects
							(font
								(size 1.27 1.27)
							)
						)
					)
				)
				(pin input line
					(at 0 -27.94 0)
					(length 5.08)
					(name "MGTYRXP1_226"
						(effects
							(font
								(size 1.27 1.27)
							)
						)
					)
					(number "K2"
						(effects
							(font
								(size 1.27 1.27)
							)
						)
					)
				)
				(pin input line
					(at 0 -30.48 0)
					(length 5.08)
					(name "MGTYRXN1_226"
						(effects
							(font
								(size 1.27 1.27)
							)
						)
					)
					(number "K1"
						(effects
							(font
								(size 1.27 1.27)
							)
						)
					)
				)
				(pin input line
					(at 0 -33.02 0)
					(length 5.08)
					(name "MGTYRXP2_226"
						(effects
							(font
								(size 1.27 1.27)
							)
						)
					)
					(number "H2"
						(effects
							(font
								(size 1.27 1.27)
							)
						)
					)
				)
				(pin input line
					(at 0 -35.56 0)
					(length 5.08)
					(name "MGTYRXN2_226"
						(effects
							(font
								(size 1.27 1.27)
							)
						)
					)
					(number "H1"
						(effects
							(font
								(size 1.27 1.27)
							)
						)
					)
				)
				(pin input line
					(at 0 -38.1 0)
					(length 5.08)
					(name "MGTYRXP3_226"
						(effects
							(font
								(size 1.27 1.27)
							)
						)
					)
					(number "F2"
						(effects
							(font
								(size 1.27 1.27)
							)
						)
					)
				)
				(pin input line
					(at 0 -40.64 0)
					(length 5.08)
					(name "MGTYRXN3_226"
						(effects
							(font
								(size 1.27 1.27)
							)
						)
					)
					(number "F1"
						(effects
							(font
								(size 1.27 1.27)
							)
						)
					)
				)
				(pin input line
					(at 0 -45.72 0)
					(length 5.08)
					(name "MGTREFCLK0P_226"
						(effects
							(font
								(size 1.27 1.27)
							)
						)
					)
					(number "P7"
						(effects
							(font
								(size 1.27 1.27)
							)
						)
					)
				)
				(pin input line
					(at 0 -48.26 0)
					(length 5.08)
					(name "MGTREFCLK0N_226"
						(effects
							(font
								(size 1.27 1.27)
							)
						)
					)
					(number "P6"
						(effects
							(font
								(size 1.27 1.27)
							)
						)
					)
				)
				(pin input line
					(at 0 -50.8 0)
					(length 5.08)
					(name "MGTREFCLK1P_226"
						(effects
							(font
								(size 1.27 1.27)
							)
						)
					)
					(number "M7"
						(effects
							(font
								(size 1.27 1.27)
							)
						)
					)
				)
				(pin input line
					(at 0 -53.34 0)
					(length 5.08)
					(name "MGTREFCLK1N_226"
						(effects
							(font
								(size 1.27 1.27)
							)
						)
					)
					(number "M6"
						(effects
							(font
								(size 1.27 1.27)
							)
						)
					)
				)
			)
			(symbol "XCAU25P-2FFVB676I_3_12_1"
				(rectangle
					(start 5.08 2.54)
					(end 35.56 -27.94)
					(stroke
						(width 0.254)
						(type default)
					)
					(fill
						(type background)
					)
				)
				(text ""
					(at 21.59 -3.175 900)
					(effects
						(font
							(size 1.27 1.27)
							(thickness 0.15)
						)
						(justify right top)
					)
				)
				(text ""
					(at 21.59 -3.175 900)
					(effects
						(font
							(size 1.27 1.27)
							(thickness 0.15)
						)
						(justify right top)
					)
				)
				(pin input line
					(at 0 0 0)
					(length 5.08)
					(name "MGTAVTT_R"
						(effects
							(font
								(size 1.27 1.27)
							)
						)
					)
					(number "A7"
						(effects
							(font
								(size 1.27 1.27)
							)
						)
					)
				)
				(pin passive line
					(at 0 0 0)
					(length 5.08)
					(hide yes)
					(name "MGTAVTT_R"
						(effects
							(font
								(size 1.27 1.27)
							)
						)
					)
					(number "AB5"
						(effects
							(font
								(size 1.27 1.27)
							)
						)
					)
				)
				(pin passive line
					(at 0 0 0)
					(length 5.08)
					(hide yes)
					(name "MGTAVTT_R"
						(effects
							(font
								(size 1.27 1.27)
							)
						)
					)
					(number "AE7"
						(effects
							(font
								(size 1.27 1.27)
							)
						)
					)
				)
				(pin passive line
					(at 0 0 0)
					(length 5.08)
					(hide yes)
					(name "MGTAVTT_R"
						(effects
							(font
								(size 1.27 1.27)
							)
						)
					)
					(number "C7"
						(effects
							(font
								(size 1.27 1.27)
							)
						)
					)
				)
				(pin passive line
					(at 0 0 0)
					(length 5.08)
					(hide yes)
					(name "MGTAVTT_R"
						(effects
							(font
								(size 1.27 1.27)
							)
						)
					)
					(number "E7"
						(effects
							(font
								(size 1.27 1.27)
							)
						)
					)
				)
				(pin passive line
					(at 0 0 0)
					(length 5.08)
					(hide yes)
					(name "MGTAVTT_R"
						(effects
							(font
								(size 1.27 1.27)
							)
						)
					)
					(number "F5"
						(effects
							(font
								(size 1.27 1.27)
							)
						)
					)
				)
				(pin passive line
					(at 0 0 0)
					(length 5.08)
					(hide yes)
					(name "MGTAVTT_R"
						(effects
							(font
								(size 1.27 1.27)
							)
						)
					)
					(number "G7"
						(effects
							(font
								(size 1.27 1.27)
							)
						)
					)
				)
				(pin passive line
					(at 0 0 0)
					(length 5.08)
					(hide yes)
					(name "MGTAVTT_R"
						(effects
							(font
								(size 1.27 1.27)
							)
						)
					)
					(number "H5"
						(effects
							(font
								(size 1.27 1.27)
							)
						)
					)
				)
				(pin passive line
					(at 0 0 0)
					(length 5.08)
					(hide yes)
					(name "MGTAVTT_R"
						(effects
							(font
								(size 1.27 1.27)
							)
						)
					)
					(number "K5"
						(effects
							(font
								(size 1.27 1.27)
							)
						)
					)
				)
				(pin passive line
					(at 0 0 0)
					(length 5.08)
					(hide yes)
					(name "MGTAVTT_R"
						(effects
							(font
								(size 1.27 1.27)
							)
						)
					)
					(number "M5"
						(effects
							(font
								(size 1.27 1.27)
							)
						)
					)
				)
				(pin passive line
					(at 0 0 0)
					(length 5.08)
					(hide yes)
					(name "MGTAVTT_R"
						(effects
							(font
								(size 1.27 1.27)
							)
						)
					)
					(number "P5"
						(effects
							(font
								(size 1.27 1.27)
							)
						)
					)
				)
				(pin passive line
					(at 0 0 0)
					(length 5.08)
					(hide yes)
					(name "MGTAVTT_R"
						(effects
							(font
								(size 1.27 1.27)
							)
						)
					)
					(number "T5"
						(effects
							(font
								(size 1.27 1.27)
							)
						)
					)
				)
				(pin passive line
					(at 0 0 0)
					(length 5.08)
					(hide yes)
					(name "MGTAVTT_R"
						(effects
							(font
								(size 1.27 1.27)
							)
						)
					)
					(number "V5"
						(effects
							(font
								(size 1.27 1.27)
							)
						)
					)
				)
				(pin passive line
					(at 0 0 0)
					(length 5.08)
					(hide yes)
					(name "MGTAVTT_R"
						(effects
							(font
								(size 1.27 1.27)
							)
						)
					)
					(number "Y5"
						(effects
							(font
								(size 1.27 1.27)
							)
						)
					)
				)
				(pin power_in line
					(at 0 -2.54 0)
					(length 5.08)
					(name "MGTAVCC_R"
						(effects
							(font
								(size 1.27 1.27)
							)
						)
					)
					(number "AA7"
						(effects
							(font
								(size 1.27 1.27)
							)
						)
					)
				)
				(pin passive line
					(at 0 -2.54 0)
					(length 5.08)
					(hide yes)
					(name "MGTAVCC_R"
						(effects
							(font
								(size 1.27 1.27)
							)
						)
					)
					(number "AC7"
						(effects
							(font
								(size 1.27 1.27)
							)
						)
					)
				)
				(pin passive line
					(at 0 -2.54 0)
					(length 5.08)
					(hide yes)
					(name "MGTAVCC_R"
						(effects
							(font
								(size 1.27 1.27)
							)
						)
					)
					(number "J7"
						(effects
							(font
								(size 1.27 1.27)
							)
						)
					)
				)
				(pin passive line
					(at 0 -2.54 0)
					(length 5.08)
					(hide yes)
					(name "MGTAVCC_R"
						(effects
							(font
								(size 1.27 1.27)
							)
						)
					)
					(number "L7"
						(effects
							(font
								(size 1.27 1.27)
							)
						)
					)
				)
				(pin passive line
					(at 0 -2.54 0)
					(length 5.08)
					(hide yes)
					(name "MGTAVCC_R"
						(effects
							(font
								(size 1.27 1.27)
							)
						)
					)
					(number "N7"
						(effects
							(font
								(size 1.27 1.27)
							)
						)
					)
				)
				(pin passive line
					(at 0 -2.54 0)
					(length 5.08)
					(hide yes)
					(name "MGTAVCC_R"
						(effects
							(font
								(size 1.27 1.27)
							)
						)
					)
					(number "W7"
						(effects
							(font
								(size 1.27 1.27)
							)
						)
					)
				)
				(pin input line
					(at 0 -5.08 0)
					(length 5.08)
					(name "MGTRREF_R"
						(effects
							(font
								(size 1.27 1.27)
							)
						)
					)
					(number "AD9"
						(effects
							(font
								(size 1.27 1.27)
							)
						)
					)
				)
				(pin power_in line
					(at 0 -7.62 0)
					(length 5.08)
					(name "MGTVCCAUX_R"
						(effects
							(font
								(size 1.27 1.27)
							)
						)
					)
					(number "R7"
						(effects
							(font
								(size 1.27 1.27)
							)
						)
					)
				)
				(pin passive line
					(at 0 -7.62 0)
					(length 5.08)
					(hide yes)
					(name "MGTVCCAUX_R"
						(effects
							(font
								(size 1.27 1.27)
							)
						)
					)
					(number "U7"
						(effects
							(font
								(size 1.27 1.27)
							)
						)
					)
				)
				(pin input line
					(at 0 -10.16 0)
					(length 5.08)
					(name "MGTAVTTRCAL_R"
						(effects
							(font
								(size 1.27 1.27)
							)
						)
					)
					(number "AD8"
						(effects
							(font
								(size 1.27 1.27)
							)
						)
					)
				)
				(pin input line
					(at 0 -20.32 0)
					(length 5.08)
					(name "RSVDGND"
						(effects
							(font
								(size 1.27 1.27)
							)
						)
					)
					(number "W11"
						(effects
							(font
								(size 1.27 1.27)
							)
						)
					)
				)
				(pin input line
					(at 0 -22.86 0)
					(length 5.08)
					(name "GNDADC"
						(effects
							(font
								(size 1.27 1.27)
							)
						)
					)
					(number "N13"
						(effects
							(font
								(size 1.27 1.27)
							)
						)
					)
				)
				(pin power_in line
					(at 0 -25.4 0)
					(length 5.08)
					(name "GND"
						(effects
							(font
								(size 1.27 1.27)
							)
						)
					)
					(number "A1"
						(effects
							(font
								(size 1.27 1.27)
							)
						)
					)
				)
				(pin passive line
					(at 0 -25.4 0)
					(length 5.08)
					(hide yes)
					(name "GND"
						(effects
							(font
								(size 1.27 1.27)
							)
						)
					)
					(number "A11"
						(effects
							(font
								(size 1.27 1.27)
							)
						)
					)
				)
				(pin passive line
					(at 0 -25.4 0)
					(length 5.08)
					(hide yes)
					(name "GND"
						(effects
							(font
								(size 1.27 1.27)
							)
						)
					)
					(number "A16"
						(effects
							(font
								(size 1.27 1.27)
							)
						)
					)
				)
				(pin passive line
					(at 0 -25.4 0)
					(length 5.08)
					(hide yes)
					(name "GND"
						(effects
							(font
								(size 1.27 1.27)
							)
						)
					)
					(number "A2"
						(effects
							(font
								(size 1.27 1.27)
							)
						)
					)
				)
				(pin passive line
					(at 0 -25.4 0)
					(length 5.08)
					(hide yes)
					(name "GND"
						(effects
							(font
								(size 1.27 1.27)
							)
						)
					)
					(number "A21"
						(effects
							(font
								(size 1.27 1.27)
							)
						)
					)
				)
				(pin passive line
					(at 0 -25.4 0)
					(length 5.08)
					(hide yes)
					(name "GND"
						(effects
							(font
								(size 1.27 1.27)
							)
						)
					)
					(number "A26"
						(effects
							(font
								(size 1.27 1.27)
							)
						)
					)
				)
				(pin passive line
					(at 0 -25.4 0)
					(length 5.08)
					(hide yes)
					(name "GND"
						(effects
							(font
								(size 1.27 1.27)
							)
						)
					)
					(number "A5"
						(effects
							(font
								(size 1.27 1.27)
							)
						)
					)
				)
				(pin passive line
					(at 0 -25.4 0)
					(length 5.08)
					(hide yes)
					(name "GND"
						(effects
							(font
								(size 1.27 1.27)
							)
						)
					)
					(number "A6"
						(effects
							(font
								(size 1.27 1.27)
							)
						)
					)
				)
				(pin passive line
					(at 0 -25.4 0)
					(length 5.08)
					(hide yes)
					(name "GND"
						(effects
							(font
								(size 1.27 1.27)
							)
						)
					)
					(number "A8"
						(effects
							(font
								(size 1.27 1.27)
							)
						)
					)
				)
				(pin passive line
					(at 0 -25.4 0)
					(length 5.08)
					(hide yes)
					(name "GND"
						(effects
							(font
								(size 1.27 1.27)
							)
						)
					)
					(number "AA1"
						(effects
							(font
								(size 1.27 1.27)
							)
						)
					)
				)
				(pin passive line
					(at 0 -25.4 0)
					(length 5.08)
					(hide yes)
					(name "GND"
						(effects
							(font
								(size 1.27 1.27)
							)
						)
					)
					(number "AA16"
						(effects
							(font
								(size 1.27 1.27)
							)
						)
					)
				)
				(pin passive line
					(at 0 -25.4 0)
					(length 5.08)
					(hide yes)
					(name "GND"
						(effects
							(font
								(size 1.27 1.27)
							)
						)
					)
					(number "AA2"
						(effects
							(font
								(size 1.27 1.27)
							)
						)
					)
				)
				(pin passive line
					(at 0 -25.4 0)
					(length 5.08)
					(hide yes)
					(name "GND"
						(effects
							(font
								(size 1.27 1.27)
							)
						)
					)
					(number "AA26"
						(effects
							(font
								(size 1.27 1.27)
							)
						)
					)
				)
				(pin passive line
					(at 0 -25.4 0)
					(length 5.08)
					(hide yes)
					(name "GND"
						(effects
							(font
								(size 1.27 1.27)
							)
						)
					)
					(number "AA3"
						(effects
							(font
								(size 1.27 1.27)
							)
						)
					)
				)
				(pin passive line
					(at 0 -25.4 0)
					(length 5.08)
					(hide yes)
					(name "GND"
						(effects
							(font
								(size 1.27 1.27)
							)
						)
					)
					(number "AA6"
						(effects
							(font
								(size 1.27 1.27)
							)
						)
					)
				)
				(pin passive line
					(at 0 -25.4 0)
					(length 5.08)
					(hide yes)
					(name "GND"
						(effects
							(font
								(size 1.27 1.27)
							)
						)
					)
					(number "AA8"
						(effects
							(font
								(size 1.27 1.27)
							)
						)
					)
				)
				(pin passive line
					(at 0 -25.4 0)
					(length 5.08)
					(hide yes)
					(name "GND"
						(effects
							(font
								(size 1.27 1.27)
							)
						)
					)
					(number "AB13"
						(effects
							(font
								(size 1.27 1.27)
							)
						)
					)
				)
				(pin passive line
					(at 0 -25.4 0)
					(length 5.08)
					(hide yes)
					(name "GND"
						(effects
							(font
								(size 1.27 1.27)
							)
						)
					)
					(number "AB23"
						(effects
							(font
								(size 1.27 1.27)
							)
						)
					)
				)
				(pin passive line
					(at 0 -25.4 0)
					(length 5.08)
					(hide yes)
					(name "GND"
						(effects
							(font
								(size 1.27 1.27)
							)
						)
					)
					(number "AB3"
						(effects
							(font
								(size 1.27 1.27)
							)
						)
					)
				)
				(pin passive line
					(at 0 -25.4 0)
					(length 5.08)
					(hide yes)
					(name "GND"
						(effects
							(font
								(size 1.27 1.27)
							)
						)
					)
					(number "AB4"
						(effects
							(font
								(size 1.27 1.27)
							)
						)
					)
				)
				(pin passive line
					(at 0 -25.4 0)
					(length 5.08)
					(hide yes)
					(name "GND"
						(effects
							(font
								(size 1.27 1.27)
							)
						)
					)
					(number "AB8"
						(effects
							(font
								(size 1.27 1.27)
							)
						)
					)
				)
				(pin passive line
					(at 0 -25.4 0)
					(length 5.08)
					(hide yes)
					(name "GND"
						(effects
							(font
								(size 1.27 1.27)
							)
						)
					)
					(number "AC1"
						(effects
							(font
								(size 1.27 1.27)
							)
						)
					)
				)
				(pin passive line
					(at 0 -25.4 0)
					(length 5.08)
					(hide yes)
					(name "GND"
						(effects
							(font
								(size 1.27 1.27)
							)
						)
					)
					(number "AC10"
						(effects
							(font
								(size 1.27 1.27)
							)
						)
					)
				)
				(pin passive line
					(at 0 -25.4 0)
					(length 5.08)
					(hide yes)
					(name "GND"
						(effects
							(font
								(size 1.27 1.27)
							)
						)
					)
					(number "AC2"
						(effects
							(font
								(size 1.27 1.27)
							)
						)
					)
				)
				(pin passive line
					(at 0 -25.4 0)
					(length 5.08)
					(hide yes)
					(name "GND"
						(effects
							(font
								(size 1.27 1.27)
							)
						)
					)
					(number "AC20"
						(effects
							(font
								(size 1.27 1.27)
							)
						)
					)
				)
				(pin passive line
					(at 0 -25.4 0)
					(length 5.08)
					(hide yes)
					(name "GND"
						(effects
							(font
								(size 1.27 1.27)
							)
						)
					)
					(number "AC25"
						(effects
							(font
								(size 1.27 1.27)
							)
						)
					)
				)
				(pin passive line
					(at 0 -25.4 0)
					(length 5.08)
					(hide yes)
					(name "GND"
						(effects
							(font
								(size 1.27 1.27)
							)
						)
					)
					(number "AC3"
						(effects
							(font
								(size 1.27 1.27)
							)
						)
					)
				)
				(pin passive line
					(at 0 -25.4 0)
					(length 5.08)
					(hide yes)
					(name "GND"
						(effects
							(font
								(size 1.27 1.27)
							)
						)
					)
					(number "AC6"
						(effects
							(font
								(size 1.27 1.27)
							)
						)
					)
				)
				(pin passive line
					(at 0 -25.4 0)
					(length 5.08)
					(hide yes)
					(name "GND"
						(effects
							(font
								(size 1.27 1.27)
							)
						)
					)
					(number "AC8"
						(effects
							(font
								(size 1.27 1.27)
							)
						)
					)
				)
				(pin passive line
					(at 0 -25.4 0)
					(length 5.08)
					(hide yes)
					(name "GND"
						(effects
							(font
								(size 1.27 1.27)
							)
						)
					)
					(number "AC9"
						(effects
							(font
								(size 1.27 1.27)
							)
						)
					)
				)
				(pin passive line
					(at 0 -25.4 0)
					(length 5.08)
					(hide yes)
					(name "GND"
						(effects
							(font
								(size 1.27 1.27)
							)
						)
					)
					(number "AD10"
						(effects
							(font
								(size 1.27 1.27)
							)
						)
					)
				)
				(pin passive line
					(at 0 -25.4 0)
					(length 5.08)
					(hide yes)
					(name "GND"
						(effects
							(font
								(size 1.27 1.27)
							)
						)
					)
					(number "AD17"
						(effects
							(font
								(size 1.27 1.27)
							)
						)
					)
				)
				(pin passive line
					(at 0 -25.4 0)
					(length 5.08)
					(hide yes)
					(name "GND"
						(effects
							(font
								(size 1.27 1.27)
							)
						)
					)
					(number "AD3"
						(effects
							(font
								(size 1.27 1.27)
							)
						)
					)
				)
				(pin passive line
					(at 0 -25.4 0)
					(length 5.08)
					(hide yes)
					(name "GND"
						(effects
							(font
								(size 1.27 1.27)
							)
						)
					)
					(number "AD4"
						(effects
							(font
								(size 1.27 1.27)
							)
						)
					)
				)
				(pin passive line
					(at 0 -25.4 0)
					(length 5.08)
					(hide yes)
					(name "GND"
						(effects
							(font
								(size 1.27 1.27)
							)
						)
					)
					(number "AD5"
						(effects
							(font
								(size 1.27 1.27)
							)
						)
					)
				)
				(pin passive line
					(at 0 -25.4 0)
					(length 5.08)
					(hide yes)
					(name "GND"
						(effects
							(font
								(size 1.27 1.27)
							)
						)
					)
					(number "AE1"
						(effects
							(font
								(size 1.27 1.27)
							)
						)
					)
				)
				(pin passive line
					(at 0 -25.4 0)
					(length 5.08)
					(hide yes)
					(name "GND"
						(effects
							(font
								(size 1.27 1.27)
							)
						)
					)
					(number "AE10"
						(effects
							(font
								(size 1.27 1.27)
							)
						)
					)
				)
				(pin passive line
					(at 0 -25.4 0)
					(length 5.08)
					(hide yes)
					(name "GND"
						(effects
							(font
								(size 1.27 1.27)
							)
						)
					)
					(number "AE14"
						(effects
							(font
								(size 1.27 1.27)
							)
						)
					)
				)
				(pin passive line
					(at 0 -25.4 0)
					(length 5.08)
					(hide yes)
					(name "GND"
						(effects
							(font
								(size 1.27 1.27)
							)
						)
					)
					(number "AE19"
						(effects
							(font
								(size 1.27 1.27)
							)
						)
					)
				)
				(pin passive line
					(at 0 -25.4 0)
					(length 5.08)
					(hide yes)
					(name "GND"
						(effects
							(font
								(size 1.27 1.27)
							)
						)
					)
					(number "AE2"
						(effects
							(font
								(size 1.27 1.27)
							)
						)
					)
				)
				(pin passive line
					(at 0 -25.4 0)
					(length 5.08)
					(hide yes)
					(name "GND"
						(effects
							(font
								(size 1.27 1.27)
							)
						)
					)
					(number "AE24"
						(effects
							(font
								(size 1.27 1.27)
							)
						)
					)
				)
				(pin passive line
					(at 0 -25.4 0)
					(length 5.08)
					(hide yes)
					(name "GND"
						(effects
							(font
								(size 1.27 1.27)
							)
						)
					)
					(number "AE5"
						(effects
							(font
								(size 1.27 1.27)
							)
						)
					)
				)
				(pin passive line
					(at 0 -25.4 0)
					(length 5.08)
					(hide yes)
					(name "GND"
						(effects
							(font
								(size 1.27 1.27)
							)
						)
					)
					(number "AE6"
						(effects
							(font
								(size 1.27 1.27)
							)
						)
					)
				)
				(pin passive line
					(at 0 -25.4 0)
					(length 5.08)
					(hide yes)
					(name "GND"
						(effects
							(font
								(size 1.27 1.27)
							)
						)
					)
					(number "AF10"
						(effects
							(font
								(size 1.27 1.27)
							)
						)
					)
				)
				(pin passive line
					(at 0 -25.4 0)
					(length 5.08)
					(hide yes)
					(name "GND"
						(effects
							(font
								(size 1.27 1.27)
							)
						)
					)
					(number "AF11"
						(effects
							(font
								(size 1.27 1.27)
							)
						)
					)
				)
				(pin passive line
					(at 0 -25.4 0)
					(length 5.08)
					(hide yes)
					(name "GND"
						(effects
							(font
								(size 1.27 1.27)
							)
						)
					)
					(number "AF16"
						(effects
							(font
								(size 1.27 1.27)
							)
						)
					)
				)
				(pin passive line
					(at 0 -25.4 0)
					(length 5.08)
					(hide yes)
					(name "GND"
						(effects
							(font
								(size 1.27 1.27)
							)
						)
					)
					(number "AF21"
						(effects
							(font
								(size 1.27 1.27)
							)
						)
					)
				)
				(pin passive line
					(at 0 -25.4 0)
					(length 5.08)
					(hide yes)
					(name "GND"
						(effects
							(font
								(size 1.27 1.27)
							)
						)
					)
					(number "AF26"
						(effects
							(font
								(size 1.27 1.27)
							)
						)
					)
				)
				(pin passive line
					(at 0 -25.4 0)
					(length 5.08)
					(hide yes)
					(name "GND"
						(effects
							(font
								(size 1.27 1.27)
							)
						)
					)
					(number "AF3"
						(effects
							(font
								(size 1.27 1.27)
							)
						)
					)
				)
				(pin passive line
					(at 0 -25.4 0)
					(length 5.08)
					(hide yes)
					(name "GND"
						(effects
							(font
								(size 1.27 1.27)
							)
						)
					)
					(number "AF4"
						(effects
							(font
								(size 1.27 1.27)
							)
						)
					)
				)
				(pin passive line
					(at 0 -25.4 0)
					(length 5.08)
					(hide yes)
					(name "GND"
						(effects
							(font
								(size 1.27 1.27)
							)
						)
					)
					(number "AF5"
						(effects
							(font
								(size 1.27 1.27)
							)
						)
					)
				)
				(pin passive line
					(at 0 -25.4 0)
					(length 5.08)
					(hide yes)
					(name "GND"
						(effects
							(font
								(size 1.27 1.27)
							)
						)
					)
					(number "AF8"
						(effects
							(font
								(size 1.27 1.27)
							)
						)
					)
				)
				(pin passive line
					(at 0 -25.4 0)
					(length 5.08)
					(hide yes)
					(name "GND"
						(effects
							(font
								(size 1.27 1.27)
							)
						)
					)
					(number "AF9"
						(effects
							(font
								(size 1.27 1.27)
							)
						)
					)
				)
				(pin passive line
					(at 0 -25.4 0)
					(length 5.08)
					(hide yes)
					(name "GND"
						(effects
							(font
								(size 1.27 1.27)
							)
						)
					)
					(number "B13"
						(effects
							(font
								(size 1.27 1.27)
							)
						)
					)
				)
				(pin passive line
					(at 0 -25.4 0)
					(length 5.08)
					(hide yes)
					(name "GND"
						(effects
							(font
								(size 1.27 1.27)
							)
						)
					)
					(number "B18"
						(effects
							(font
								(size 1.27 1.27)
							)
						)
					)
				)
				(pin passive line
					(at 0 -25.4 0)
					(length 5.08)
					(hide yes)
					(name "GND"
						(effects
							(font
								(size 1.27 1.27)
							)
						)
					)
					(number "B23"
						(effects
							(font
								(size 1.27 1.27)
							)
						)
					)
				)
				(pin passive line
					(at 0 -25.4 0)
					(length 5.08)
					(hide yes)
					(name "GND"
						(effects
							(font
								(size 1.27 1.27)
							)
						)
					)
					(number "B3"
						(effects
							(font
								(size 1.27 1.27)
							)
						)
					)
				)
				(pin passive line
					(at 0 -25.4 0)
					(length 5.08)
					(hide yes)
					(name "GND"
						(effects
							(font
								(size 1.27 1.27)
							)
						)
					)
					(number "B4"
						(effects
							(font
								(size 1.27 1.27)
							)
						)
					)
				)
				(pin passive line
					(at 0 -25.4 0)
					(length 5.08)
					(hide yes)
					(name "GND"
						(effects
							(font
								(size 1.27 1.27)
							)
						)
					)
					(number "B5"
						(effects
							(font
								(size 1.27 1.27)
							)
						)
					)
				)
				(pin passive line
					(at 0 -25.4 0)
					(length 5.08)
					(hide yes)
					(name "GND"
						(effects
							(font
								(size 1.27 1.27)
							)
						)
					)
					(number "B8"
						(effects
							(font
								(size 1.27 1.27)
							)
						)
					)
				)
				(pin passive line
					(at 0 -25.4 0)
					(length 5.08)
					(hide yes)
					(name "GND"
						(effects
							(font
								(size 1.27 1.27)
							)
						)
					)
					(number "C1"
						(effects
							(font
								(size 1.27 1.27)
							)
						)
					)
				)
				(pin passive line
					(at 0 -25.4 0)
					(length 5.08)
					(hide yes)
					(name "GND"
						(effects
							(font
								(size 1.27 1.27)
							)
						)
					)
					(number "C10"
						(effects
							(font
								(size 1.27 1.27)
							)
						)
					)
				)
				(pin passive line
					(at 0 -25.4 0)
					(length 5.08)
					(hide yes)
					(name "GND"
						(effects
							(font
								(size 1.27 1.27)
							)
						)
					)
					(number "C15"
						(effects
							(font
								(size 1.27 1.27)
							)
						)
					)
				)
				(pin passive line
					(at 0 -25.4 0)
					(length 5.08)
					(hide yes)
					(name "GND"
						(effects
							(font
								(size 1.27 1.27)
							)
						)
					)
					(number "C2"
						(effects
							(font
								(size 1.27 1.27)
							)
						)
					)
				)
				(pin passive line
					(at 0 -25.4 0)
					(length 5.08)
					(hide yes)
					(name "GND"
						(effects
							(font
								(size 1.27 1.27)
							)
						)
					)
					(number "C25"
						(effects
							(font
								(size 1.27 1.27)
							)
						)
					)
				)
				(pin passive line
					(at 0 -25.4 0)
					(length 5.08)
					(hide yes)
					(name "GND"
						(effects
							(font
								(size 1.27 1.27)
							)
						)
					)
					(number "C5"
						(effects
							(font
								(size 1.27 1.27)
							)
						)
					)
				)
				(pin passive line
					(at 0 -25.4 0)
					(length 5.08)
					(hide yes)
					(name "GND"
						(effects
							(font
								(size 1.27 1.27)
							)
						)
					)
					(number "C6"
						(effects
							(font
								(size 1.27 1.27)
							)
						)
					)
				)
				(pin passive line
					(at 0 -25.4 0)
					(length 5.08)
					(hide yes)
					(name "GND"
						(effects
							(font
								(size 1.27 1.27)
							)
						)
					)
					(number "C8"
						(effects
							(font
								(size 1.27 1.27)
							)
						)
					)
				)
				(pin passive line
					(at 0 -25.4 0)
					(length 5.08)
					(hide yes)
					(name "GND"
						(effects
							(font
								(size 1.27 1.27)
							)
						)
					)
					(number "D12"
						(effects
							(font
								(size 1.27 1.27)
							)
						)
					)
				)
				(pin passive line
					(at 0 -25.4 0)
					(length 5.08)
					(hide yes)
					(name "GND"
						(effects
							(font
								(size 1.27 1.27)
							)
						)
					)
					(number "D22"
						(effects
							(font
								(size 1.27 1.27)
							)
						)
					)
				)
				(pin passive line
					(at 0 -25.4 0)
					(length 5.08)
					(hide yes)
					(name "GND"
						(effects
							(font
								(size 1.27 1.27)
							)
						)
					)
					(number "D3"
						(effects
							(font
								(size 1.27 1.27)
							)
						)
					)
				)
				(pin passive line
					(at 0 -25.4 0)
					(length 5.08)
					(hide yes)
					(name "GND"
						(effects
							(font
								(size 1.27 1.27)
							)
						)
					)
					(number "D4"
						(effects
							(font
								(size 1.27 1.27)
							)
						)
					)
				)
				(pin passive line
					(at 0 -25.4 0)
					(length 5.08)
					(hide yes)
					(name "GND"
						(effects
							(font
								(size 1.27 1.27)
							)
						)
					)
					(number "D5"
						(effects
							(font
								(size 1.27 1.27)
							)
						)
					)
				)
				(pin passive line
					(at 0 -25.4 0)
					(length 5.08)
					(hide yes)
					(name "GND"
						(effects
							(font
								(size 1.27 1.27)
							)
						)
					)
					(number "D8"
						(effects
							(font
								(size 1.27 1.27)
							)
						)
					)
				)
				(pin passive line
					(at 0 -25.4 0)
					(length 5.08)
					(hide yes)
					(name "GND"
						(effects
							(font
								(size 1.27 1.27)
							)
						)
					)
					(number "E1"
						(effects
							(font
								(size 1.27 1.27)
							)
						)
					)
				)
				(pin passive line
					(at 0 -25.4 0)
					(length 5.08)
					(hide yes)
					(name "GND"
						(effects
							(font
								(size 1.27 1.27)
							)
						)
					)
					(number "E19"
						(effects
							(font
								(size 1.27 1.27)
							)
						)
					)
				)
				(pin passive line
					(at 0 -25.4 0)
					(length 5.08)
					(hide yes)
					(name "GND"
						(effects
							(font
								(size 1.27 1.27)
							)
						)
					)
					(number "E2"
						(effects
							(font
								(size 1.27 1.27)
							)
						)
					)
				)
				(pin passive line
					(at 0 -25.4 0)
					(length 5.08)
					(hide yes)
					(name "GND"
						(effects
							(font
								(size 1.27 1.27)
							)
						)
					)
					(number "E3"
						(effects
							(font
								(size 1.27 1.27)
							)
						)
					)
				)
				(pin passive line
					(at 0 -25.4 0)
					(length 5.08)
					(hide yes)
					(name "GND"
						(effects
							(font
								(size 1.27 1.27)
							)
						)
					)
					(number "E6"
						(effects
							(font
								(size 1.27 1.27)
							)
						)
					)
				)
				(pin passive line
					(at 0 -25.4 0)
					(length 5.08)
					(hide yes)
					(name "GND"
						(effects
							(font
								(size 1.27 1.27)
							)
						)
					)
					(number "E8"
						(effects
							(font
								(size 1.27 1.27)
							)
						)
					)
				)
				(pin passive line
					(at 0 -25.4 0)
					(length 5.08)
					(hide yes)
					(name "GND"
						(effects
							(font
								(size 1.27 1.27)
							)
						)
					)
					(number "F11"
						(effects
							(font
								(size 1.27 1.27)
							)
						)
					)
				)
				(pin passive line
					(at 0 -25.4 0)
					(length 5.08)
					(hide yes)
					(name "GND"
						(effects
							(font
								(size 1.27 1.27)
							)
						)
					)
					(number "F16"
						(effects
							(font
								(size 1.27 1.27)
							)
						)
					)
				)
				(pin passive line
					(at 0 -25.4 0)
					(length 5.08)
					(hide yes)
					(name "GND"
						(effects
							(font
								(size 1.27 1.27)
							)
						)
					)
					(number "F21"
						(effects
							(font
								(size 1.27 1.27)
							)
						)
					)
				)
				(pin passive line
					(at 0 -25.4 0)
					(length 5.08)
					(hide yes)
					(name "GND"
						(effects
							(font
								(size 1.27 1.27)
							)
						)
					)
					(number "F26"
						(effects
							(font
								(size 1.27 1.27)
							)
						)
					)
				)
				(pin passive line
					(at 0 -25.4 0)
					(length 5.08)
					(hide yes)
					(name "GND"
						(effects
							(font
								(size 1.27 1.27)
							)
						)
					)
					(number "F3"
						(effects
							(font
								(size 1.27 1.27)
							)
						)
					)
				)
				(pin passive line
					(at 0 -25.4 0)
					(length 5.08)
					(hide yes)
					(name "GND"
						(effects
							(font
								(size 1.27 1.27)
							)
						)
					)
					(number "F4"
						(effects
							(font
								(size 1.27 1.27)
							)
						)
					)
				)
				(pin passive line
					(at 0 -25.4 0)
					(length 5.08)
					(hide yes)
					(name "GND"
						(effects
							(font
								(size 1.27 1.27)
							)
						)
					)
					(number "F8"
						(effects
							(font
								(size 1.27 1.27)
							)
						)
					)
				)
				(pin passive line
					(at 0 -25.4 0)
					(length 5.08)
					(hide yes)
					(name "GND"
						(effects
							(font
								(size 1.27 1.27)
							)
						)
					)
					(number "G1"
						(effects
							(font
								(size 1.27 1.27)
							)
						)
					)
				)
				(pin passive line
					(at 0 -25.4 0)
					(length 5.08)
					(hide yes)
					(name "GND"
						(effects
							(font
								(size 1.27 1.27)
							)
						)
					)
					(number "G13"
						(effects
							(font
								(size 1.27 1.27)
							)
						)
					)
				)
				(pin passive line
					(at 0 -25.4 0)
					(length 5.08)
					(hide yes)
					(name "GND"
						(effects
							(font
								(size 1.27 1.27)
							)
						)
					)
					(number "G2"
						(effects
							(font
								(size 1.27 1.27)
							)
						)
					)
				)
				(pin passive line
					(at 0 -25.4 0)
					(length 5.08)
					(hide yes)
					(name "GND"
						(effects
							(font
								(size 1.27 1.27)
							)
						)
					)
					(number "G23"
						(effects
							(font
								(size 1.27 1.27)
							)
						)
					)
				)
				(pin passive line
					(at 0 -25.4 0)
					(length 5.08)
					(hide yes)
					(name "GND"
						(effects
							(font
								(size 1.27 1.27)
							)
						)
					)
					(number "G3"
						(effects
							(font
								(size 1.27 1.27)
							)
						)
					)
				)
				(pin passive line
					(at 0 -25.4 0)
					(length 5.08)
					(hide yes)
					(name "GND"
						(effects
							(font
								(size 1.27 1.27)
							)
						)
					)
					(number "G6"
						(effects
							(font
								(size 1.27 1.27)
							)
						)
					)
				)
				(pin passive line
					(at 0 -25.4 0)
					(length 5.08)
					(hide yes)
					(name "GND"
						(effects
							(font
								(size 1.27 1.27)
							)
						)
					)
					(number "G8"
						(effects
							(font
								(size 1.27 1.27)
							)
						)
					)
				)
				(pin passive line
					(at 0 -25.4 0)
					(length 5.08)
					(hide yes)
					(name "GND"
						(effects
							(font
								(size 1.27 1.27)
							)
						)
					)
					(number "H20"
						(effects
							(font
								(size 1.27 1.27)
							)
						)
					)
				)
				(pin passive line
					(at 0 -25.4 0)
					(length 5.08)
					(hide yes)
					(name "GND"
						(effects
							(font
								(size 1.27 1.27)
							)
						)
					)
					(number "H3"
						(effects
							(font
								(size 1.27 1.27)
							)
						)
					)
				)
				(pin passive line
					(at 0 -25.4 0)
					(length 5.08)
					(hide yes)
					(name "GND"
						(effects
							(font
								(size 1.27 1.27)
							)
						)
					)
					(number "H4"
						(effects
							(font
								(size 1.27 1.27)
							)
						)
					)
				)
				(pin passive line
					(at 0 -25.4 0)
					(length 5.08)
					(hide yes)
					(name "GND"
						(effects
							(font
								(size 1.27 1.27)
							)
						)
					)
					(number "H8"
						(effects
							(font
								(size 1.27 1.27)
							)
						)
					)
				)
				(pin passive line
					(at 0 -25.4 0)
					(length 5.08)
					(hide yes)
					(name "GND"
						(effects
							(font
								(size 1.27 1.27)
							)
						)
					)
					(number "J1"
						(effects
							(font
								(size 1.27 1.27)
							)
						)
					)
				)
				(pin passive line
					(at 0 -25.4 0)
					(length 5.08)
					(hide yes)
					(name "GND"
						(effects
							(font
								(size 1.27 1.27)
							)
						)
					)
					(number "J17"
						(effects
							(font
								(size 1.27 1.27)
							)
						)
					)
				)
				(pin passive line
					(at 0 -25.4 0)
					(length 5.08)
					(hide yes)
					(name "GND"
						(effects
							(font
								(size 1.27 1.27)
							)
						)
					)
					(number "J2"
						(effects
							(font
								(size 1.27 1.27)
							)
						)
					)
				)
				(pin passive line
					(at 0 -25.4 0)
					(length 5.08)
					(hide yes)
					(name "GND"
						(effects
							(font
								(size 1.27 1.27)
							)
						)
					)
					(number "J3"
						(effects
							(font
								(size 1.27 1.27)
							)
						)
					)
				)
				(pin passive line
					(at 0 -25.4 0)
					(length 5.08)
					(hide yes)
					(name "GND"
						(effects
							(font
								(size 1.27 1.27)
							)
						)
					)
					(number "J6"
						(effects
							(font
								(size 1.27 1.27)
							)
						)
					)
				)
				(pin passive line
					(at 0 -25.4 0)
					(length 5.08)
					(hide yes)
					(name "GND"
						(effects
							(font
								(size 1.27 1.27)
							)
						)
					)
					(number "J8"
						(effects
							(font
								(size 1.27 1.27)
							)
						)
					)
				)
				(pin passive line
					(at 0 -25.4 0)
					(length 5.08)
					(hide yes)
					(name "GND"
						(effects
							(font
								(size 1.27 1.27)
							)
						)
					)
					(number "K12"
						(effects
							(font
								(size 1.27 1.27)
							)
						)
					)
				)
				(pin passive line
					(at 0 -25.4 0)
					(length 5.08)
					(hide yes)
					(name "GND"
						(effects
							(font
								(size 1.27 1.27)
							)
						)
					)
					(number "K14"
						(effects
							(font
								(size 1.27 1.27)
							)
						)
					)
				)
				(pin passive line
					(at 0 -25.4 0)
					(length 5.08)
					(hide yes)
					(name "GND"
						(effects
							(font
								(size 1.27 1.27)
							)
						)
					)
					(number "K16"
						(effects
							(font
								(size 1.27 1.27)
							)
						)
					)
				)
				(pin passive line
					(at 0 -25.4 0)
					(length 5.08)
					(hide yes)
					(name "GND"
						(effects
							(font
								(size 1.27 1.27)
							)
						)
					)
					(number "K19"
						(effects
							(font
								(size 1.27 1.27)
							)
						)
					)
				)
				(pin passive line
					(at 0 -25.4 0)
					(length 5.08)
					(hide yes)
					(name "GND"
						(effects
							(font
								(size 1.27 1.27)
							)
						)
					)
					(number "K24"
						(effects
							(font
								(size 1.27 1.27)
							)
						)
					)
				)
				(pin passive line
					(at 0 -25.4 0)
					(length 5.08)
					(hide yes)
					(name "GND"
						(effects
							(font
								(size 1.27 1.27)
							)
						)
					)
					(number "K3"
						(effects
							(font
								(size 1.27 1.27)
							)
						)
					)
				)
				(pin passive line
					(at 0 -25.4 0)
					(length 5.08)
					(hide yes)
					(name "GND"
						(effects
							(font
								(size 1.27 1.27)
							)
						)
					)
					(number "K4"
						(effects
							(font
								(size 1.27 1.27)
							)
						)
					)
				)
				(pin passive line
					(at 0 -25.4 0)
					(length 5.08)
					(hide yes)
					(name "GND"
						(effects
							(font
								(size 1.27 1.27)
							)
						)
					)
					(number "K8"
						(effects
							(font
								(size 1.27 1.27)
							)
						)
					)
				)
				(pin passive line
					(at 0 -25.4 0)
					(length 5.08)
					(hide yes)
					(name "GND"
						(effects
							(font
								(size 1.27 1.27)
							)
						)
					)
					(number "L1"
						(effects
							(font
								(size 1.27 1.27)
							)
						)
					)
				)
				(pin passive line
					(at 0 -25.4 0)
					(length 5.08)
					(hide yes)
					(name "GND"
						(effects
							(font
								(size 1.27 1.27)
							)
						)
					)
					(number "L11"
						(effects
							(font
								(size 1.27 1.27)
							)
						)
					)
				)
				(pin passive line
					(at 0 -25.4 0)
					(length 5.08)
					(hide yes)
					(name "GND"
						(effects
							(font
								(size 1.27 1.27)
							)
						)
					)
					(number "L13"
						(effects
							(font
								(size 1.27 1.27)
							)
						)
					)
				)
				(pin passive line
					(at 0 -25.4 0)
					(length 5.08)
					(hide yes)
					(name "GND"
						(effects
							(font
								(size 1.27 1.27)
							)
						)
					)
					(number "L15"
						(effects
							(font
								(size 1.27 1.27)
							)
						)
					)
				)
				(pin passive line
					(at 0 -25.4 0)
					(length 5.08)
					(hide yes)
					(name "GND"
						(effects
							(font
								(size 1.27 1.27)
							)
						)
					)
					(number "L17"
						(effects
							(font
								(size 1.27 1.27)
							)
						)
					)
				)
				(pin passive line
					(at 0 -25.4 0)
					(length 5.08)
					(hide yes)
					(name "GND"
						(effects
							(font
								(size 1.27 1.27)
							)
						)
					)
					(number "L2"
						(effects
							(font
								(size 1.27 1.27)
							)
						)
					)
				)
				(pin passive line
					(at 0 -25.4 0)
					(length 5.08)
					(hide yes)
					(name "GND"
						(effects
							(font
								(size 1.27 1.27)
							)
						)
					)
					(number "L21"
						(effects
							(font
								(size 1.27 1.27)
							)
						)
					)
				)
				(pin passive line
					(at 0 -25.4 0)
					(length 5.08)
					(hide yes)
					(name "GND"
						(effects
							(font
								(size 1.27 1.27)
							)
						)
					)
					(number "L26"
						(effects
							(font
								(size 1.27 1.27)
							)
						)
					)
				)
				(pin passive line
					(at 0 -25.4 0)
					(length 5.08)
					(hide yes)
					(name "GND"
						(effects
							(font
								(size 1.27 1.27)
							)
						)
					)
					(number "L3"
						(effects
							(font
								(size 1.27 1.27)
							)
						)
					)
				)
				(pin passive line
					(at 0 -25.4 0)
					(length 5.08)
					(hide yes)
					(name "GND"
						(effects
							(font
								(size 1.27 1.27)
							)
						)
					)
					(number "L6"
						(effects
							(font
								(size 1.27 1.27)
							)
						)
					)
				)
				(pin passive line
					(at 0 -25.4 0)
					(length 5.08)
					(hide yes)
					(name "GND"
						(effects
							(font
								(size 1.27 1.27)
							)
						)
					)
					(number "L8"
						(effects
							(font
								(size 1.27 1.27)
							)
						)
					)
				)
				(pin passive line
					(at 0 -25.4 0)
					(length 5.08)
					(hide yes)
					(name "GND"
						(effects
							(font
								(size 1.27 1.27)
							)
						)
					)
					(number "M10"
						(effects
							(font
								(size 1.27 1.27)
							)
						)
					)
				)
				(pin passive line
					(at 0 -25.4 0)
					(length 5.08)
					(hide yes)
					(name "GND"
						(effects
							(font
								(size 1.27 1.27)
							)
						)
					)
					(number "M12"
						(effects
							(font
								(size 1.27 1.27)
							)
						)
					)
				)
				(pin passive line
					(at 0 -25.4 0)
					(length 5.08)
					(hide yes)
					(name "GND"
						(effects
							(font
								(size 1.27 1.27)
							)
						)
					)
					(number "M14"
						(effects
							(font
								(size 1.27 1.27)
							)
						)
					)
				)
				(pin passive line
					(at 0 -25.4 0)
					(length 5.08)
					(hide yes)
					(name "GND"
						(effects
							(font
								(size 1.27 1.27)
							)
						)
					)
					(number "M16"
						(effects
							(font
								(size 1.27 1.27)
							)
						)
					)
				)
				(pin passive line
					(at 0 -25.4 0)
					(length 5.08)
					(hide yes)
					(name "GND"
						(effects
							(font
								(size 1.27 1.27)
							)
						)
					)
					(number "M23"
						(effects
							(font
								(size 1.27 1.27)
							)
						)
					)
				)
				(pin passive line
					(at 0 -25.4 0)
					(length 5.08)
					(hide yes)
					(name "GND"
						(effects
							(font
								(size 1.27 1.27)
							)
						)
					)
					(number "M3"
						(effects
							(font
								(size 1.27 1.27)
							)
						)
					)
				)
				(pin passive line
					(at 0 -25.4 0)
					(length 5.08)
					(hide yes)
					(name "GND"
						(effects
							(font
								(size 1.27 1.27)
							)
						)
					)
					(number "M4"
						(effects
							(font
								(size 1.27 1.27)
							)
						)
					)
				)
				(pin passive line
					(at 0 -25.4 0)
					(length 5.08)
					(hide yes)
					(name "GND"
						(effects
							(font
								(size 1.27 1.27)
							)
						)
					)
					(number "M8"
						(effects
							(font
								(size 1.27 1.27)
							)
						)
					)
				)
				(pin passive line
					(at 0 -25.4 0)
					(length 5.08)
					(hide yes)
					(name "GND"
						(effects
							(font
								(size 1.27 1.27)
							)
						)
					)
					(number "N1"
						(effects
							(font
								(size 1.27 1.27)
							)
						)
					)
				)
				(pin passive line
					(at 0 -25.4 0)
					(length 5.08)
					(hide yes)
					(name "GND"
						(effects
							(font
								(size 1.27 1.27)
							)
						)
					)
					(number "N11"
						(effects
							(font
								(size 1.27 1.27)
							)
						)
					)
				)
				(pin passive line
					(at 0 -25.4 0)
					(length 5.08)
					(hide yes)
					(name "GND"
						(effects
							(font
								(size 1.27 1.27)
							)
						)
					)
					(number "N15"
						(effects
							(font
								(size 1.27 1.27)
							)
						)
					)
				)
				(pin passive line
					(at 0 -25.4 0)
					(length 5.08)
					(hide yes)
					(name "GND"
						(effects
							(font
								(size 1.27 1.27)
							)
						)
					)
					(number "N17"
						(effects
							(font
								(size 1.27 1.27)
							)
						)
					)
				)
				(pin passive line
					(at 0 -25.4 0)
					(length 5.08)
					(hide yes)
					(name "GND"
						(effects
							(font
								(size 1.27 1.27)
							)
						)
					)
					(number "N2"
						(effects
							(font
								(size 1.27 1.27)
							)
						)
					)
				)
				(pin passive line
					(at 0 -25.4 0)
					(length 5.08)
					(hide yes)
					(name "GND"
						(effects
							(font
								(size 1.27 1.27)
							)
						)
					)
					(number "N20"
						(effects
							(font
								(size 1.27 1.27)
							)
						)
					)
				)
				(pin passive line
					(at 0 -25.4 0)
					(length 5.08)
					(hide yes)
					(name "GND"
						(effects
							(font
								(size 1.27 1.27)
							)
						)
					)
					(number "N25"
						(effects
							(font
								(size 1.27 1.27)
							)
						)
					)
				)
				(pin passive line
					(at 0 -25.4 0)
					(length 5.08)
					(hide yes)
					(name "GND"
						(effects
							(font
								(size 1.27 1.27)
							)
						)
					)
					(number "N3"
						(effects
							(font
								(size 1.27 1.27)
							)
						)
					)
				)
				(pin passive line
					(at 0 -25.4 0)
					(length 5.08)
					(hide yes)
					(name "GND"
						(effects
							(font
								(size 1.27 1.27)
							)
						)
					)
					(number "N6"
						(effects
							(font
								(size 1.27 1.27)
							)
						)
					)
				)
				(pin passive line
					(at 0 -25.4 0)
					(length 5.08)
					(hide yes)
					(name "GND"
						(effects
							(font
								(size 1.27 1.27)
							)
						)
					)
					(number "N8"
						(effects
							(font
								(size 1.27 1.27)
							)
						)
					)
				)
				(pin passive line
					(at 0 -25.4 0)
					(length 5.08)
					(hide yes)
					(name "GND"
						(effects
							(font
								(size 1.27 1.27)
							)
						)
					)
					(number "P10"
						(effects
							(font
								(size 1.27 1.27)
							)
						)
					)
				)
				(pin passive line
					(at 0 -25.4 0)
					(length 5.08)
					(hide yes)
					(name "GND"
						(effects
							(font
								(size 1.27 1.27)
							)
						)
					)
					(number "P12"
						(effects
							(font
								(size 1.27 1.27)
							)
						)
					)
				)
				(pin passive line
					(at 0 -25.4 0)
					(length 5.08)
					(hide yes)
					(name "GND"
						(effects
							(font
								(size 1.27 1.27)
							)
						)
					)
					(number "P16"
						(effects
							(font
								(size 1.27 1.27)
							)
						)
					)
				)
				(pin passive line
					(at 0 -25.4 0)
					(length 5.08)
					(hide yes)
					(name "GND"
						(effects
							(font
								(size 1.27 1.27)
							)
						)
					)
					(number "P3"
						(effects
							(font
								(size 1.27 1.27)
							)
						)
					)
				)
				(pin passive line
					(at 0 -25.4 0)
					(length 5.08)
					(hide yes)
					(name "GND"
						(effects
							(font
								(size 1.27 1.27)
							)
						)
					)
					(number "P4"
						(effects
							(font
								(size 1.27 1.27)
							)
						)
					)
				)
				(pin passive line
					(at 0 -25.4 0)
					(length 5.08)
					(hide yes)
					(name "GND"
						(effects
							(font
								(size 1.27 1.27)
							)
						)
					)
					(number "P8"
						(effects
							(font
								(size 1.27 1.27)
							)
						)
					)
				)
				(pin passive line
					(at 0 -25.4 0)
					(length 5.08)
					(hide yes)
					(name "GND"
						(effects
							(font
								(size 1.27 1.27)
							)
						)
					)
					(number "R1"
						(effects
							(font
								(size 1.27 1.27)
							)
						)
					)
				)
				(pin passive line
					(at 0 -25.4 0)
					(length 5.08)
					(hide yes)
					(name "GND"
						(effects
							(font
								(size 1.27 1.27)
							)
						)
					)
					(number "R11"
						(effects
							(font
								(size 1.27 1.27)
							)
						)
					)
				)
				(pin passive line
					(at 0 -25.4 0)
					(length 5.08)
					(hide yes)
					(name "GND"
						(effects
							(font
								(size 1.27 1.27)
							)
						)
					)
					(number "R15"
						(effects
							(font
								(size 1.27 1.27)
							)
						)
					)
				)
				(pin passive line
					(at 0 -25.4 0)
					(length 5.08)
					(hide yes)
					(name "GND"
						(effects
							(font
								(size 1.27 1.27)
							)
						)
					)
					(number "R17"
						(effects
							(font
								(size 1.27 1.27)
							)
						)
					)
				)
				(pin passive line
					(at 0 -25.4 0)
					(length 5.08)
					(hide yes)
					(name "GND"
						(effects
							(font
								(size 1.27 1.27)
							)
						)
					)
					(number "R19"
						(effects
							(font
								(size 1.27 1.27)
							)
						)
					)
				)
				(pin passive line
					(at 0 -25.4 0)
					(length 5.08)
					(hide yes)
					(name "GND"
						(effects
							(font
								(size 1.27 1.27)
							)
						)
					)
					(number "R2"
						(effects
							(font
								(size 1.27 1.27)
							)
						)
					)
				)
				(pin passive line
					(at 0 -25.4 0)
					(length 5.08)
					(hide yes)
					(name "GND"
						(effects
							(font
								(size 1.27 1.27)
							)
						)
					)
					(number "R24"
						(effects
							(font
								(size 1.27 1.27)
							)
						)
					)
				)
				(pin passive line
					(at 0 -25.4 0)
					(length 5.08)
					(hide yes)
					(name "GND"
						(effects
							(font
								(size 1.27 1.27)
							)
						)
					)
					(number "R3"
						(effects
							(font
								(size 1.27 1.27)
							)
						)
					)
				)
				(pin passive line
					(at 0 -25.4 0)
					(length 5.08)
					(hide yes)
					(name "GND"
						(effects
							(font
								(size 1.27 1.27)
							)
						)
					)
					(number "R6"
						(effects
							(font
								(size 1.27 1.27)
							)
						)
					)
				)
				(pin passive line
					(at 0 -25.4 0)
					(length 5.08)
					(hide yes)
					(name "GND"
						(effects
							(font
								(size 1.27 1.27)
							)
						)
					)
					(number "R8"
						(effects
							(font
								(size 1.27 1.27)
							)
						)
					)
				)
				(pin passive line
					(at 0 -25.4 0)
					(length 5.08)
					(hide yes)
					(name "GND"
						(effects
							(font
								(size 1.27 1.27)
							)
						)
					)
					(number "T10"
						(effects
							(font
								(size 1.27 1.27)
							)
						)
					)
				)
				(pin passive line
					(at 0 -25.4 0)
					(length 5.08)
					(hide yes)
					(name "GND"
						(effects
							(font
								(size 1.27 1.27)
							)
						)
					)
					(number "T12"
						(effects
							(font
								(size 1.27 1.27)
							)
						)
					)
				)
				(pin passive line
					(at 0 -25.4 0)
					(length 5.08)
					(hide yes)
					(name "GND"
						(effects
							(font
								(size 1.27 1.27)
							)
						)
					)
					(number "T16"
						(effects
							(font
								(size 1.27 1.27)
							)
						)
					)
				)
				(pin passive line
					(at 0 -25.4 0)
					(length 5.08)
					(hide yes)
					(name "GND"
						(effects
							(font
								(size 1.27 1.27)
							)
						)
					)
					(number "T21"
						(effects
							(font
								(size 1.27 1.27)
							)
						)
					)
				)
				(pin passive line
					(at 0 -25.4 0)
					(length 5.08)
					(hide yes)
					(name "GND"
						(effects
							(font
								(size 1.27 1.27)
							)
						)
					)
					(number "T26"
						(effects
							(font
								(size 1.27 1.27)
							)
						)
					)
				)
				(pin passive line
					(at 0 -25.4 0)
					(length 5.08)
					(hide yes)
					(name "GND"
						(effects
							(font
								(size 1.27 1.27)
							)
						)
					)
					(number "T3"
						(effects
							(font
								(size 1.27 1.27)
							)
						)
					)
				)
				(pin passive line
					(at 0 -25.4 0)
					(length 5.08)
					(hide yes)
					(name "GND"
						(effects
							(font
								(size 1.27 1.27)
							)
						)
					)
					(number "T4"
						(effects
							(font
								(size 1.27 1.27)
							)
						)
					)
				)
				(pin passive line
					(at 0 -25.4 0)
					(length 5.08)
					(hide yes)
					(name "GND"
						(effects
							(font
								(size 1.27 1.27)
							)
						)
					)
					(number "T8"
						(effects
							(font
								(size 1.27 1.27)
							)
						)
					)
				)
				(pin passive line
					(at 0 -25.4 0)
					(length 5.08)
					(hide yes)
					(name "GND"
						(effects
							(font
								(size 1.27 1.27)
							)
						)
					)
					(number "U1"
						(effects
							(font
								(size 1.27 1.27)
							)
						)
					)
				)
				(pin passive line
					(at 0 -25.4 0)
					(length 5.08)
					(hide yes)
					(name "GND"
						(effects
							(font
								(size 1.27 1.27)
							)
						)
					)
					(number "U11"
						(effects
							(font
								(size 1.27 1.27)
							)
						)
					)
				)
				(pin passive line
					(at 0 -25.4 0)
					(length 5.08)
					(hide yes)
					(name "GND"
						(effects
							(font
								(size 1.27 1.27)
							)
						)
					)
					(number "U13"
						(effects
							(font
								(size 1.27 1.27)
							)
						)
					)
				)
				(pin passive line
					(at 0 -25.4 0)
					(length 5.08)
					(hide yes)
					(name "GND"
						(effects
							(font
								(size 1.27 1.27)
							)
						)
					)
					(number "U15"
						(effects
							(font
								(size 1.27 1.27)
							)
						)
					)
				)
				(pin passive line
					(at 0 -25.4 0)
					(length 5.08)
					(hide yes)
					(name "GND"
						(effects
							(font
								(size 1.27 1.27)
							)
						)
					)
					(number "U17"
						(effects
							(font
								(size 1.27 1.27)
							)
						)
					)
				)
				(pin passive line
					(at 0 -25.4 0)
					(length 5.08)
					(hide yes)
					(name "GND"
						(effects
							(font
								(size 1.27 1.27)
							)
						)
					)
					(number "U18"
						(effects
							(font
								(size 1.27 1.27)
							)
						)
					)
				)
				(pin passive line
					(at 0 -25.4 0)
					(length 5.08)
					(hide yes)
					(name "GND"
						(effects
							(font
								(size 1.27 1.27)
							)
						)
					)
					(number "U2"
						(effects
							(font
								(size 1.27 1.27)
							)
						)
					)
				)
				(pin passive line
					(at 0 -25.4 0)
					(length 5.08)
					(hide yes)
					(name "GND"
						(effects
							(font
								(size 1.27 1.27)
							)
						)
					)
					(number "U3"
						(effects
							(font
								(size 1.27 1.27)
							)
						)
					)
				)
				(pin passive line
					(at 0 -25.4 0)
					(length 5.08)
					(hide yes)
					(name "GND"
						(effects
							(font
								(size 1.27 1.27)
							)
						)
					)
					(number "U6"
						(effects
							(font
								(size 1.27 1.27)
							)
						)
					)
				)
				(pin passive line
					(at 0 -25.4 0)
					(length 5.08)
					(hide yes)
					(name "GND"
						(effects
							(font
								(size 1.27 1.27)
							)
						)
					)
					(number "U8"
						(effects
							(font
								(size 1.27 1.27)
							)
						)
					)
				)
				(pin passive line
					(at 0 -25.4 0)
					(length 5.08)
					(hide yes)
					(name "GND"
						(effects
							(font
								(size 1.27 1.27)
							)
						)
					)
					(number "V10"
						(effects
							(font
								(size 1.27 1.27)
							)
						)
					)
				)
				(pin passive line
					(at 0 -25.4 0)
					(length 5.08)
					(hide yes)
					(name "GND"
						(effects
							(font
								(size 1.27 1.27)
							)
						)
					)
					(number "V12"
						(effects
							(font
								(size 1.27 1.27)
							)
						)
					)
				)
				(pin passive line
					(at 0 -25.4 0)
					(length 5.08)
					(hide yes)
					(name "GND"
						(effects
							(font
								(size 1.27 1.27)
							)
						)
					)
					(number "V14"
						(effects
							(font
								(size 1.27 1.27)
							)
						)
					)
				)
				(pin passive line
					(at 0 -25.4 0)
					(length 5.08)
					(hide yes)
					(name "GND"
						(effects
							(font
								(size 1.27 1.27)
							)
						)
					)
					(number "V16"
						(effects
							(font
								(size 1.27 1.27)
							)
						)
					)
				)
				(pin passive line
					(at 0 -25.4 0)
					(length 5.08)
					(hide yes)
					(name "GND"
						(effects
							(font
								(size 1.27 1.27)
							)
						)
					)
					(number "V20"
						(effects
							(font
								(size 1.27 1.27)
							)
						)
					)
				)
				(pin passive line
					(at 0 -25.4 0)
					(length 5.08)
					(hide yes)
					(name "GND"
						(effects
							(font
								(size 1.27 1.27)
							)
						)
					)
					(number "V25"
						(effects
							(font
								(size 1.27 1.27)
							)
						)
					)
				)
				(pin passive line
					(at 0 -25.4 0)
					(length 5.08)
					(hide yes)
					(name "GND"
						(effects
							(font
								(size 1.27 1.27)
							)
						)
					)
					(number "V3"
						(effects
							(font
								(size 1.27 1.27)
							)
						)
					)
				)
				(pin passive line
					(at 0 -25.4 0)
					(length 5.08)
					(hide yes)
					(name "GND"
						(effects
							(font
								(size 1.27 1.27)
							)
						)
					)
					(number "V4"
						(effects
							(font
								(size 1.27 1.27)
							)
						)
					)
				)
				(pin passive line
					(at 0 -25.4 0)
					(length 5.08)
					(hide yes)
					(name "GND"
						(effects
							(font
								(size 1.27 1.27)
							)
						)
					)
					(number "V8"
						(effects
							(font
								(size 1.27 1.27)
							)
						)
					)
				)
				(pin passive line
					(at 0 -25.4 0)
					(length 5.08)
					(hide yes)
					(name "GND"
						(effects
							(font
								(size 1.27 1.27)
							)
						)
					)
					(number "W1"
						(effects
							(font
								(size 1.27 1.27)
							)
						)
					)
				)
				(pin passive line
					(at 0 -25.4 0)
					(length 5.08)
					(hide yes)
					(name "GND"
						(effects
							(font
								(size 1.27 1.27)
							)
						)
					)
					(number "W17"
						(effects
							(font
								(size 1.27 1.27)
							)
						)
					)
				)
				(pin passive line
					(at 0 -25.4 0)
					(length 5.08)
					(hide yes)
					(name "GND"
						(effects
							(font
								(size 1.27 1.27)
							)
						)
					)
					(number "W2"
						(effects
							(font
								(size 1.27 1.27)
							)
						)
					)
				)
				(pin passive line
					(at 0 -25.4 0)
					(length 5.08)
					(hide yes)
					(name "GND"
						(effects
							(font
								(size 1.27 1.27)
							)
						)
					)
					(number "W22"
						(effects
							(font
								(size 1.27 1.27)
							)
						)
					)
				)
				(pin passive line
					(at 0 -25.4 0)
					(length 5.08)
					(hide yes)
					(name "GND"
						(effects
							(font
								(size 1.27 1.27)
							)
						)
					)
					(number "W3"
						(effects
							(font
								(size 1.27 1.27)
							)
						)
					)
				)
				(pin passive line
					(at 0 -25.4 0)
					(length 5.08)
					(hide yes)
					(name "GND"
						(effects
							(font
								(size 1.27 1.27)
							)
						)
					)
					(number "W6"
						(effects
							(font
								(size 1.27 1.27)
							)
						)
					)
				)
				(pin passive line
					(at 0 -25.4 0)
					(length 5.08)
					(hide yes)
					(name "GND"
						(effects
							(font
								(size 1.27 1.27)
							)
						)
					)
					(number "W8"
						(effects
							(font
								(size 1.27 1.27)
							)
						)
					)
				)
				(pin passive line
					(at 0 -25.4 0)
					(length 5.08)
					(hide yes)
					(name "GND"
						(effects
							(font
								(size 1.27 1.27)
							)
						)
					)
					(number "Y19"
						(effects
							(font
								(size 1.27 1.27)
							)
						)
					)
				)
				(pin passive line
					(at 0 -25.4 0)
					(length 5.08)
					(hide yes)
					(name "GND"
						(effects
							(font
								(size 1.27 1.27)
							)
						)
					)
					(number "Y3"
						(effects
							(font
								(size 1.27 1.27)
							)
						)
					)
				)
				(pin passive line
					(at 0 -25.4 0)
					(length 5.08)
					(hide yes)
					(name "GND"
						(effects
							(font
								(size 1.27 1.27)
							)
						)
					)
					(number "Y4"
						(effects
							(font
								(size 1.27 1.27)
							)
						)
					)
				)
				(pin passive line
					(at 0 -25.4 0)
					(length 5.08)
					(hide yes)
					(name "GND"
						(effects
							(font
								(size 1.27 1.27)
							)
						)
					)
					(number "Y8"
						(effects
							(font
								(size 1.27 1.27)
							)
						)
					)
				)
				(pin no_connect line
					(at 7.62 2.54 270)
					(length 5.08)
					(hide yes)
					(name "NC"
						(effects
							(font
								(size 1.27 1.27)
							)
						)
					)
					(number "B2"
						(effects
							(font
								(size 1.27 1.27)
							)
						)
					)
				)
				(pin no_connect line
					(at 10.16 2.54 270)
					(length 5.08)
					(hide yes)
					(name "NC"
						(effects
							(font
								(size 1.27 1.27)
							)
						)
					)
					(number "C4"
						(effects
							(font
								(size 1.27 1.27)
							)
						)
					)
				)
				(pin no_connect line
					(at 10.16 -27.94 90)
					(length 5.08)
					(hide yes)
					(name "NC"
						(effects
							(font
								(size 1.27 1.27)
							)
						)
					)
					(number "A4"
						(effects
							(font
								(size 1.27 1.27)
							)
						)
					)
				)
				(pin no_connect line
					(at 12.7 2.54 270)
					(length 5.08)
					(hide yes)
					(name "NC"
						(effects
							(font
								(size 1.27 1.27)
							)
						)
					)
					(number "D2"
						(effects
							(font
								(size 1.27 1.27)
							)
						)
					)
				)
				(pin no_connect line
					(at 12.7 -27.94 90)
					(length 5.08)
					(hide yes)
					(name "NC"
						(effects
							(font
								(size 1.27 1.27)
							)
						)
					)
					(number "F6"
						(effects
							(font
								(size 1.27 1.27)
							)
						)
					)
				)
				(pin no_connect line
					(at 15.24 2.54 270)
					(length 5.08)
					(hide yes)
					(name "NC"
						(effects
							(font
								(size 1.27 1.27)
							)
						)
					)
					(number "A3"
						(effects
							(font
								(size 1.27 1.27)
							)
						)
					)
				)
				(pin no_connect line
					(at 15.24 -27.94 90)
					(length 5.08)
					(hide yes)
					(name "NC"
						(effects
							(font
								(size 1.27 1.27)
							)
						)
					)
					(number "E4"
						(effects
							(font
								(size 1.27 1.27)
							)
						)
					)
				)
				(pin no_connect line
					(at 17.78 2.54 270)
					(length 5.08)
					(hide yes)
					(name "NC"
						(effects
							(font
								(size 1.27 1.27)
							)
						)
					)
					(number "B1"
						(effects
							(font
								(size 1.27 1.27)
							)
						)
					)
				)
				(pin no_connect line
					(at 17.78 -27.94 90)
					(length 5.08)
					(hide yes)
					(name "NC"
						(effects
							(font
								(size 1.27 1.27)
							)
						)
					)
					(number "D6"
						(effects
							(font
								(size 1.27 1.27)
							)
						)
					)
				)
				(pin no_connect line
					(at 20.32 2.54 270)
					(length 5.08)
					(hide yes)
					(name "NC"
						(effects
							(font
								(size 1.27 1.27)
							)
						)
					)
					(number "C3"
						(effects
							(font
								(size 1.27 1.27)
							)
						)
					)
				)
				(pin no_connect line
					(at 20.32 -27.94 90)
					(length 5.08)
					(hide yes)
					(name "NC"
						(effects
							(font
								(size 1.27 1.27)
							)
						)
					)
					(number "B6"
						(effects
							(font
								(size 1.27 1.27)
							)
						)
					)
				)
				(pin no_connect line
					(at 22.86 2.54 270)
					(length 5.08)
					(hide yes)
					(name "NC"
						(effects
							(font
								(size 1.27 1.27)
							)
						)
					)
					(number "D1"
						(effects
							(font
								(size 1.27 1.27)
							)
						)
					)
				)
				(pin no_connect line
					(at 22.86 -27.94 90)
					(length 5.08)
					(hide yes)
					(name "NC"
						(effects
							(font
								(size 1.27 1.27)
							)
						)
					)
					(number "F7"
						(effects
							(font
								(size 1.27 1.27)
							)
						)
					)
				)
				(pin no_connect line
					(at 25.4 2.54 270)
					(length 5.08)
					(hide yes)
					(name "NC"
						(effects
							(font
								(size 1.27 1.27)
							)
						)
					)
					(number "H7"
						(effects
							(font
								(size 1.27 1.27)
							)
						)
					)
				)
				(pin no_connect line
					(at 25.4 -27.94 90)
					(length 5.08)
					(hide yes)
					(name "NC"
						(effects
							(font
								(size 1.27 1.27)
							)
						)
					)
					(number "E5"
						(effects
							(font
								(size 1.27 1.27)
							)
						)
					)
				)
				(pin no_connect line
					(at 27.94 2.54 270)
					(length 5.08)
					(hide yes)
					(name "NC"
						(effects
							(font
								(size 1.27 1.27)
							)
						)
					)
					(number "H6"
						(effects
							(font
								(size 1.27 1.27)
							)
						)
					)
				)
				(pin no_connect line
					(at 27.94 -27.94 90)
					(length 5.08)
					(hide yes)
					(name "NC"
						(effects
							(font
								(size 1.27 1.27)
							)
						)
					)
					(number "D7"
						(effects
							(font
								(size 1.27 1.27)
							)
						)
					)
				)
				(pin no_connect line
					(at 30.48 2.54 270)
					(length 5.08)
					(hide yes)
					(name "NC"
						(effects
							(font
								(size 1.27 1.27)
							)
						)
					)
					(number "K7"
						(effects
							(font
								(size 1.27 1.27)
							)
						)
					)
				)
				(pin no_connect line
					(at 30.48 -27.94 90)
					(length 5.08)
					(hide yes)
					(name "NC"
						(effects
							(font
								(size 1.27 1.27)
							)
						)
					)
					(number "B7"
						(effects
							(font
								(size 1.27 1.27)
							)
						)
					)
				)
				(pin no_connect line
					(at 33.02 2.54 270)
					(length 5.08)
					(hide yes)
					(name "NC"
						(effects
							(font
								(size 1.27 1.27)
							)
						)
					)
					(number "K6"
						(effects
							(font
								(size 1.27 1.27)
							)
						)
					)
				)
				(pin power_in line
					(at 40.64 0 180)
					(length 5.08)
					(name "VCCINT"
						(effects
							(font
								(size 1.27 1.27)
							)
						)
					)
					(number "K11"
						(effects
							(font
								(size 1.27 1.27)
							)
						)
					)
				)
				(pin passive line
					(at 40.64 0 180)
					(length 5.08)
					(hide yes)
					(name "VCCINT"
						(effects
							(font
								(size 1.27 1.27)
							)
						)
					)
					(number "K13"
						(effects
							(font
								(size 1.27 1.27)
							)
						)
					)
				)
				(pin passive line
					(at 40.64 0 180)
					(length 5.08)
					(hide yes)
					(name "VCCINT"
						(effects
							(font
								(size 1.27 1.27)
							)
						)
					)
					(number "K15"
						(effects
							(font
								(size 1.27 1.27)
							)
						)
					)
				)
				(pin passive line
					(at 40.64 0 180)
					(length 5.08)
					(hide yes)
					(name "VCCINT"
						(effects
							(font
								(size 1.27 1.27)
							)
						)
					)
					(number "K17"
						(effects
							(font
								(size 1.27 1.27)
							)
						)
					)
				)
				(pin passive line
					(at 40.64 0 180)
					(length 5.08)
					(hide yes)
					(name "VCCINT"
						(effects
							(font
								(size 1.27 1.27)
							)
						)
					)
					(number "L10"
						(effects
							(font
								(size 1.27 1.27)
							)
						)
					)
				)
				(pin passive line
					(at 40.64 0 180)
					(length 5.08)
					(hide yes)
					(name "VCCINT"
						(effects
							(font
								(size 1.27 1.27)
							)
						)
					)
					(number "L12"
						(effects
							(font
								(size 1.27 1.27)
							)
						)
					)
				)
				(pin passive line
					(at 40.64 0 180)
					(length 5.08)
					(hide yes)
					(name "VCCINT"
						(effects
							(font
								(size 1.27 1.27)
							)
						)
					)
					(number "L14"
						(effects
							(font
								(size 1.27 1.27)
							)
						)
					)
				)
				(pin passive line
					(at 40.64 0 180)
					(length 5.08)
					(hide yes)
					(name "VCCINT"
						(effects
							(font
								(size 1.27 1.27)
							)
						)
					)
					(number "L16"
						(effects
							(font
								(size 1.27 1.27)
							)
						)
					)
				)
				(pin passive line
					(at 40.64 0 180)
					(length 5.08)
					(hide yes)
					(name "VCCINT"
						(effects
							(font
								(size 1.27 1.27)
							)
						)
					)
					(number "M11"
						(effects
							(font
								(size 1.27 1.27)
							)
						)
					)
				)
				(pin passive line
					(at 40.64 0 180)
					(length 5.08)
					(hide yes)
					(name "VCCINT"
						(effects
							(font
								(size 1.27 1.27)
							)
						)
					)
					(number "M13"
						(effects
							(font
								(size 1.27 1.27)
							)
						)
					)
				)
				(pin passive line
					(at 40.64 0 180)
					(length 5.08)
					(hide yes)
					(name "VCCINT"
						(effects
							(font
								(size 1.27 1.27)
							)
						)
					)
					(number "M15"
						(effects
							(font
								(size 1.27 1.27)
							)
						)
					)
				)
				(pin passive line
					(at 40.64 0 180)
					(length 5.08)
					(hide yes)
					(name "VCCINT"
						(effects
							(font
								(size 1.27 1.27)
							)
						)
					)
					(number "M17"
						(effects
							(font
								(size 1.27 1.27)
							)
						)
					)
				)
				(pin passive line
					(at 40.64 0 180)
					(length 5.08)
					(hide yes)
					(name "VCCINT"
						(effects
							(font
								(size 1.27 1.27)
							)
						)
					)
					(number "N10"
						(effects
							(font
								(size 1.27 1.27)
							)
						)
					)
				)
				(pin passive line
					(at 40.64 0 180)
					(length 5.08)
					(hide yes)
					(name "VCCINT"
						(effects
							(font
								(size 1.27 1.27)
							)
						)
					)
					(number "N12"
						(effects
							(font
								(size 1.27 1.27)
							)
						)
					)
				)
				(pin passive line
					(at 40.64 0 180)
					(length 5.08)
					(hide yes)
					(name "VCCINT"
						(effects
							(font
								(size 1.27 1.27)
							)
						)
					)
					(number "N16"
						(effects
							(font
								(size 1.27 1.27)
							)
						)
					)
				)
				(pin passive line
					(at 40.64 0 180)
					(length 5.08)
					(hide yes)
					(name "VCCINT"
						(effects
							(font
								(size 1.27 1.27)
							)
						)
					)
					(number "P11"
						(effects
							(font
								(size 1.27 1.27)
							)
						)
					)
				)
				(pin passive line
					(at 40.64 0 180)
					(length 5.08)
					(hide yes)
					(name "VCCINT"
						(effects
							(font
								(size 1.27 1.27)
							)
						)
					)
					(number "P15"
						(effects
							(font
								(size 1.27 1.27)
							)
						)
					)
				)
				(pin passive line
					(at 40.64 0 180)
					(length 5.08)
					(hide yes)
					(name "VCCINT"
						(effects
							(font
								(size 1.27 1.27)
							)
						)
					)
					(number "P17"
						(effects
							(font
								(size 1.27 1.27)
							)
						)
					)
				)
				(pin passive line
					(at 40.64 0 180)
					(length 5.08)
					(hide yes)
					(name "VCCINT"
						(effects
							(font
								(size 1.27 1.27)
							)
						)
					)
					(number "R10"
						(effects
							(font
								(size 1.27 1.27)
							)
						)
					)
				)
				(pin passive line
					(at 40.64 0 180)
					(length 5.08)
					(hide yes)
					(name "VCCINT"
						(effects
							(font
								(size 1.27 1.27)
							)
						)
					)
					(number "R12"
						(effects
							(font
								(size 1.27 1.27)
							)
						)
					)
				)
				(pin passive line
					(at 40.64 0 180)
					(length 5.08)
					(hide yes)
					(name "VCCINT"
						(effects
							(font
								(size 1.27 1.27)
							)
						)
					)
					(number "R16"
						(effects
							(font
								(size 1.27 1.27)
							)
						)
					)
				)
				(pin passive line
					(at 40.64 0 180)
					(length 5.08)
					(hide yes)
					(name "VCCINT"
						(effects
							(font
								(size 1.27 1.27)
							)
						)
					)
					(number "T11"
						(effects
							(font
								(size 1.27 1.27)
							)
						)
					)
				)
				(pin passive line
					(at 40.64 0 180)
					(length 5.08)
					(hide yes)
					(name "VCCINT"
						(effects
							(font
								(size 1.27 1.27)
							)
						)
					)
					(number "T15"
						(effects
							(font
								(size 1.27 1.27)
							)
						)
					)
				)
				(pin passive line
					(at 40.64 0 180)
					(length 5.08)
					(hide yes)
					(name "VCCINT"
						(effects
							(font
								(size 1.27 1.27)
							)
						)
					)
					(number "T17"
						(effects
							(font
								(size 1.27 1.27)
							)
						)
					)
				)
				(pin passive line
					(at 40.64 0 180)
					(length 5.08)
					(hide yes)
					(name "VCCINT"
						(effects
							(font
								(size 1.27 1.27)
							)
						)
					)
					(number "U10"
						(effects
							(font
								(size 1.27 1.27)
							)
						)
					)
				)
				(pin passive line
					(at 40.64 0 180)
					(length 5.08)
					(hide yes)
					(name "VCCINT"
						(effects
							(font
								(size 1.27 1.27)
							)
						)
					)
					(number "U12"
						(effects
							(font
								(size 1.27 1.27)
							)
						)
					)
				)
				(pin passive line
					(at 40.64 0 180)
					(length 5.08)
					(hide yes)
					(name "VCCINT"
						(effects
							(font
								(size 1.27 1.27)
							)
						)
					)
					(number "U14"
						(effects
							(font
								(size 1.27 1.27)
							)
						)
					)
				)
				(pin passive line
					(at 40.64 0 180)
					(length 5.08)
					(hide yes)
					(name "VCCINT"
						(effects
							(font
								(size 1.27 1.27)
							)
						)
					)
					(number "U16"
						(effects
							(font
								(size 1.27 1.27)
							)
						)
					)
				)
				(pin passive line
					(at 40.64 0 180)
					(length 5.08)
					(hide yes)
					(name "VCCINT"
						(effects
							(font
								(size 1.27 1.27)
							)
						)
					)
					(number "V11"
						(effects
							(font
								(size 1.27 1.27)
							)
						)
					)
				)
				(pin passive line
					(at 40.64 0 180)
					(length 5.08)
					(hide yes)
					(name "VCCINT"
						(effects
							(font
								(size 1.27 1.27)
							)
						)
					)
					(number "V13"
						(effects
							(font
								(size 1.27 1.27)
							)
						)
					)
				)
				(pin passive line
					(at 40.64 0 180)
					(length 5.08)
					(hide yes)
					(name "VCCINT"
						(effects
							(font
								(size 1.27 1.27)
							)
						)
					)
					(number "V15"
						(effects
							(font
								(size 1.27 1.27)
							)
						)
					)
				)
				(pin passive line
					(at 40.64 0 180)
					(length 5.08)
					(hide yes)
					(name "VCCINT"
						(effects
							(font
								(size 1.27 1.27)
							)
						)
					)
					(number "V17"
						(effects
							(font
								(size 1.27 1.27)
							)
						)
					)
				)
				(pin power_in line
					(at 40.64 -2.54 180)
					(length 5.08)
					(name "VCCINT_IO"
						(effects
							(font
								(size 1.27 1.27)
							)
						)
					)
					(number "L9"
						(effects
							(font
								(size 1.27 1.27)
							)
						)
					)
				)
				(pin passive line
					(at 40.64 -2.54 180)
					(length 5.08)
					(hide yes)
					(name "VCCINT_IO"
						(effects
							(font
								(size 1.27 1.27)
							)
						)
					)
					(number "M9"
						(effects
							(font
								(size 1.27 1.27)
							)
						)
					)
				)
				(pin passive line
					(at 40.64 -2.54 180)
					(length 5.08)
					(hide yes)
					(name "VCCINT_IO"
						(effects
							(font
								(size 1.27 1.27)
							)
						)
					)
					(number "N9"
						(effects
							(font
								(size 1.27 1.27)
							)
						)
					)
				)
				(pin passive line
					(at 40.64 -2.54 180)
					(length 5.08)
					(hide yes)
					(name "VCCINT_IO"
						(effects
							(font
								(size 1.27 1.27)
							)
						)
					)
					(number "P9"
						(effects
							(font
								(size 1.27 1.27)
							)
						)
					)
				)
				(pin power_in line
					(at 40.64 -7.62 180)
					(length 5.08)
					(name "VCCAUX"
						(effects
							(font
								(size 1.27 1.27)
							)
						)
					)
					(number "M18"
						(effects
							(font
								(size 1.27 1.27)
							)
						)
					)
				)
				(pin passive line
					(at 40.64 -7.62 180)
					(length 5.08)
					(hide yes)
					(name "VCCAUX"
						(effects
							(font
								(size 1.27 1.27)
							)
						)
					)
					(number "N18"
						(effects
							(font
								(size 1.27 1.27)
							)
						)
					)
				)
				(pin power_in line
					(at 40.64 -10.16 180)
					(length 5.08)
					(name "VCCAUX_IO"
						(effects
							(font
								(size 1.27 1.27)
							)
						)
					)
					(number "P18"
						(effects
							(font
								(size 1.27 1.27)
							)
						)
					)
				)
				(pin passive line
					(at 40.64 -10.16 180)
					(length 5.08)
					(hide yes)
					(name "VCCAUX_IO"
						(effects
							(font
								(size 1.27 1.27)
							)
						)
					)
					(number "R18"
						(effects
							(font
								(size 1.27 1.27)
							)
						)
					)
				)
				(pin passive line
					(at 40.64 -10.16 180)
					(length 5.08)
					(hide yes)
					(name "VCCAUX_IO"
						(effects
							(font
								(size 1.27 1.27)
							)
						)
					)
					(number "T18"
						(effects
							(font
								(size 1.27 1.27)
							)
						)
					)
				)
				(pin power_in line
					(at 40.64 -15.24 180)
					(length 5.08)
					(name "VCCBRAM"
						(effects
							(font
								(size 1.27 1.27)
							)
						)
					)
					(number "R9"
						(effects
							(font
								(size 1.27 1.27)
							)
						)
					)
				)
				(pin passive line
					(at 40.64 -15.24 180)
					(length 5.08)
					(hide yes)
					(name "VCCBRAM"
						(effects
							(font
								(size 1.27 1.27)
							)
						)
					)
					(number "T9"
						(effects
							(font
								(size 1.27 1.27)
							)
						)
					)
				)
				(pin passive line
					(at 40.64 -15.24 180)
					(length 5.08)
					(hide yes)
					(name "VCCBRAM"
						(effects
							(font
								(size 1.27 1.27)
							)
						)
					)
					(number "U9"
						(effects
							(font
								(size 1.27 1.27)
							)
						)
					)
				)
				(pin passive line
					(at 40.64 -15.24 180)
					(length 5.08)
					(hide yes)
					(name "VCCBRAM"
						(effects
							(font
								(size 1.27 1.27)
							)
						)
					)
					(number "V9"
						(effects
							(font
								(size 1.27 1.27)
							)
						)
					)
				)
				(pin power_in line
					(at 40.64 -20.32 180)
					(length 5.08)
					(name "VCCADC"
						(effects
							(font
								(size 1.27 1.27)
							)
						)
					)
					(number "N14"
						(effects
							(font
								(size 1.27 1.27)
							)
						)
					)
				)
				(pin power_in line
					(at 40.64 -25.4 180)
					(length 5.08)
					(name "VBATT"
						(effects
							(font
								(size 1.27 1.27)
							)
						)
					)
					(number "Y9"
						(effects
							(font
								(size 1.27 1.27)
							)
						)
					)
				)
			)
		)
	(symbol "antmicroBarrelPowerConnectors:BarrelJack_Pin2mm_694106106102"
			(pin_names
				(hide yes)
			)
			(exclude_from_sim no)
			(in_bom yes)
			(on_board yes)
			(property "Reference" "J"
				(at 15.24 -5.08 0)
				(effects
					(font
						(size 1.27 1.27)
						(thickness 0.15)
					)
					(justify left bottom)
				)
			)
			(property "Value" "BarrelJack_Pin2mm_694106106102"
				(at 15.24 -10.16 0)
				(effects
					(font
						(size 1.27 1.27)
						(thickness 0.15)
					)
					(justify left bottom)
					(hide yes)
				)
			)
			(property "Footprint" "antmicro-footprints:BarrelJack_Pin2mm_694106106102"
				(at 15.24 -12.7 0)
				(effects
					(font
						(size 1.27 1.27)
						(thickness 0.15)
					)
					(justify left bottom)
					(hide yes)
				)
			)
			(property "Datasheet" "https://www.we-online.com/components/products/datasheet/694106106102.pdf"
				(at 15.24 -15.24 0)
				(effects
					(font
						(size 1.27 1.27)
						(thickness 0.15)
					)
					(justify left bottom)
					(hide yes)
				)
			)
			(property "Description" "DC Power Connector, Jack, 5 A, 2 mm, PCB Mount, Surface Mount"
				(at 15.24 -17.78 0)
				(effects
					(font
						(size 1.27 1.27)
						(thickness 0.15)
					)
					(justify left bottom)
					(hide yes)
				)
			)
			(property "MPN" "694106106102"
				(at 15.24 -7.62 0)
				(effects
					(font
						(size 1.27 1.27)
						(thickness 0.15)
					)
					(justify left bottom)
				)
			)
			(property "Manufacturer" "Würth Elektronik"
				(at 15.24 -20.32 0)
				(effects
					(font
						(size 1.27 1.27)
						(thickness 0.15)
					)
					(justify left bottom)
					(hide yes)
				)
			)
			(property "Author" "Antmicro"
				(at 15.24 -22.86 0)
				(effects
					(font
						(size 1.27 1.27)
						(thickness 0.15)
					)
					(justify left bottom)
					(hide yes)
				)
			)
			(property "License" "Apache-2.0"
				(at 15.24 -25.4 0)
				(effects
					(font
						(size 1.27 1.27)
						(thickness 0.15)
					)
					(justify left bottom)
					(hide yes)
				)
			)
			(property "ki_keywords" "CONNECTOR"
				(at 0 0 0)
				(effects
					(font
						(size 1.27 1.27)
					)
					(hide yes)
				)
			)
			(symbol "BarrelJack_Pin2mm_694106106102_1_1"
				(rectangle
					(start -12.7 1.905)
					(end -2.54 -6.985)
					(stroke
						(width 0.254)
						(type default)
					)
					(fill
						(type background)
					)
				)
				(rectangle
					(start -8.255 0.635)
					(end -4.445 -0.635)
					(stroke
						(width 0.254)
						(type default)
					)
					(fill
						(type outline)
					)
				)
				(arc
					(start -8.255 -0.635)
					(mid -8.8873 0)
					(end -8.255 0.635)
					(stroke
						(width 0.254)
						(type default)
					)
					(fill
						(type outline)
					)
				)
				(polyline
					(pts
						(xy -6.35 -2.54) (xy -6.985 -2.54) (xy -6.35 -3.81) (xy -5.715 -2.54) (xy -6.35 -2.54)
					)
					(stroke
						(width 0.254)
						(type default)
					)
					(fill
						(type none)
					)
				)
				(rectangle
					(start -4.445 1.27)
					(end -3.81 -1.27)
					(stroke
						(width 0.254)
						(type default)
					)
					(fill
						(type none)
					)
				)
				(polyline
					(pts
						(xy -2.54 0) (xy -3.81 0)
					)
					(stroke
						(width 0.254)
						(type default)
					)
					(fill
						(type background)
					)
				)
				(polyline
					(pts
						(xy -2.54 -2.54) (xy -5.715 -2.54)
					)
					(stroke
						(width 0.254)
						(type default)
					)
					(fill
						(type background)
					)
				)
				(polyline
					(pts
						(xy -2.54 -5.08) (xy -7.62 -5.08) (xy -8.89 -3.81) (xy -10.16 -5.08)
					)
					(stroke
						(width 0.254)
						(type default)
					)
					(fill
						(type none)
					)
				)
				(pin passive line
					(at 0 0 180)
					(length 2.54)
					(name "1"
						(effects
							(font
								(size 1.27 1.27)
							)
						)
					)
					(number "1"
						(effects
							(font
								(size 1.27 1.27)
							)
						)
					)
				)
				(pin passive line
					(at 0 0 180)
					(length 2.54)
					(hide yes)
					(name "1"
						(effects
							(font
								(size 1.27 1.27)
							)
						)
					)
					(number "1"
						(effects
							(font
								(size 1.27 1.27)
							)
						)
					)
				)
				(pin passive line
					(at 0 -2.54 180)
					(length 2.54)
					(name "3"
						(effects
							(font
								(size 1.27 1.27)
							)
						)
					)
					(number "3"
						(effects
							(font
								(size 1.27 1.27)
							)
						)
					)
				)
				(pin passive line
					(at 0 -5.08 180)
					(length 2.54)
					(name "2"
						(effects
							(font
								(size 1.27 1.27)
							)
						)
					)
					(number "2"
						(effects
							(font
								(size 1.27 1.27)
							)
						)
					)
				)
			)
		)
	(symbol "antmicroCapacitors0402:C_100n_0402"
			(pin_numbers
				(hide yes)
			)
			(pin_names
				(hide yes)
			)
			(exclude_from_sim no)
			(in_bom yes)
			(on_board yes)
			(property "Reference" "C"
				(at 20.32 -5.08 0)
				(effects
					(font
						(size 1.27 1.27)
						(thickness 0.15)
					)
					(justify left bottom)
				)
			)
			(property "Value" "C_100n_0402"
				(at 20.32 -10.16 0)
				(effects
					(font
						(size 1.27 1.27)
						(thickness 0.15)
					)
					(justify left bottom)
					(hide yes)
				)
			)
			(property "Footprint" "antmicro-footprints:C_0402_1005Metric"
				(at 20.32 -12.7 0)
				(effects
					(font
						(size 1.27 1.27)
						(thickness 0.15)
					)
					(justify left bottom)
					(hide yes)
				)
			)
			(property "Datasheet" "https://www.murata.com/products/productdetail?partno=GRM155R61H104KE14%23"
				(at 20.32 -15.24 0)
				(effects
					(font
						(size 1.27 1.27)
						(thickness 0.15)
					)
					(justify left bottom)
					(hide yes)
				)
			)
			(property "Description" "SMD Multilayer Ceramic Capacitor, 0.1 µF, 50 V, 0402 [1005 Metric], ± 10%, X5R, GRM Series"
				(at 0 0 0)
				(effects
					(font
						(size 1.27 1.27)
					)
					(hide yes)
				)
			)
			(property "MPN" "GRM155R61H104KE14D"
				(at 20.32 -17.78 0)
				(effects
					(font
						(size 1.27 1.27)
						(thickness 0.15)
					)
					(justify left bottom)
					(hide yes)
				)
			)
			(property "Manufacturer" "Murata"
				(at 20.32 -20.32 0)
				(effects
					(font
						(size 1.27 1.27)
						(thickness 0.15)
					)
					(justify left bottom)
					(hide yes)
				)
			)
			(property "License" "Apache-2.0"
				(at 20.32 -22.86 0)
				(effects
					(font
						(size 1.27 1.27)
						(thickness 0.15)
					)
					(justify left bottom)
					(hide yes)
				)
			)
			(property "Author" "Antmicro"
				(at 20.32 -25.4 0)
				(effects
					(font
						(size 1.27 1.27)
						(thickness 0.15)
					)
					(justify left bottom)
					(hide yes)
				)
			)
			(property "Val" "100n"
				(at 20.32 -7.62 0)
				(effects
					(font
						(size 1.27 1.27)
						(thickness 0.15)
					)
					(justify left bottom)
				)
			)
			(property "Voltage" "50V"
				(at 20.32 -27.94 0)
				(effects
					(font
						(size 1.27 1.27)
					)
					(justify left bottom)
					(hide yes)
				)
			)
			(property "Dielectric" "X5R"
				(at 20.32 -30.48 0)
				(effects
					(font
						(size 1.27 1.27)
					)
					(justify left bottom)
					(hide yes)
				)
			)
			(property "ki_keywords" "0402, SMT, CAPACITOR, PASSIVE, CERAMIC, MLCC"
				(at 0 0 0)
				(effects
					(font
						(size 1.27 1.27)
					)
					(hide yes)
				)
			)
			(symbol "C_100n_0402_0_1"
				(polyline
					(pts
						(xy 2.032 -1.524) (xy 2.032 1.524)
					)
					(stroke
						(width 0.3048)
						(type default)
					)
					(fill
						(type none)
					)
				)
				(polyline
					(pts
						(xy 3.048 -1.524) (xy 3.048 1.524)
					)
					(stroke
						(width 0.3302)
						(type default)
					)
					(fill
						(type none)
					)
				)
			)
			(symbol "C_100n_0402_1_1"
				(pin passive line
					(at 0 0 0)
					(length 2.032)
					(name "~"
						(effects
							(font
								(size 1.27 1.27)
							)
						)
					)
					(number "1"
						(effects
							(font
								(size 1.27 1.27)
							)
						)
					)
				)
				(pin passive line
					(at 5.08 0 180)
					(length 2.032)
					(name "~"
						(effects
							(font
								(size 1.27 1.27)
							)
						)
					)
					(number "2"
						(effects
							(font
								(size 1.27 1.27)
							)
						)
					)
				)
			)
		)
	(symbol "antmicroCapacitors0402:C_10n_0402"
			(pin_numbers
				(hide yes)
			)
			(pin_names
				(hide yes)
			)
			(exclude_from_sim no)
			(in_bom yes)
			(on_board yes)
			(property "Reference" "C"
				(at 20.32 -5.08 0)
				(effects
					(font
						(size 1.27 1.27)
						(thickness 0.15)
					)
					(justify left bottom)
				)
			)
			(property "Value" "C_10n_0402"
				(at 20.32 -10.16 0)
				(effects
					(font
						(size 1.27 1.27)
						(thickness 0.15)
					)
					(justify left bottom)
					(hide yes)
				)
			)
			(property "Footprint" "antmicro-footprints:C_0402_1005Metric"
				(at 20.32 -12.7 0)
				(effects
					(font
						(size 1.27 1.27)
						(thickness 0.15)
					)
					(justify left bottom)
					(hide yes)
				)
			)
			(property "Datasheet" "https://www.murata.com/products/productdetail?partno=GRM155R71H103KA88%23"
				(at 20.32 -15.24 0)
				(effects
					(font
						(size 1.27 1.27)
						(thickness 0.15)
					)
					(justify left bottom)
					(hide yes)
				)
			)
			(property "Description" "SMD Multilayer Ceramic Capacitor, 10000 pF, 50 V, 0402 [1005 Metric], ± 10%, X7R, GRM Series"
				(at 0 0 0)
				(effects
					(font
						(size 1.27 1.27)
					)
					(hide yes)
				)
			)
			(property "MPN" "GRM155R71H103KA88D"
				(at 20.32 -17.78 0)
				(effects
					(font
						(size 1.27 1.27)
						(thickness 0.15)
					)
					(justify left bottom)
					(hide yes)
				)
			)
			(property "Manufacturer" "Murata"
				(at 20.32 -20.32 0)
				(effects
					(font
						(size 1.27 1.27)
						(thickness 0.15)
					)
					(justify left bottom)
					(hide yes)
				)
			)
			(property "License" "Apache-2.0"
				(at 20.32 -22.86 0)
				(effects
					(font
						(size 1.27 1.27)
						(thickness 0.15)
					)
					(justify left bottom)
					(hide yes)
				)
			)
			(property "Author" "Antmicro"
				(at 20.32 -25.4 0)
				(effects
					(font
						(size 1.27 1.27)
						(thickness 0.15)
					)
					(justify left bottom)
					(hide yes)
				)
			)
			(property "Val" "10n"
				(at 20.32 -7.62 0)
				(effects
					(font
						(size 1.27 1.27)
						(thickness 0.15)
					)
					(justify left bottom)
				)
			)
			(property "Voltage" "50V"
				(at 20.32 -27.94 0)
				(effects
					(font
						(size 1.27 1.27)
					)
					(justify left bottom)
					(hide yes)
				)
			)
			(property "Dielectric" "X7R"
				(at 20.32 -30.48 0)
				(effects
					(font
						(size 1.27 1.27)
					)
					(justify left bottom)
					(hide yes)
				)
			)
			(property "ki_keywords" "0402, SMT, CAPACITOR, PASSIVE"
				(at 0 0 0)
				(effects
					(font
						(size 1.27 1.27)
					)
					(hide yes)
				)
			)
			(symbol "C_10n_0402_0_1"
				(polyline
					(pts
						(xy 2.032 -1.524) (xy 2.032 1.524)
					)
					(stroke
						(width 0.3048)
						(type default)
					)
					(fill
						(type none)
					)
				)
				(polyline
					(pts
						(xy 3.048 -1.524) (xy 3.048 1.524)
					)
					(stroke
						(width 0.3302)
						(type default)
					)
					(fill
						(type none)
					)
				)
			)
			(symbol "C_10n_0402_1_1"
				(pin passive line
					(at 0 0 0)
					(length 2.032)
					(name "~"
						(effects
							(font
								(size 1.27 1.27)
							)
						)
					)
					(number "1"
						(effects
							(font
								(size 1.27 1.27)
							)
						)
					)
				)
				(pin passive line
					(at 5.08 0 180)
					(length 2.032)
					(name "~"
						(effects
							(font
								(size 1.27 1.27)
							)
						)
					)
					(number "2"
						(effects
							(font
								(size 1.27 1.27)
							)
						)
					)
				)
			)
		)
	(symbol "antmicroCapacitors0402:C_10u_10V_0402"
			(pin_numbers
				(hide yes)
			)
			(pin_names
				(hide yes)
			)
			(exclude_from_sim no)
			(in_bom yes)
			(on_board yes)
			(property "Reference" "C"
				(at 20.32 -5.08 0)
				(effects
					(font
						(size 1.27 1.27)
						(thickness 0.15)
					)
					(justify left bottom)
				)
			)
			(property "Value" "C_10u_10V_0402"
				(at 20.32 -10.16 0)
				(effects
					(font
						(size 1.27 1.27)
						(thickness 0.15)
					)
					(justify left bottom)
					(hide yes)
				)
			)
			(property "Footprint" "antmicro-footprints:C_0402_1005Metric"
				(at 20.32 -12.7 0)
				(effects
					(font
						(size 1.27 1.27)
						(thickness 0.15)
					)
					(justify left bottom)
					(hide yes)
				)
			)
			(property "Datasheet" "https://www.murata.com/products/productdetail?partno=GRM155R61A106ME11%23"
				(at 20.32 -15.24 0)
				(effects
					(font
						(size 1.27 1.27)
						(thickness 0.15)
					)
					(justify left bottom)
					(hide yes)
				)
			)
			(property "Description" "Multilayer Ceramic Capacitors MLCC - SMD/SMT 10 uF 10 VDC 20% 0402 X5R"
				(at 0 0 0)
				(effects
					(font
						(size 1.27 1.27)
					)
					(hide yes)
				)
			)
			(property "MPN" "GRM155R61A106ME11D"
				(at 20.32 -17.78 0)
				(effects
					(font
						(size 1.27 1.27)
						(thickness 0.15)
					)
					(justify left bottom)
					(hide yes)
				)
			)
			(property "Manufacturer" "Murata"
				(at 20.32 -20.32 0)
				(effects
					(font
						(size 1.27 1.27)
						(thickness 0.15)
					)
					(justify left bottom)
					(hide yes)
				)
			)
			(property "License" "Apache-2.0"
				(at 20.32 -22.86 0)
				(effects
					(font
						(size 1.27 1.27)
						(thickness 0.15)
					)
					(justify left bottom)
					(hide yes)
				)
			)
			(property "Author" "Antmicro"
				(at 20.32 -25.4 0)
				(effects
					(font
						(size 1.27 1.27)
						(thickness 0.15)
					)
					(justify left bottom)
					(hide yes)
				)
			)
			(property "Val" "10u"
				(at 20.32 -7.62 0)
				(effects
					(font
						(size 1.27 1.27)
						(thickness 0.15)
					)
					(justify left bottom)
				)
			)
			(property "Voltage" "10V"
				(at 20.32 -27.94 0)
				(effects
					(font
						(size 1.27 1.27)
					)
					(justify left bottom)
					(hide yes)
				)
			)
			(property "Dielectric" "X5R"
				(at 20.32 -30.48 0)
				(effects
					(font
						(size 1.27 1.27)
					)
					(justify left bottom)
					(hide yes)
				)
			)
			(property "ki_keywords" "0402, SMT, CAPACITOR, PASSIVE, CERAMIC"
				(at 0 0 0)
				(effects
					(font
						(size 1.27 1.27)
					)
					(hide yes)
				)
			)
			(symbol "C_10u_10V_0402_0_1"
				(polyline
					(pts
						(xy 2.032 -1.524) (xy 2.032 1.524)
					)
					(stroke
						(width 0.3048)
						(type default)
					)
					(fill
						(type none)
					)
				)
				(polyline
					(pts
						(xy 3.048 -1.524) (xy 3.048 1.524)
					)
					(stroke
						(width 0.3302)
						(type default)
					)
					(fill
						(type none)
					)
				)
			)
			(symbol "C_10u_10V_0402_1_1"
				(pin passive line
					(at 0 0 0)
					(length 2.032)
					(name "~"
						(effects
							(font
								(size 1.27 1.27)
							)
						)
					)
					(number "1"
						(effects
							(font
								(size 1.27 1.27)
							)
						)
					)
				)
				(pin passive line
					(at 5.08 0 180)
					(length 2.032)
					(name "~"
						(effects
							(font
								(size 1.27 1.27)
							)
						)
					)
					(number "2"
						(effects
							(font
								(size 1.27 1.27)
							)
						)
					)
				)
			)
		)
	(symbol "antmicroCapacitors0402:C_10u_6.3V_0402"
			(pin_numbers
				(hide yes)
			)
			(pin_names
				(hide yes)
			)
			(exclude_from_sim no)
			(in_bom yes)
			(on_board yes)
			(property "Reference" "C"
				(at 20.32 -5.08 0)
				(effects
					(font
						(size 1.27 1.27)
						(thickness 0.15)
					)
					(justify left bottom)
				)
			)
			(property "Value" "C_10u_6.3V_0402"
				(at 20.32 -10.16 0)
				(effects
					(font
						(size 1.27 1.27)
						(thickness 0.15)
					)
					(justify left bottom)
					(hide yes)
				)
			)
			(property "Footprint" "antmicro-footprints:C_0402_1005Metric"
				(at 20.32 -12.7 0)
				(effects
					(font
						(size 1.27 1.27)
						(thickness 0.15)
					)
					(justify left bottom)
					(hide yes)
				)
			)
			(property "Datasheet" "https://www.murata.com/products/productdetail?partno=GRM155R60J106ME15%23"
				(at 20.32 -15.24 0)
				(effects
					(font
						(size 1.27 1.27)
						(thickness 0.15)
					)
					(justify left bottom)
					(hide yes)
				)
			)
			(property "Description" "SMD Multilayer Ceramic Capacitor, 10 µF, 6.3 V, 0402 [1005 Metric], ± 20%, X5R, GRM Series"
				(at 0 0 0)
				(effects
					(font
						(size 1.27 1.27)
					)
					(hide yes)
				)
			)
			(property "MPN" "GRM155R60J106ME15D"
				(at 20.32 -17.78 0)
				(effects
					(font
						(size 1.27 1.27)
						(thickness 0.15)
					)
					(justify left bottom)
					(hide yes)
				)
			)
			(property "Manufacturer" "Murata"
				(at 20.32 -20.32 0)
				(effects
					(font
						(size 1.27 1.27)
						(thickness 0.15)
					)
					(justify left bottom)
					(hide yes)
				)
			)
			(property "License" "Apache-2.0"
				(at 20.32 -22.86 0)
				(effects
					(font
						(size 1.27 1.27)
						(thickness 0.15)
					)
					(justify left bottom)
					(hide yes)
				)
			)
			(property "Author" "Antmicro"
				(at 20.32 -25.4 0)
				(effects
					(font
						(size 1.27 1.27)
						(thickness 0.15)
					)
					(justify left bottom)
					(hide yes)
				)
			)
			(property "Val" "10u"
				(at 20.32 -7.62 0)
				(effects
					(font
						(size 1.27 1.27)
						(thickness 0.15)
					)
					(justify left bottom)
				)
			)
			(property "Voltage" "6.3V"
				(at 20.32 -27.94 0)
				(effects
					(font
						(size 1.27 1.27)
					)
					(justify left bottom)
					(hide yes)
				)
			)
			(property "Dielectric" "X5R"
				(at 20.32 -30.48 0)
				(effects
					(font
						(size 1.27 1.27)
					)
					(justify left bottom)
					(hide yes)
				)
			)
			(property "ki_keywords" "0402, SMT, CAPACITOR, PASSIVE, CERAMIC"
				(at 0 0 0)
				(effects
					(font
						(size 1.27 1.27)
					)
					(hide yes)
				)
			)
			(symbol "C_10u_6.3V_0402_0_1"
				(polyline
					(pts
						(xy 2.032 -1.524) (xy 2.032 1.524)
					)
					(stroke
						(width 0.3048)
						(type default)
					)
					(fill
						(type none)
					)
				)
				(polyline
					(pts
						(xy 3.048 -1.524) (xy 3.048 1.524)
					)
					(stroke
						(width 0.3302)
						(type default)
					)
					(fill
						(type none)
					)
				)
			)
			(symbol "C_10u_6.3V_0402_1_1"
				(pin passive line
					(at 0 0 0)
					(length 2.032)
					(name "~"
						(effects
							(font
								(size 1.27 1.27)
							)
						)
					)
					(number "1"
						(effects
							(font
								(size 1.27 1.27)
							)
						)
					)
				)
				(pin passive line
					(at 5.08 0 180)
					(length 2.032)
					(name "~"
						(effects
							(font
								(size 1.27 1.27)
							)
						)
					)
					(number "2"
						(effects
							(font
								(size 1.27 1.27)
							)
						)
					)
				)
			)
		)
	(symbol "antmicroCapacitors0402:C_18p_0402"
			(pin_numbers
				(hide yes)
			)
			(pin_names
				(hide yes)
			)
			(exclude_from_sim no)
			(in_bom yes)
			(on_board yes)
			(property "Reference" "C"
				(at 20.32 -5.08 0)
				(effects
					(font
						(size 1.27 1.27)
						(thickness 0.15)
					)
					(justify left bottom)
				)
			)
			(property "Value" "C_18p_0402"
				(at 20.32 -10.16 0)
				(effects
					(font
						(size 1.27 1.27)
						(thickness 0.15)
					)
					(justify left bottom)
					(hide yes)
				)
			)
			(property "Footprint" "antmicro-footprints:C_0402_1005Metric"
				(at 20.32 -12.7 0)
				(effects
					(font
						(size 1.27 1.27)
						(thickness 0.15)
					)
					(justify left bottom)
					(hide yes)
				)
			)
			(property "Datasheet" "https://product.samsungsem.com/mlcc/CL05C180JB51PN.do"
				(at 20.32 -15.24 0)
				(effects
					(font
						(size 1.27 1.27)
						(thickness 0.15)
					)
					(justify left bottom)
					(hide yes)
				)
			)
			(property "Description" "SMD Multilayer Ceramic Capacitor, 18 pF, 50 V, 0402 [1005 Metric], ± 5%, C0G / NP0, MC"
				(at 0 0 0)
				(effects
					(font
						(size 1.27 1.27)
					)
					(hide yes)
				)
			)
			(property "MPN" "CL05C180JB51PNC"
				(at 20.32 -17.78 0)
				(effects
					(font
						(size 1.27 1.27)
						(thickness 0.15)
					)
					(justify left bottom)
					(hide yes)
				)
			)
			(property "Manufacturer" "Samsung Electro-Mechanics"
				(at 20.32 -20.32 0)
				(effects
					(font
						(size 1.27 1.27)
						(thickness 0.15)
					)
					(justify left bottom)
					(hide yes)
				)
			)
			(property "License" "Apache-2.0"
				(at 20.32 -22.86 0)
				(effects
					(font
						(size 1.27 1.27)
						(thickness 0.15)
					)
					(justify left bottom)
					(hide yes)
				)
			)
			(property "Author" "Antmicro"
				(at 20.32 -25.4 0)
				(effects
					(font
						(size 1.27 1.27)
						(thickness 0.15)
					)
					(justify left bottom)
					(hide yes)
				)
			)
			(property "Val" "18p"
				(at 20.32 -7.62 0)
				(effects
					(font
						(size 1.27 1.27)
						(thickness 0.15)
					)
					(justify left bottom)
				)
			)
			(property "Voltage" ""
				(at 20.32 -27.94 0)
				(effects
					(font
						(size 1.27 1.27)
					)
					(justify left bottom)
					(hide yes)
				)
			)
			(property "Dielectric" ""
				(at 20.32 -30.48 0)
				(effects
					(font
						(size 1.27 1.27)
					)
					(justify left bottom)
					(hide yes)
				)
			)
			(property "ki_keywords" "0402, SMT, CAPACITOR, PASSIVE"
				(at 0 0 0)
				(effects
					(font
						(size 1.27 1.27)
					)
					(hide yes)
				)
			)
			(symbol "C_18p_0402_0_1"
				(polyline
					(pts
						(xy 2.032 -1.524) (xy 2.032 1.524)
					)
					(stroke
						(width 0.3048)
						(type default)
					)
					(fill
						(type none)
					)
				)
				(polyline
					(pts
						(xy 3.048 -1.524) (xy 3.048 1.524)
					)
					(stroke
						(width 0.3302)
						(type default)
					)
					(fill
						(type none)
					)
				)
			)
			(symbol "C_18p_0402_1_1"
				(pin passive line
					(at 0 0 0)
					(length 2.032)
					(name "~"
						(effects
							(font
								(size 1.27 1.27)
							)
						)
					)
					(number "1"
						(effects
							(font
								(size 1.27 1.27)
							)
						)
					)
				)
				(pin passive line
					(at 5.08 0 180)
					(length 2.032)
					(name "~"
						(effects
							(font
								(size 1.27 1.27)
							)
						)
					)
					(number "2"
						(effects
							(font
								(size 1.27 1.27)
							)
						)
					)
				)
			)
		)
	(symbol "antmicroCapacitors0402:C_1u_0402"
			(pin_numbers
				(hide yes)
			)
			(pin_names
				(hide yes)
			)
			(exclude_from_sim no)
			(in_bom yes)
			(on_board yes)
			(property "Reference" "C"
				(at 20.32 -5.08 0)
				(effects
					(font
						(size 1.27 1.27)
						(thickness 0.15)
					)
					(justify left bottom)
				)
			)
			(property "Value" "C_1u_0402"
				(at 20.32 -10.16 0)
				(effects
					(font
						(size 1.27 1.27)
						(thickness 0.15)
					)
					(justify left bottom)
					(hide yes)
				)
			)
			(property "Footprint" "antmicro-footprints:C_0402_1005Metric"
				(at 20.32 -12.7 0)
				(effects
					(font
						(size 1.27 1.27)
						(thickness 0.15)
					)
					(justify left bottom)
					(hide yes)
				)
			)
			(property "Datasheet" "https://product.tdk.com/en/search/capacitor/ceramic/mlcc/info?part_no=C1005X6S1A105K050BC"
				(at 20.32 -15.24 0)
				(effects
					(font
						(size 1.27 1.27)
						(thickness 0.15)
					)
					(justify left bottom)
					(hide yes)
				)
			)
			(property "Description" "SMD Multilayer Ceramic Capacitor, 1 µF, 10 V, 0402 [1005 Metric], ± 10%, X6S, C"
				(at 0 0 0)
				(effects
					(font
						(size 1.27 1.27)
					)
					(hide yes)
				)
			)
			(property "MPN" "C1005X6S1A105K050BC"
				(at 20.32 -17.78 0)
				(effects
					(font
						(size 1.27 1.27)
						(thickness 0.15)
					)
					(justify left bottom)
					(hide yes)
				)
			)
			(property "Manufacturer" "TDK"
				(at 20.32 -20.32 0)
				(effects
					(font
						(size 1.27 1.27)
						(thickness 0.15)
					)
					(justify left bottom)
					(hide yes)
				)
			)
			(property "License" "Apache-2.0"
				(at 20.32 -22.86 0)
				(effects
					(font
						(size 1.27 1.27)
						(thickness 0.15)
					)
					(justify left bottom)
					(hide yes)
				)
			)
			(property "Author" "Antmicro"
				(at 20.32 -25.4 0)
				(effects
					(font
						(size 1.27 1.27)
						(thickness 0.15)
					)
					(justify left bottom)
					(hide yes)
				)
			)
			(property "Val" "1u"
				(at 20.32 -7.62 0)
				(effects
					(font
						(size 1.27 1.27)
						(thickness 0.15)
					)
					(justify left bottom)
				)
			)
			(property "Voltage" ""
				(at 20.32 -27.94 0)
				(effects
					(font
						(size 1.27 1.27)
					)
					(justify left bottom)
					(hide yes)
				)
			)
			(property "Dielectric" ""
				(at 20.32 -30.48 0)
				(effects
					(font
						(size 1.27 1.27)
					)
					(justify left bottom)
					(hide yes)
				)
			)
			(property "ki_keywords" "0402, SMT, CAPACITOR, PASSIVE, CERAMIC, MLCC"
				(at 0 0 0)
				(effects
					(font
						(size 1.27 1.27)
					)
					(hide yes)
				)
			)
			(symbol "C_1u_0402_0_1"
				(polyline
					(pts
						(xy 2.032 -1.524) (xy 2.032 1.524)
					)
					(stroke
						(width 0.3048)
						(type default)
					)
					(fill
						(type none)
					)
				)
				(polyline
					(pts
						(xy 3.048 -1.524) (xy 3.048 1.524)
					)
					(stroke
						(width 0.3302)
						(type default)
					)
					(fill
						(type none)
					)
				)
			)
			(symbol "C_1u_0402_1_1"
				(pin passive line
					(at 0 0 0)
					(length 2.032)
					(name "~"
						(effects
							(font
								(size 1.27 1.27)
							)
						)
					)
					(number "1"
						(effects
							(font
								(size 1.27 1.27)
							)
						)
					)
				)
				(pin passive line
					(at 5.08 0 180)
					(length 2.032)
					(name "~"
						(effects
							(font
								(size 1.27 1.27)
							)
						)
					)
					(number "2"
						(effects
							(font
								(size 1.27 1.27)
							)
						)
					)
				)
			)
		)
	(symbol "antmicroCapacitors0402:C_1u_25V_0402"
			(pin_numbers
				(hide yes)
			)
			(pin_names
				(hide yes)
			)
			(exclude_from_sim no)
			(in_bom yes)
			(on_board yes)
			(property "Reference" "C"
				(at 20.32 -5.08 0)
				(effects
					(font
						(size 1.27 1.27)
						(thickness 0.15)
					)
					(justify left bottom)
				)
			)
			(property "Value" "C_1u_25V_0402"
				(at 20.32 -10.16 0)
				(effects
					(font
						(size 1.27 1.27)
						(thickness 0.15)
					)
					(justify left bottom)
					(hide yes)
				)
			)
			(property "Footprint" "antmicro-footprints:C_0402_1005Metric"
				(at 20.32 -12.7 0)
				(effects
					(font
						(size 1.27 1.27)
						(thickness 0.15)
					)
					(justify left bottom)
					(hide yes)
				)
			)
			(property "Datasheet" "https://www.murata.com/products/productdetail?partno=GRM155R61E105KE11%23"
				(at 20.32 -15.24 0)
				(effects
					(font
						(size 1.27 1.27)
						(thickness 0.15)
					)
					(justify left bottom)
					(hide yes)
				)
			)
			(property "Description" "SMD Multilayer Ceramic Capacitor, 1 µF, 25 V, 0402 [1005 Metric], ± 10%, X5R, GRM Series"
				(at 0 0 0)
				(effects
					(font
						(size 1.27 1.27)
					)
					(hide yes)
				)
			)
			(property "MPN" "GRM155R61E105KE11J"
				(at 20.32 -17.78 0)
				(effects
					(font
						(size 1.27 1.27)
						(thickness 0.15)
					)
					(justify left bottom)
					(hide yes)
				)
			)
			(property "Manufacturer" "Murata"
				(at 20.32 -20.32 0)
				(effects
					(font
						(size 1.27 1.27)
						(thickness 0.15)
					)
					(justify left bottom)
					(hide yes)
				)
			)
			(property "License" "Apache-2.0"
				(at 20.32 -22.86 0)
				(effects
					(font
						(size 1.27 1.27)
						(thickness 0.15)
					)
					(justify left bottom)
					(hide yes)
				)
			)
			(property "Author" "Antmicro"
				(at 20.32 -25.4 0)
				(effects
					(font
						(size 1.27 1.27)
						(thickness 0.15)
					)
					(justify left bottom)
					(hide yes)
				)
			)
			(property "Val" "1u"
				(at 20.32 -7.62 0)
				(effects
					(font
						(size 1.27 1.27)
						(thickness 0.15)
					)
					(justify left bottom)
				)
			)
			(property "Voltage" "25V"
				(at 20.32 -27.94 0)
				(effects
					(font
						(size 1.27 1.27)
					)
					(justify left bottom)
					(hide yes)
				)
			)
			(property "Dielectric" "X5R"
				(at 20.32 -30.48 0)
				(effects
					(font
						(size 1.27 1.27)
					)
					(justify left bottom)
					(hide yes)
				)
			)
			(property "ki_keywords" "0402, SMT, CAPACITOR, PASSIVE, CERAMIC"
				(at 0 0 0)
				(effects
					(font
						(size 1.27 1.27)
					)
					(hide yes)
				)
			)
			(symbol "C_1u_25V_0402_0_1"
				(polyline
					(pts
						(xy 2.032 -1.524) (xy 2.032 1.524)
					)
					(stroke
						(width 0.3048)
						(type default)
					)
					(fill
						(type none)
					)
				)
				(polyline
					(pts
						(xy 3.048 -1.524) (xy 3.048 1.524)
					)
					(stroke
						(width 0.3302)
						(type default)
					)
					(fill
						(type none)
					)
				)
			)
			(symbol "C_1u_25V_0402_1_1"
				(pin passive line
					(at 0 0 0)
					(length 2.032)
					(name "~"
						(effects
							(font
								(size 1.27 1.27)
							)
						)
					)
					(number "1"
						(effects
							(font
								(size 1.27 1.27)
							)
						)
					)
				)
				(pin passive line
					(at 5.08 0 180)
					(length 2.032)
					(name "~"
						(effects
							(font
								(size 1.27 1.27)
							)
						)
					)
					(number "2"
						(effects
							(font
								(size 1.27 1.27)
							)
						)
					)
				)
			)
		)
	(symbol "antmicroCapacitors0402:C_220n_16V_0402"
			(pin_numbers
				(hide yes)
			)
			(pin_names
				(hide yes)
			)
			(exclude_from_sim no)
			(in_bom yes)
			(on_board yes)
			(property "Reference" "C"
				(at 20.32 -5.08 0)
				(effects
					(font
						(size 1.27 1.27)
						(thickness 0.15)
					)
					(justify left bottom)
				)
			)
			(property "Value" "C_220n_16V_0402"
				(at 20.32 -10.16 0)
				(effects
					(font
						(size 1.27 1.27)
						(thickness 0.15)
					)
					(justify left bottom)
					(hide yes)
				)
			)
			(property "Footprint" "antmicro-footprints:C_0402_1005Metric"
				(at 20.32 -12.7 0)
				(effects
					(font
						(size 1.27 1.27)
						(thickness 0.15)
					)
					(justify left bottom)
					(hide yes)
				)
			)
			(property "Datasheet" "https://www.murata.com/products/productdetail?partno=GRM155R71C224KA12%23"
				(at 20.32 -15.24 0)
				(effects
					(font
						(size 1.27 1.27)
						(thickness 0.15)
					)
					(justify left bottom)
					(hide yes)
				)
			)
			(property "Description" "SMD Multilayer Ceramic Capacitor, 0.22 µF, 16 V, 0402 [1005 Metric], ± 10%, X7R, GRM Series"
				(at 0 0 0)
				(effects
					(font
						(size 1.27 1.27)
					)
					(hide yes)
				)
			)
			(property "MPN" "GRM155R71C224KA12D"
				(at 20.32 -17.78 0)
				(effects
					(font
						(size 1.27 1.27)
						(thickness 0.15)
					)
					(justify left bottom)
					(hide yes)
				)
			)
			(property "Manufacturer" "Murata"
				(at 20.32 -20.32 0)
				(effects
					(font
						(size 1.27 1.27)
						(thickness 0.15)
					)
					(justify left bottom)
					(hide yes)
				)
			)
			(property "License" "Apache-2.0"
				(at 20.32 -22.86 0)
				(effects
					(font
						(size 1.27 1.27)
						(thickness 0.15)
					)
					(justify left bottom)
					(hide yes)
				)
			)
			(property "Author" "Antmicro"
				(at 20.32 -25.4 0)
				(effects
					(font
						(size 1.27 1.27)
						(thickness 0.15)
					)
					(justify left bottom)
					(hide yes)
				)
			)
			(property "Val" "220n"
				(at 20.32 -7.62 0)
				(effects
					(font
						(size 1.27 1.27)
						(thickness 0.15)
					)
					(justify left bottom)
				)
			)
			(property "Voltage" "16V"
				(at 20.32 -27.94 0)
				(effects
					(font
						(size 1.27 1.27)
					)
					(justify left bottom)
					(hide yes)
				)
			)
			(property "Dielectric" "X7R"
				(at 20.32 -30.48 0)
				(effects
					(font
						(size 1.27 1.27)
					)
					(justify left bottom)
					(hide yes)
				)
			)
			(property "ki_keywords" "0402, SMT, CAPACITOR, PASSIVE, CERAMIC"
				(at 0 0 0)
				(effects
					(font
						(size 1.27 1.27)
					)
					(hide yes)
				)
			)
			(symbol "C_220n_16V_0402_0_1"
				(polyline
					(pts
						(xy 2.032 -1.524) (xy 2.032 1.524)
					)
					(stroke
						(width 0.3048)
						(type default)
					)
					(fill
						(type none)
					)
				)
				(polyline
					(pts
						(xy 3.048 -1.524) (xy 3.048 1.524)
					)
					(stroke
						(width 0.3302)
						(type default)
					)
					(fill
						(type none)
					)
				)
			)
			(symbol "C_220n_16V_0402_1_1"
				(pin passive line
					(at 0 0 0)
					(length 2.032)
					(name "~"
						(effects
							(font
								(size 1.27 1.27)
							)
						)
					)
					(number "1"
						(effects
							(font
								(size 1.27 1.27)
							)
						)
					)
				)
				(pin passive line
					(at 5.08 0 180)
					(length 2.032)
					(name "~"
						(effects
							(font
								(size 1.27 1.27)
							)
						)
					)
					(number "2"
						(effects
							(font
								(size 1.27 1.27)
							)
						)
					)
				)
			)
		)
	(symbol "antmicroCapacitors0402:C_22p_0402"
			(pin_numbers
				(hide yes)
			)
			(pin_names
				(hide yes)
			)
			(exclude_from_sim no)
			(in_bom yes)
			(on_board yes)
			(property "Reference" "C"
				(at 20.32 -5.08 0)
				(effects
					(font
						(size 1.27 1.27)
						(thickness 0.15)
					)
					(justify left bottom)
				)
			)
			(property "Value" "C_22p_0402"
				(at 20.32 -10.16 0)
				(effects
					(font
						(size 1.27 1.27)
						(thickness 0.15)
					)
					(justify left bottom)
					(hide yes)
				)
			)
			(property "Footprint" "antmicro-footprints:C_0402_1005Metric"
				(at 20.32 -12.7 0)
				(effects
					(font
						(size 1.27 1.27)
						(thickness 0.15)
					)
					(justify left bottom)
					(hide yes)
				)
			)
			(property "Datasheet" "https://www.yageo.com/en/Chart/Download/pdf/CC0402JRNPO9BN220"
				(at 20.32 -15.24 0)
				(effects
					(font
						(size 1.27 1.27)
						(thickness 0.15)
					)
					(justify left bottom)
					(hide yes)
				)
			)
			(property "Description" "SMD Multilayer Ceramic Capacitor, 22 pF, 50 V, 0402 [1005 Metric], ± 5%, C0G / NP0, CC Series"
				(at 0 0 0)
				(effects
					(font
						(size 1.27 1.27)
					)
					(hide yes)
				)
			)
			(property "MPN" "CC0402JRNPO9BN220"
				(at 20.32 -17.78 0)
				(effects
					(font
						(size 1.27 1.27)
						(thickness 0.15)
					)
					(justify left bottom)
					(hide yes)
				)
			)
			(property "Manufacturer" "YAGEO"
				(at 20.32 -20.32 0)
				(effects
					(font
						(size 1.27 1.27)
						(thickness 0.15)
					)
					(justify left bottom)
					(hide yes)
				)
			)
			(property "License" "Apache-2.0"
				(at 20.32 -22.86 0)
				(effects
					(font
						(size 1.27 1.27)
						(thickness 0.15)
					)
					(justify left bottom)
					(hide yes)
				)
			)
			(property "Author" "Antmicro"
				(at 20.32 -25.4 0)
				(effects
					(font
						(size 1.27 1.27)
						(thickness 0.15)
					)
					(justify left bottom)
					(hide yes)
				)
			)
			(property "Val" "22p"
				(at 20.32 -7.62 0)
				(effects
					(font
						(size 1.27 1.27)
						(thickness 0.15)
					)
					(justify left bottom)
				)
			)
			(property "Voltage" ""
				(at 20.32 -27.94 0)
				(effects
					(font
						(size 1.27 1.27)
					)
					(justify left bottom)
					(hide yes)
				)
			)
			(property "Dielectric" ""
				(at 20.32 -30.48 0)
				(effects
					(font
						(size 1.27 1.27)
					)
					(justify left bottom)
					(hide yes)
				)
			)
			(property "ki_keywords" "0402, SMT, CAPACITOR, PASSIVE, MLCC, CERAMIC"
				(at 0 0 0)
				(effects
					(font
						(size 1.27 1.27)
					)
					(hide yes)
				)
			)
			(symbol "C_22p_0402_0_1"
				(polyline
					(pts
						(xy 2.032 -1.524) (xy 2.032 1.524)
					)
					(stroke
						(width 0.3048)
						(type default)
					)
					(fill
						(type none)
					)
				)
				(polyline
					(pts
						(xy 3.048 -1.524) (xy 3.048 1.524)
					)
					(stroke
						(width 0.3302)
						(type default)
					)
					(fill
						(type none)
					)
				)
			)
			(symbol "C_22p_0402_1_1"
				(pin passive line
					(at 0 0 0)
					(length 2.032)
					(name "~"
						(effects
							(font
								(size 1.27 1.27)
							)
						)
					)
					(number "1"
						(effects
							(font
								(size 1.27 1.27)
							)
						)
					)
				)
				(pin passive line
					(at 5.08 0 180)
					(length 2.032)
					(name "~"
						(effects
							(font
								(size 1.27 1.27)
							)
						)
					)
					(number "2"
						(effects
							(font
								(size 1.27 1.27)
							)
						)
					)
				)
			)
		)
	(symbol "antmicroCapacitors0402:C_470n_0402"
			(pin_numbers
				(hide yes)
			)
			(pin_names
				(hide yes)
			)
			(exclude_from_sim no)
			(in_bom yes)
			(on_board yes)
			(property "Reference" "C"
				(at 20.32 -5.08 0)
				(effects
					(font
						(size 1.27 1.27)
						(thickness 0.15)
					)
					(justify left bottom)
				)
			)
			(property "Value" "C_470n_0402"
				(at 20.32 -10.16 0)
				(effects
					(font
						(size 1.27 1.27)
						(thickness 0.15)
					)
					(justify left bottom)
					(hide yes)
				)
			)
			(property "Footprint" "antmicro-footprints:C_0402_1005Metric"
				(at 20.32 -12.7 0)
				(effects
					(font
						(size 1.27 1.27)
						(thickness 0.15)
					)
					(justify left bottom)
					(hide yes)
				)
			)
			(property "Datasheet" "https://product.tdk.com/en/search/capacitor/ceramic/mlcc/info?part_no=C1005X5R1E474M050BB"
				(at 20.32 -15.24 0)
				(effects
					(font
						(size 1.27 1.27)
						(thickness 0.15)
					)
					(justify left bottom)
					(hide yes)
				)
			)
			(property "Description" "SMD Multilayer Ceramic Capacitor, 0.47 µF, 25 V, 0402 [1005 Metric], ± 20%, X5R, C"
				(at 0 0 0)
				(effects
					(font
						(size 1.27 1.27)
					)
					(hide yes)
				)
			)
			(property "MPN" "C1005X5R1E474M050BB"
				(at 20.32 -17.78 0)
				(effects
					(font
						(size 1.27 1.27)
						(thickness 0.15)
					)
					(justify left bottom)
					(hide yes)
				)
			)
			(property "Manufacturer" "TDK"
				(at 20.32 -20.32 0)
				(effects
					(font
						(size 1.27 1.27)
						(thickness 0.15)
					)
					(justify left bottom)
					(hide yes)
				)
			)
			(property "License" "Apache-2.0"
				(at 20.32 -22.86 0)
				(effects
					(font
						(size 1.27 1.27)
						(thickness 0.15)
					)
					(justify left bottom)
					(hide yes)
				)
			)
			(property "Author" "Antmicro"
				(at 20.32 -25.4 0)
				(effects
					(font
						(size 1.27 1.27)
						(thickness 0.15)
					)
					(justify left bottom)
					(hide yes)
				)
			)
			(property "Val" "470n"
				(at 20.32 -7.62 0)
				(effects
					(font
						(size 1.27 1.27)
						(thickness 0.15)
					)
					(justify left bottom)
				)
			)
			(property "Voltage" ""
				(at 20.32 -27.94 0)
				(effects
					(font
						(size 1.27 1.27)
					)
					(justify left bottom)
					(hide yes)
				)
			)
			(property "Dielectric" ""
				(at 20.32 -30.48 0)
				(effects
					(font
						(size 1.27 1.27)
					)
					(justify left bottom)
					(hide yes)
				)
			)
			(property "ki_keywords" "0402, SMT, CAPACITOR, PASSIVE, CERAMIC, MLCC"
				(at 0 0 0)
				(effects
					(font
						(size 1.27 1.27)
					)
					(hide yes)
				)
			)
			(symbol "C_470n_0402_0_1"
				(polyline
					(pts
						(xy 2.032 -1.524) (xy 2.032 1.524)
					)
					(stroke
						(width 0.3048)
						(type default)
					)
					(fill
						(type none)
					)
				)
				(polyline
					(pts
						(xy 3.048 -1.524) (xy 3.048 1.524)
					)
					(stroke
						(width 0.3302)
						(type default)
					)
					(fill
						(type none)
					)
				)
			)
			(symbol "C_470n_0402_1_1"
				(pin passive line
					(at 0 0 0)
					(length 2.032)
					(name "~"
						(effects
							(font
								(size 1.27 1.27)
							)
						)
					)
					(number "1"
						(effects
							(font
								(size 1.27 1.27)
							)
						)
					)
				)
				(pin passive line
					(at 5.08 0 180)
					(length 2.032)
					(name "~"
						(effects
							(font
								(size 1.27 1.27)
							)
						)
					)
					(number "2"
						(effects
							(font
								(size 1.27 1.27)
							)
						)
					)
				)
			)
		)
	(symbol "antmicroCapacitors0402:C_4u7_0402"
			(pin_numbers
				(hide yes)
			)
			(pin_names
				(hide yes)
			)
			(exclude_from_sim no)
			(in_bom yes)
			(on_board yes)
			(property "Reference" "C"
				(at 20.32 -5.08 0)
				(effects
					(font
						(size 1.27 1.27)
						(thickness 0.15)
					)
					(justify left bottom)
				)
			)
			(property "Value" "C_4u7_0402"
				(at 20.32 -10.16 0)
				(effects
					(font
						(size 1.27 1.27)
						(thickness 0.15)
					)
					(justify left bottom)
					(hide yes)
				)
			)
			(property "Footprint" "antmicro-footprints:C_0402_1005Metric"
				(at 20.32 -12.7 0)
				(effects
					(font
						(size 1.27 1.27)
						(thickness 0.15)
					)
					(justify left bottom)
					(hide yes)
				)
			)
			(property "Datasheet" "https://www.murata.com/products/productdetail?partno=GRM155R61A475MEAA%23"
				(at 20.32 -15.24 0)
				(effects
					(font
						(size 1.27 1.27)
						(thickness 0.15)
					)
					(justify left bottom)
					(hide yes)
				)
			)
			(property "Description" "SMD Multilayer Ceramic Capacitor, 4.7 µF, 10 V, 0402 [1005 Metric], ± 20%, X5R, GRM Series"
				(at 0 0 0)
				(effects
					(font
						(size 1.27 1.27)
					)
					(hide yes)
				)
			)
			(property "MPN" "GRM155R61A475MEAAD"
				(at 20.32 -17.78 0)
				(effects
					(font
						(size 1.27 1.27)
						(thickness 0.15)
					)
					(justify left bottom)
					(hide yes)
				)
			)
			(property "Manufacturer" "Murata"
				(at 20.32 -20.32 0)
				(effects
					(font
						(size 1.27 1.27)
						(thickness 0.15)
					)
					(justify left bottom)
					(hide yes)
				)
			)
			(property "License" "Apache-2.0"
				(at 20.32 -22.86 0)
				(effects
					(font
						(size 1.27 1.27)
						(thickness 0.15)
					)
					(justify left bottom)
					(hide yes)
				)
			)
			(property "Author" "Antmicro"
				(at 20.32 -25.4 0)
				(effects
					(font
						(size 1.27 1.27)
						(thickness 0.15)
					)
					(justify left bottom)
					(hide yes)
				)
			)
			(property "Val" "4u7"
				(at 20.32 -7.62 0)
				(effects
					(font
						(size 1.27 1.27)
						(thickness 0.15)
					)
					(justify left bottom)
				)
			)
			(property "Voltage" ""
				(at 20.32 -27.94 0)
				(effects
					(font
						(size 1.27 1.27)
					)
					(justify left bottom)
					(hide yes)
				)
			)
			(property "Dielectric" ""
				(at 20.32 -30.48 0)
				(effects
					(font
						(size 1.27 1.27)
					)
					(justify left bottom)
					(hide yes)
				)
			)
			(property "ki_keywords" "0402, SMT, CAPACITOR, PASSIVE"
				(at 0 0 0)
				(effects
					(font
						(size 1.27 1.27)
					)
					(hide yes)
				)
			)
			(symbol "C_4u7_0402_0_1"
				(polyline
					(pts
						(xy 2.032 -1.524) (xy 2.032 1.524)
					)
					(stroke
						(width 0.3048)
						(type default)
					)
					(fill
						(type none)
					)
				)
				(polyline
					(pts
						(xy 3.048 -1.524) (xy 3.048 1.524)
					)
					(stroke
						(width 0.3302)
						(type default)
					)
					(fill
						(type none)
					)
				)
			)
			(symbol "C_4u7_0402_1_1"
				(pin passive line
					(at 0 0 0)
					(length 2.032)
					(name "~"
						(effects
							(font
								(size 1.27 1.27)
							)
						)
					)
					(number "1"
						(effects
							(font
								(size 1.27 1.27)
							)
						)
					)
				)
				(pin passive line
					(at 5.08 0 180)
					(length 2.032)
					(name "~"
						(effects
							(font
								(size 1.27 1.27)
							)
						)
					)
					(number "2"
						(effects
							(font
								(size 1.27 1.27)
							)
						)
					)
				)
			)
		)
	(symbol "antmicroCapacitors0402:C_4u7_25V_0402"
			(pin_numbers
				(hide yes)
			)
			(pin_names
				(hide yes)
			)
			(exclude_from_sim no)
			(in_bom yes)
			(on_board yes)
			(property "Reference" "C"
				(at 20.32 -5.08 0)
				(effects
					(font
						(size 1.27 1.27)
						(thickness 0.15)
					)
					(justify left bottom)
				)
			)
			(property "Value" "C_4u7_25V_0402"
				(at 20.32 -10.16 0)
				(effects
					(font
						(size 1.27 1.27)
						(thickness 0.15)
					)
					(justify left bottom)
					(hide yes)
				)
			)
			(property "Footprint" "antmicro-footprints:C_0402_1005Metric"
				(at 20.32 -12.7 0)
				(effects
					(font
						(size 1.27 1.27)
						(thickness 0.15)
					)
					(justify left bottom)
					(hide yes)
				)
			)
			(property "Datasheet" "https://www.murata.com/products/productdetail?partno=GRM155C61E475ME15%23"
				(at 20.32 -15.24 0)
				(effects
					(font
						(size 1.27 1.27)
						(thickness 0.15)
					)
					(justify left bottom)
					(hide yes)
				)
			)
			(property "Description" "SMD Multilayer Ceramic Capacitor"
				(at 0 0 0)
				(effects
					(font
						(size 1.27 1.27)
					)
					(hide yes)
				)
			)
			(property "MPN" "GRM155C61E475ME15J"
				(at 20.32 -17.78 0)
				(effects
					(font
						(size 1.27 1.27)
						(thickness 0.15)
					)
					(justify left bottom)
					(hide yes)
				)
			)
			(property "Manufacturer" "Murata"
				(at 20.32 -20.32 0)
				(effects
					(font
						(size 1.27 1.27)
						(thickness 0.15)
					)
					(justify left bottom)
					(hide yes)
				)
			)
			(property "License" "Apache-2.0"
				(at 20.32 -22.86 0)
				(effects
					(font
						(size 1.27 1.27)
						(thickness 0.15)
					)
					(justify left bottom)
					(hide yes)
				)
			)
			(property "Author" "Antmicro"
				(at 20.32 -25.4 0)
				(effects
					(font
						(size 1.27 1.27)
						(thickness 0.15)
					)
					(justify left bottom)
					(hide yes)
				)
			)
			(property "Val" "4u7"
				(at 20.32 -7.62 0)
				(effects
					(font
						(size 1.27 1.27)
						(thickness 0.15)
					)
					(justify left bottom)
				)
			)
			(property "Voltage" "25V"
				(at 20.32 -27.94 0)
				(effects
					(font
						(size 1.27 1.27)
					)
					(justify left bottom)
					(hide yes)
				)
			)
			(property "Dielectric" "X5S"
				(at 20.32 -30.48 0)
				(effects
					(font
						(size 1.27 1.27)
					)
					(justify left bottom)
					(hide yes)
				)
			)
			(property "ki_keywords" "0402, SMT, CAPACITOR, PASSIVE, CERAMIC"
				(at 0 0 0)
				(effects
					(font
						(size 1.27 1.27)
					)
					(hide yes)
				)
			)
			(symbol "C_4u7_25V_0402_0_1"
				(polyline
					(pts
						(xy 2.032 -1.524) (xy 2.032 1.524)
					)
					(stroke
						(width 0.3048)
						(type default)
					)
					(fill
						(type none)
					)
				)
				(polyline
					(pts
						(xy 3.048 -1.524) (xy 3.048 1.524)
					)
					(stroke
						(width 0.3302)
						(type default)
					)
					(fill
						(type none)
					)
				)
			)
			(symbol "C_4u7_25V_0402_1_1"
				(pin passive line
					(at 0 0 0)
					(length 2.032)
					(name "~"
						(effects
							(font
								(size 1.27 1.27)
							)
						)
					)
					(number "1"
						(effects
							(font
								(size 1.27 1.27)
							)
						)
					)
				)
				(pin passive line
					(at 5.08 0 180)
					(length 2.032)
					(name "~"
						(effects
							(font
								(size 1.27 1.27)
							)
						)
					)
					(number "2"
						(effects
							(font
								(size 1.27 1.27)
							)
						)
					)
				)
			)
		)
	(symbol "antmicroCapacitors0603:C_10u_25V_0603"
			(pin_numbers
				(hide yes)
			)
			(pin_names
				(hide yes)
			)
			(exclude_from_sim no)
			(in_bom yes)
			(on_board yes)
			(property "Reference" "C"
				(at 20.32 -5.08 0)
				(effects
					(font
						(size 1.27 1.27)
						(thickness 0.15)
					)
					(justify left bottom)
				)
			)
			(property "Value" "C_10u_25V_0603"
				(at 20.32 -10.16 0)
				(effects
					(font
						(size 1.27 1.27)
						(thickness 0.15)
					)
					(justify left bottom)
					(hide yes)
				)
			)
			(property "Footprint" "antmicro-footprints:C_0603_1608Metric"
				(at 20.32 -12.7 0)
				(effects
					(font
						(size 1.27 1.27)
						(thickness 0.15)
					)
					(justify left bottom)
					(hide yes)
				)
			)
			(property "Datasheet" "https://product.tdk.com/en/search/capacitor/ceramic/mlcc/info?part_no=C1608X5R1E106M080AC"
				(at 20.32 -15.24 0)
				(effects
					(font
						(size 1.27 1.27)
						(thickness 0.15)
					)
					(justify left bottom)
					(hide yes)
				)
			)
			(property "Description" "SMD Multilayer Ceramic Capacitor, 10 µF, 25 V, 0603 [1608 Metric], ± 20%, X5R, C"
				(at 0 0 0)
				(effects
					(font
						(size 1.27 1.27)
					)
					(hide yes)
				)
			)
			(property "MPN" "C1608X5R1E106M080AC"
				(at 20.32 -17.78 0)
				(effects
					(font
						(size 1.27 1.27)
						(thickness 0.15)
					)
					(justify left bottom)
					(hide yes)
				)
			)
			(property "Manufacturer" "TDK"
				(at 20.32 -20.32 0)
				(effects
					(font
						(size 1.27 1.27)
						(thickness 0.15)
					)
					(justify left bottom)
					(hide yes)
				)
			)
			(property "License" "Apache-2.0"
				(at 20.32 -22.86 0)
				(effects
					(font
						(size 1.27 1.27)
						(thickness 0.15)
					)
					(justify left bottom)
					(hide yes)
				)
			)
			(property "Author" "Antmicro"
				(at 20.32 -25.4 0)
				(effects
					(font
						(size 1.27 1.27)
						(thickness 0.15)
					)
					(justify left bottom)
					(hide yes)
				)
			)
			(property "Val" "10u"
				(at 20.32 -7.62 0)
				(effects
					(font
						(size 1.27 1.27)
						(thickness 0.15)
					)
					(justify left bottom)
				)
			)
			(property "Voltage" "25V"
				(at 20.32 -27.94 0)
				(effects
					(font
						(size 1.27 1.27)
					)
					(justify left bottom)
					(hide yes)
				)
			)
			(property "Dielectric" ""
				(at 20.32 -30.48 0)
				(effects
					(font
						(size 1.27 1.27)
					)
					(justify left bottom)
					(hide yes)
				)
			)
			(property "ki_keywords" "0603, SMT, CAPACITOR, PASSIVE, CERAMIC, MLCC"
				(at 0 0 0)
				(effects
					(font
						(size 1.27 1.27)
					)
					(hide yes)
				)
			)
			(symbol "C_10u_25V_0603_0_1"
				(polyline
					(pts
						(xy 2.032 -1.524) (xy 2.032 1.524)
					)
					(stroke
						(width 0.3048)
						(type default)
					)
					(fill
						(type none)
					)
				)
				(polyline
					(pts
						(xy 3.048 -1.524) (xy 3.048 1.524)
					)
					(stroke
						(width 0.3302)
						(type default)
					)
					(fill
						(type none)
					)
				)
			)
			(symbol "C_10u_25V_0603_1_1"
				(pin passive line
					(at 0 0 0)
					(length 2.032)
					(name "~"
						(effects
							(font
								(size 1.27 1.27)
							)
						)
					)
					(number "1"
						(effects
							(font
								(size 1.27 1.27)
							)
						)
					)
				)
				(pin passive line
					(at 5.08 0 180)
					(length 2.032)
					(name "~"
						(effects
							(font
								(size 1.27 1.27)
							)
						)
					)
					(number "2"
						(effects
							(font
								(size 1.27 1.27)
							)
						)
					)
				)
			)
		)
	(symbol "antmicroCapacitors0603:C_1u_25V_0603"
			(pin_numbers
				(hide yes)
			)
			(pin_names
				(hide yes)
			)
			(exclude_from_sim no)
			(in_bom yes)
			(on_board yes)
			(property "Reference" "C"
				(at 20.32 -5.08 0)
				(effects
					(font
						(size 1.27 1.27)
						(thickness 0.15)
					)
					(justify left bottom)
				)
			)
			(property "Value" "C_1u_25V_0603"
				(at 20.32 -10.16 0)
				(effects
					(font
						(size 1.27 1.27)
						(thickness 0.15)
					)
					(justify left bottom)
					(hide yes)
				)
			)
			(property "Footprint" "antmicro-footprints:C_0603_1608Metric"
				(at 20.32 -12.7 0)
				(effects
					(font
						(size 1.27 1.27)
						(thickness 0.15)
					)
					(justify left bottom)
					(hide yes)
				)
			)
			(property "Datasheet" "https://product.samsungsem.com/mlcc/CL10A105KA8NNN.do"
				(at 20.32 -15.24 0)
				(effects
					(font
						(size 1.27 1.27)
						(thickness 0.15)
					)
					(justify left bottom)
					(hide yes)
				)
			)
			(property "Description" "SMD Multilayer Ceramic Capacitor, 1 µF, 25 V, 0603 [1608 Metric], ± 10%, X5R, CL"
				(at 0 0 0)
				(effects
					(font
						(size 1.27 1.27)
					)
					(hide yes)
				)
			)
			(property "MPN" "CL10A105KA8NNNC"
				(at 20.32 -17.78 0)
				(effects
					(font
						(size 1.27 1.27)
						(thickness 0.15)
					)
					(justify left bottom)
					(hide yes)
				)
			)
			(property "Manufacturer" "Samsung Electro-Mechanics"
				(at 20.32 -20.32 0)
				(effects
					(font
						(size 1.27 1.27)
						(thickness 0.15)
					)
					(justify left bottom)
					(hide yes)
				)
			)
			(property "License" "Apache-2.0"
				(at 20.32 -22.86 0)
				(effects
					(font
						(size 1.27 1.27)
						(thickness 0.15)
					)
					(justify left bottom)
					(hide yes)
				)
			)
			(property "Author" "Antmicro"
				(at 20.32 -25.4 0)
				(effects
					(font
						(size 1.27 1.27)
						(thickness 0.15)
					)
					(justify left bottom)
					(hide yes)
				)
			)
			(property "Val" "1u"
				(at 20.32 -7.62 0)
				(effects
					(font
						(size 1.27 1.27)
						(thickness 0.15)
					)
					(justify left bottom)
				)
			)
			(property "Voltage" "25V"
				(at 20.32 -27.94 0)
				(effects
					(font
						(size 1.27 1.27)
					)
					(justify left bottom)
					(hide yes)
				)
			)
			(property "Dielectric" ""
				(at 20.32 -30.48 0)
				(effects
					(font
						(size 1.27 1.27)
					)
					(justify left bottom)
					(hide yes)
				)
			)
			(property "ki_keywords" "0603, SMT, CAPACITOR, PASSIVE, CERAMIC"
				(at 0 0 0)
				(effects
					(font
						(size 1.27 1.27)
					)
					(hide yes)
				)
			)
			(symbol "C_1u_25V_0603_0_1"
				(polyline
					(pts
						(xy 2.032 -1.524) (xy 2.032 1.524)
					)
					(stroke
						(width 0.3048)
						(type default)
					)
					(fill
						(type none)
					)
				)
				(polyline
					(pts
						(xy 3.048 -1.524) (xy 3.048 1.524)
					)
					(stroke
						(width 0.3302)
						(type default)
					)
					(fill
						(type none)
					)
				)
			)
			(symbol "C_1u_25V_0603_1_1"
				(pin passive line
					(at 0 0 0)
					(length 2.032)
					(name "~"
						(effects
							(font
								(size 1.27 1.27)
							)
						)
					)
					(number "1"
						(effects
							(font
								(size 1.27 1.27)
							)
						)
					)
				)
				(pin passive line
					(at 5.08 0 180)
					(length 2.032)
					(name "~"
						(effects
							(font
								(size 1.27 1.27)
							)
						)
					)
					(number "2"
						(effects
							(font
								(size 1.27 1.27)
							)
						)
					)
				)
			)
		)
	(symbol "antmicroCapacitors0603:C_22u_0603"
			(pin_numbers
				(hide yes)
			)
			(pin_names
				(hide yes)
			)
			(exclude_from_sim no)
			(in_bom yes)
			(on_board yes)
			(property "Reference" "C"
				(at 20.32 -5.08 0)
				(effects
					(font
						(size 1.27 1.27)
						(thickness 0.15)
					)
					(justify left bottom)
				)
			)
			(property "Value" "C_22u_0603"
				(at 20.32 -10.16 0)
				(effects
					(font
						(size 1.27 1.27)
						(thickness 0.15)
					)
					(justify left bottom)
					(hide yes)
				)
			)
			(property "Footprint" "antmicro-footprints:C_0603_1608Metric"
				(at 20.32 -12.7 0)
				(effects
					(font
						(size 1.27 1.27)
						(thickness 0.15)
					)
					(justify left bottom)
					(hide yes)
				)
			)
			(property "Datasheet" "https://www.murata.com/products/productdetail?partno=GRM188R60J226MEA0%23"
				(at 20.32 -15.24 0)
				(effects
					(font
						(size 1.27 1.27)
						(thickness 0.15)
					)
					(justify left bottom)
					(hide yes)
				)
			)
			(property "Description" "SMD Multilayer Ceramic Capacitor, 22 µF, 6.3 V, 0603 [1608 Metric], ± 20%, X5R, GRM Series"
				(at 0 0 0)
				(effects
					(font
						(size 1.27 1.27)
					)
					(hide yes)
				)
			)
			(property "MPN" "GRM188R60J226MEA0D"
				(at 20.32 -17.78 0)
				(effects
					(font
						(size 1.27 1.27)
						(thickness 0.15)
					)
					(justify left bottom)
					(hide yes)
				)
			)
			(property "Manufacturer" "Murata"
				(at 20.32 -20.32 0)
				(effects
					(font
						(size 1.27 1.27)
						(thickness 0.15)
					)
					(justify left bottom)
					(hide yes)
				)
			)
			(property "License" "Apache-2.0"
				(at 20.32 -22.86 0)
				(effects
					(font
						(size 1.27 1.27)
						(thickness 0.15)
					)
					(justify left bottom)
					(hide yes)
				)
			)
			(property "Author" "Antmicro"
				(at 20.32 -25.4 0)
				(effects
					(font
						(size 1.27 1.27)
						(thickness 0.15)
					)
					(justify left bottom)
					(hide yes)
				)
			)
			(property "Val" "22u"
				(at 20.32 -7.62 0)
				(effects
					(font
						(size 1.27 1.27)
						(thickness 0.15)
					)
					(justify left bottom)
				)
			)
			(property "Voltage" ""
				(at 20.32 -27.94 0)
				(effects
					(font
						(size 1.27 1.27)
					)
					(justify left bottom)
					(hide yes)
				)
			)
			(property "Dielectric" ""
				(at 20.32 -30.48 0)
				(effects
					(font
						(size 1.27 1.27)
					)
					(justify left bottom)
					(hide yes)
				)
			)
			(property "ki_keywords" "0603, SMT, CAPACITOR, PASSIVE, CERAMIC, MLCC"
				(at 0 0 0)
				(effects
					(font
						(size 1.27 1.27)
					)
					(hide yes)
				)
			)
			(symbol "C_22u_0603_0_1"
				(polyline
					(pts
						(xy 2.032 -1.524) (xy 2.032 1.524)
					)
					(stroke
						(width 0.3048)
						(type default)
					)
					(fill
						(type none)
					)
				)
				(polyline
					(pts
						(xy 3.048 -1.524) (xy 3.048 1.524)
					)
					(stroke
						(width 0.3302)
						(type default)
					)
					(fill
						(type none)
					)
				)
			)
			(symbol "C_22u_0603_1_1"
				(pin passive line
					(at 0 0 0)
					(length 2.032)
					(name "~"
						(effects
							(font
								(size 1.27 1.27)
							)
						)
					)
					(number "1"
						(effects
							(font
								(size 1.27 1.27)
							)
						)
					)
				)
				(pin passive line
					(at 5.08 0 180)
					(length 2.032)
					(name "~"
						(effects
							(font
								(size 1.27 1.27)
							)
						)
					)
					(number "2"
						(effects
							(font
								(size 1.27 1.27)
							)
						)
					)
				)
			)
		)
	(symbol "antmicroCapacitors0603:C_47u_0603"
			(pin_numbers
				(hide yes)
			)
			(pin_names
				(hide yes)
			)
			(exclude_from_sim no)
			(in_bom yes)
			(on_board yes)
			(property "Reference" "C"
				(at 20.32 -5.08 0)
				(effects
					(font
						(size 1.27 1.27)
						(thickness 0.15)
					)
					(justify left bottom)
				)
			)
			(property "Value" "C_47u_0603"
				(at 20.32 -10.16 0)
				(effects
					(font
						(size 1.27 1.27)
						(thickness 0.15)
					)
					(justify left bottom)
					(hide yes)
				)
			)
			(property "Footprint" "antmicro-footprints:C_0603_1608Metric"
				(at 20.32 -12.7 0)
				(effects
					(font
						(size 1.27 1.27)
						(thickness 0.15)
					)
					(justify left bottom)
					(hide yes)
				)
			)
			(property "Datasheet" "https://www.murata.com/products/productdetail?partno=GRM188R60J476ME15%23"
				(at 20.32 -15.24 0)
				(effects
					(font
						(size 1.27 1.27)
						(thickness 0.15)
					)
					(justify left bottom)
					(hide yes)
				)
			)
			(property "Description" "SMD Multilayer Ceramic Capacitor, 47 µF, 6.3 V, 0603 [1608 Metric], ± 20%, X5R, GRM Series"
				(at 0 0 0)
				(effects
					(font
						(size 1.27 1.27)
					)
					(hide yes)
				)
			)
			(property "MPN" "GRM188R60J476ME15D"
				(at 20.32 -17.78 0)
				(effects
					(font
						(size 1.27 1.27)
						(thickness 0.15)
					)
					(justify left bottom)
					(hide yes)
				)
			)
			(property "Manufacturer" "Murata"
				(at 20.32 -20.32 0)
				(effects
					(font
						(size 1.27 1.27)
						(thickness 0.15)
					)
					(justify left bottom)
					(hide yes)
				)
			)
			(property "License" "Apache-2.0"
				(at 20.32 -22.86 0)
				(effects
					(font
						(size 1.27 1.27)
						(thickness 0.15)
					)
					(justify left bottom)
					(hide yes)
				)
			)
			(property "Author" "Antmicro"
				(at 20.32 -25.4 0)
				(effects
					(font
						(size 1.27 1.27)
						(thickness 0.15)
					)
					(justify left bottom)
					(hide yes)
				)
			)
			(property "Val" "47u"
				(at 20.32 -7.62 0)
				(effects
					(font
						(size 1.27 1.27)
						(thickness 0.15)
					)
					(justify left bottom)
				)
			)
			(property "Voltage" ""
				(at 20.32 -27.94 0)
				(effects
					(font
						(size 1.27 1.27)
					)
					(justify left bottom)
					(hide yes)
				)
			)
			(property "Dielectric" ""
				(at 20.32 -30.48 0)
				(effects
					(font
						(size 1.27 1.27)
					)
					(justify left bottom)
					(hide yes)
				)
			)
			(property "ki_keywords" "0603, SMT, CAPACITOR, PASSIVE, CERAMIC, MLCC"
				(at 0 0 0)
				(effects
					(font
						(size 1.27 1.27)
					)
					(hide yes)
				)
			)
			(symbol "C_47u_0603_0_1"
				(polyline
					(pts
						(xy 2.032 -1.524) (xy 2.032 1.524)
					)
					(stroke
						(width 0.3048)
						(type default)
					)
					(fill
						(type none)
					)
				)
				(polyline
					(pts
						(xy 3.048 -1.524) (xy 3.048 1.524)
					)
					(stroke
						(width 0.3302)
						(type default)
					)
					(fill
						(type none)
					)
				)
			)
			(symbol "C_47u_0603_1_1"
				(pin passive line
					(at 0 0 0)
					(length 2.032)
					(name "~"
						(effects
							(font
								(size 1.27 1.27)
							)
						)
					)
					(number "1"
						(effects
							(font
								(size 1.27 1.27)
							)
						)
					)
				)
				(pin passive line
					(at 5.08 0 180)
					(length 2.032)
					(name "~"
						(effects
							(font
								(size 1.27 1.27)
							)
						)
					)
					(number "2"
						(effects
							(font
								(size 1.27 1.27)
							)
						)
					)
				)
			)
		)
	(symbol "antmicroCapacitorsmisc:C_100n_0201"
			(pin_numbers
				(hide yes)
			)
			(pin_names
				(hide yes)
			)
			(exclude_from_sim no)
			(in_bom yes)
			(on_board yes)
			(property "Reference" "C"
				(at 20.32 -5.08 0)
				(effects
					(font
						(size 1.27 1.27)
						(thickness 0.15)
					)
					(justify left bottom)
				)
			)
			(property "Value" "C_100n_0201"
				(at 20.32 -10.16 0)
				(effects
					(font
						(size 1.27 1.27)
						(thickness 0.15)
					)
					(justify left bottom)
					(hide yes)
				)
			)
			(property "Footprint" "antmicro-footprints:C_0201"
				(at 20.32 -12.7 0)
				(effects
					(font
						(size 1.27 1.27)
						(thickness 0.15)
					)
					(justify left bottom)
					(hide yes)
				)
			)
			(property "Datasheet" "https://www.yageo.com/en/Chart/Download/pdf/CC0201KRX6S5BB104"
				(at 20.32 -15.24 0)
				(effects
					(font
						(size 1.27 1.27)
						(thickness 0.15)
					)
					(justify left bottom)
					(hide yes)
				)
			)
			(property "Description" "SMD Multilayer Ceramic Capacitor, 0.1 µF, 6.3 V, 0201 [0603 Metric], ± 10%, X6S, CC Series"
				(at 0 0 0)
				(effects
					(font
						(size 1.27 1.27)
					)
					(hide yes)
				)
			)
			(property "MPN" "CC0201KRX6S5BB104"
				(at 20.32 -17.78 0)
				(effects
					(font
						(size 1.27 1.27)
						(thickness 0.15)
					)
					(justify left bottom)
					(hide yes)
				)
			)
			(property "Manufacturer" "YAGEO"
				(at 20.32 -20.32 0)
				(effects
					(font
						(size 1.27 1.27)
						(thickness 0.15)
					)
					(justify left bottom)
					(hide yes)
				)
			)
			(property "License" "Apache-2.0"
				(at 20.32 -22.86 0)
				(effects
					(font
						(size 1.27 1.27)
						(thickness 0.15)
					)
					(justify left bottom)
					(hide yes)
				)
			)
			(property "Author" "Antmicro"
				(at 20.32 -25.4 0)
				(effects
					(font
						(size 1.27 1.27)
						(thickness 0.15)
					)
					(justify left bottom)
					(hide yes)
				)
			)
			(property "Val" "100n"
				(at 20.32 -7.62 0)
				(effects
					(font
						(size 1.27 1.27)
						(thickness 0.15)
					)
					(justify left bottom)
				)
			)
			(property "Voltage" ""
				(at 20.32 -27.94 0)
				(effects
					(font
						(size 1.27 1.27)
					)
					(justify left bottom)
					(hide yes)
				)
			)
			(property "Dielectric" ""
				(at 20.32 -30.48 0)
				(effects
					(font
						(size 1.27 1.27)
					)
					(justify left bottom)
					(hide yes)
				)
			)
			(symbol "C_100n_0201_0_1"
				(polyline
					(pts
						(xy 2.032 -1.524) (xy 2.032 1.524)
					)
					(stroke
						(width 0.3048)
						(type default)
					)
					(fill
						(type none)
					)
				)
				(polyline
					(pts
						(xy 3.048 -1.524) (xy 3.048 1.524)
					)
					(stroke
						(width 0.3302)
						(type default)
					)
					(fill
						(type none)
					)
				)
			)
			(symbol "C_100n_0201_1_1"
				(pin passive line
					(at 0 0 0)
					(length 2.032)
					(name "~"
						(effects
							(font
								(size 1.27 1.27)
							)
						)
					)
					(number "1"
						(effects
							(font
								(size 1.27 1.27)
							)
						)
					)
				)
				(pin passive line
					(at 5.08 0 180)
					(length 2.032)
					(name "~"
						(effects
							(font
								(size 1.27 1.27)
							)
						)
					)
					(number "2"
						(effects
							(font
								(size 1.27 1.27)
							)
						)
					)
				)
			)
		)
	(symbol "antmicroCapacitorsmisc:C_100u_0805"
			(pin_numbers
				(hide yes)
			)
			(pin_names
				(hide yes)
			)
			(exclude_from_sim no)
			(in_bom yes)
			(on_board yes)
			(property "Reference" "C"
				(at 20.32 -5.08 0)
				(effects
					(font
						(size 1.27 1.27)
						(thickness 0.15)
					)
					(justify left bottom)
				)
			)
			(property "Value" "C_100u_0805"
				(at 20.32 -10.16 0)
				(effects
					(font
						(size 1.27 1.27)
						(thickness 0.15)
					)
					(justify left bottom)
					(hide yes)
				)
			)
			(property "Footprint" "antmicro-footprints:C_0805_2012Metric"
				(at 20.32 -12.7 0)
				(effects
					(font
						(size 1.27 1.27)
						(thickness 0.15)
					)
					(justify left bottom)
					(hide yes)
				)
			)
			(property "Datasheet" "https://www.murata.com/products/productdetail?partno=GRM21BR60J107ME15%23"
				(at 20.32 -15.24 0)
				(effects
					(font
						(size 1.27 1.27)
						(thickness 0.15)
					)
					(justify left bottom)
					(hide yes)
				)
			)
			(property "Description" "SMD Multilayer Ceramic Capacitor, 100 µF, 6.3 V, 0805 [2012 Metric], ± 20%, X5R, GRM Series"
				(at 0 0 0)
				(effects
					(font
						(size 1.27 1.27)
					)
					(hide yes)
				)
			)
			(property "MPN" "GRM21BR60J107ME15L"
				(at 20.32 -17.78 0)
				(effects
					(font
						(size 1.27 1.27)
						(thickness 0.15)
					)
					(justify left bottom)
					(hide yes)
				)
			)
			(property "Manufacturer" "Murata"
				(at 20.32 -20.32 0)
				(effects
					(font
						(size 1.27 1.27)
						(thickness 0.15)
					)
					(justify left bottom)
					(hide yes)
				)
			)
			(property "License" "Apache-2.0"
				(at 20.32 -22.86 0)
				(effects
					(font
						(size 1.27 1.27)
						(thickness 0.15)
					)
					(justify left bottom)
					(hide yes)
				)
			)
			(property "Author" "Antmicro"
				(at 20.32 -25.4 0)
				(effects
					(font
						(size 1.27 1.27)
						(thickness 0.15)
					)
					(justify left bottom)
					(hide yes)
				)
			)
			(property "Val" "100u"
				(at 20.32 -7.62 0)
				(effects
					(font
						(size 1.27 1.27)
						(thickness 0.15)
					)
					(justify left bottom)
				)
			)
			(property "Voltage" ""
				(at 20.32 -27.94 0)
				(effects
					(font
						(size 1.27 1.27)
					)
					(justify left bottom)
					(hide yes)
				)
			)
			(property "Dielectric" ""
				(at 20.32 -30.48 0)
				(effects
					(font
						(size 1.27 1.27)
					)
					(justify left bottom)
					(hide yes)
				)
			)
			(property "Public" "False"
				(at 20.32 -33.02 0)
				(effects
					(font
						(size 1.27 1.27)
					)
					(justify left bottom)
					(hide yes)
				)
			)
			(property "ki_keywords" "0805, SMT, CAPACITOR, PASSIVE"
				(at 0 0 0)
				(effects
					(font
						(size 1.27 1.27)
					)
					(hide yes)
				)
			)
			(symbol "C_100u_0805_0_1"
				(polyline
					(pts
						(xy 2.032 -1.524) (xy 2.032 1.524)
					)
					(stroke
						(width 0.3048)
						(type default)
					)
					(fill
						(type none)
					)
				)
				(polyline
					(pts
						(xy 3.048 -1.524) (xy 3.048 1.524)
					)
					(stroke
						(width 0.3302)
						(type default)
					)
					(fill
						(type none)
					)
				)
			)
			(symbol "C_100u_0805_1_1"
				(pin passive line
					(at 0 0 0)
					(length 2.032)
					(name "~"
						(effects
							(font
								(size 1.27 1.27)
							)
						)
					)
					(number "1"
						(effects
							(font
								(size 1.27 1.27)
							)
						)
					)
				)
				(pin passive line
					(at 5.08 0 180)
					(length 2.032)
					(name "~"
						(effects
							(font
								(size 1.27 1.27)
							)
						)
					)
					(number "2"
						(effects
							(font
								(size 1.27 1.27)
							)
						)
					)
				)
			)
		)
	(symbol "antmicroCapacitorsmisc:C_22u_25V_0805"
			(pin_numbers
				(hide yes)
			)
			(pin_names
				(hide yes)
			)
			(exclude_from_sim no)
			(in_bom yes)
			(on_board yes)
			(property "Reference" "C"
				(at 20.32 -5.08 0)
				(effects
					(font
						(size 1.27 1.27)
						(thickness 0.15)
					)
					(justify left bottom)
				)
			)
			(property "Value" "C_22u_25V_0805"
				(at 20.32 -10.16 0)
				(effects
					(font
						(size 1.27 1.27)
						(thickness 0.15)
					)
					(justify left bottom)
					(hide yes)
				)
			)
			(property "Footprint" "antmicro-footprints:C_0805_2012Metric"
				(at 20.32 -12.7 0)
				(effects
					(font
						(size 1.27 1.27)
						(thickness 0.15)
					)
					(justify left bottom)
					(hide yes)
				)
			)
			(property "Datasheet" "https://product.samsungsem.com/mlcc/CL21A226MAYNNN.do"
				(at 20.32 -15.24 0)
				(effects
					(font
						(size 1.27 1.27)
						(thickness 0.15)
					)
					(justify left bottom)
					(hide yes)
				)
			)
			(property "Description" "SMT Multilayer Ceramic Capacitor, 22uF, +/-20%, 25V, X5R, 0805 [2012 Metric]"
				(at 0 0 0)
				(effects
					(font
						(size 1.27 1.27)
					)
					(hide yes)
				)
			)
			(property "MPN" "CL21A226MAYNNNE"
				(at 20.32 -17.78 0)
				(effects
					(font
						(size 1.27 1.27)
						(thickness 0.15)
					)
					(justify left bottom)
					(hide yes)
				)
			)
			(property "Manufacturer" "Samsung Electro-Mechanics"
				(at 20.32 -20.32 0)
				(effects
					(font
						(size 1.27 1.27)
						(thickness 0.15)
					)
					(justify left bottom)
					(hide yes)
				)
			)
			(property "License" "Apache-2.0"
				(at 20.32 -22.86 0)
				(effects
					(font
						(size 1.27 1.27)
						(thickness 0.15)
					)
					(justify left bottom)
					(hide yes)
				)
			)
			(property "Author" "Antmicro"
				(at 20.32 -25.4 0)
				(effects
					(font
						(size 1.27 1.27)
						(thickness 0.15)
					)
					(justify left bottom)
					(hide yes)
				)
			)
			(property "Val" "22u"
				(at 20.32 -7.62 0)
				(effects
					(font
						(size 1.27 1.27)
						(thickness 0.15)
					)
					(justify left bottom)
				)
			)
			(property "Voltage" "25V"
				(at 20.32 -27.94 0)
				(effects
					(font
						(size 1.27 1.27)
					)
					(justify left bottom)
				)
			)
			(property "Dielectric" "X5R"
				(at 20.32 -30.48 0)
				(effects
					(font
						(size 1.27 1.27)
					)
					(justify left bottom)
					(hide yes)
				)
			)
			(property "Public" "False"
				(at 20.32 -33.02 0)
				(effects
					(font
						(size 1.27 1.27)
					)
					(justify left bottom)
					(hide yes)
				)
			)
			(property "ki_keywords" "0805, SMT, CAPACITOR, PASSIVE"
				(at 0 0 0)
				(effects
					(font
						(size 1.27 1.27)
					)
					(hide yes)
				)
			)
			(symbol "C_22u_25V_0805_0_1"
				(polyline
					(pts
						(xy 2.032 -1.524) (xy 2.032 1.524)
					)
					(stroke
						(width 0.3048)
						(type default)
					)
					(fill
						(type none)
					)
				)
				(polyline
					(pts
						(xy 3.048 -1.524) (xy 3.048 1.524)
					)
					(stroke
						(width 0.3302)
						(type default)
					)
					(fill
						(type none)
					)
				)
			)
			(symbol "C_22u_25V_0805_1_1"
				(pin passive line
					(at 0 0 0)
					(length 2.032)
					(name "~"
						(effects
							(font
								(size 1.27 1.27)
							)
						)
					)
					(number "1"
						(effects
							(font
								(size 1.27 1.27)
							)
						)
					)
				)
				(pin passive line
					(at 5.08 0 180)
					(length 2.032)
					(name "~"
						(effects
							(font
								(size 1.27 1.27)
							)
						)
					)
					(number "2"
						(effects
							(font
								(size 1.27 1.27)
							)
						)
					)
				)
			)
		)
	(symbol "antmicroCapacitorspol:C_Pol_1m_2.5V_KEMET-T520-D"
			(pin_numbers
				(hide yes)
			)
			(pin_names
				(hide yes)
			)
			(exclude_from_sim no)
			(in_bom yes)
			(on_board yes)
			(property "Reference" "C"
				(at 13.97 0 0)
				(effects
					(font
						(size 1.27 1.27)
						(thickness 0.15)
					)
					(justify left bottom)
				)
			)
			(property "Value" "C_Pol_1m_2.5V_KEMET-T520-D"
				(at 13.97 -2.54 0)
				(effects
					(font
						(size 1.27 1.27)
						(thickness 0.15)
					)
					(justify left bottom)
					(hide yes)
				)
			)
			(property "Footprint" "antmicro-footprints:C_Pol_EIA-D"
				(at 13.97 -7.62 0)
				(effects
					(font
						(size 1.27 1.27)
						(thickness 0.15)
					)
					(justify left bottom)
					(hide yes)
				)
			)
			(property "Datasheet" "https://www.kemet.com/en/us/capacitors/product/T520D108M2R5ATE030.html"
				(at 13.97 -10.16 0)
				(effects
					(font
						(size 1.27 1.27)
						(thickness 0.15)
					)
					(justify left bottom)
					(hide yes)
				)
			)
			(property "Description" "Tantalum Polymer Capacitor, 1000 µF, ± 20%, 2.5 V, D, 0.03 ohm, 2917 [7343 Metric]"
				(at 0 0 0)
				(effects
					(font
						(size 1.27 1.27)
					)
					(hide yes)
				)
			)
			(property "MPN" "T520D108M2R5ATE030"
				(at 13.97 -12.7 0)
				(effects
					(font
						(size 1.27 1.27)
						(thickness 0.15)
					)
					(justify left bottom)
					(hide yes)
				)
			)
			(property "Manufacturer" "KEMET"
				(at 13.97 -15.24 0)
				(effects
					(font
						(size 1.27 1.27)
						(thickness 0.15)
					)
					(justify left bottom)
					(hide yes)
				)
			)
			(property "License" "Apache-2.0"
				(at 13.97 -17.78 0)
				(effects
					(font
						(size 1.27 1.27)
						(thickness 0.15)
					)
					(justify left bottom)
					(hide yes)
				)
			)
			(property "Author" "Antmicro"
				(at 13.97 -20.32 0)
				(effects
					(font
						(size 1.27 1.27)
						(thickness 0.15)
					)
					(justify left bottom)
					(hide yes)
				)
			)
			(property "Val" "1000u"
				(at 13.97 -5.08 0)
				(effects
					(font
						(size 1.27 1.27)
						(thickness 0.15)
					)
					(justify left bottom)
				)
			)
			(property "Voltage" "2.5V"
				(at 13.97 -22.86 0)
				(effects
					(font
						(size 1.27 1.27)
					)
					(justify left bottom)
					(hide yes)
				)
			)
			(property "Dielectric" "template_dielectric"
				(at 13.97 -25.4 0)
				(effects
					(font
						(size 1.27 1.27)
					)
					(justify left bottom)
					(hide yes)
				)
			)
			(property "ki_keywords" "SMT, CAPACITOR, PASSIVE, POLARIZED"
				(at 0 0 0)
				(effects
					(font
						(size 1.27 1.27)
					)
					(hide yes)
				)
			)
			(symbol "C_Pol_1m_2.5V_KEMET-T520-D_0_1"
				(polyline
					(pts
						(xy 0.9652 1.27) (xy 0.9652 1.778)
					)
					(stroke
						(width 0)
						(type default)
					)
					(fill
						(type none)
					)
				)
				(polyline
					(pts
						(xy 1.2192 1.524) (xy 0.7112 1.524)
					)
					(stroke
						(width 0)
						(type default)
					)
					(fill
						(type none)
					)
				)
				(rectangle
					(start 1.905 -1.524)
					(end 2.286 1.524)
					(stroke
						(width 0)
						(type default)
					)
					(fill
						(type none)
					)
				)
				(rectangle
					(start 2.921 -1.524)
					(end 3.302 1.524)
					(stroke
						(width 0)
						(type default)
					)
					(fill
						(type outline)
					)
				)
			)
			(symbol "C_Pol_1m_2.5V_KEMET-T520-D_1_1"
				(pin passive line
					(at 0 0 0)
					(length 1.8542)
					(name "~"
						(effects
							(font
								(size 1.27 1.27)
							)
						)
					)
					(number "1"
						(effects
							(font
								(size 1.27 1.27)
							)
						)
					)
				)
				(pin passive line
					(at 5.08 0 180)
					(length 1.8542)
					(name "~"
						(effects
							(font
								(size 1.27 1.27)
							)
						)
					)
					(number "2"
						(effects
							(font
								(size 1.27 1.27)
							)
						)
					)
				)
			)
		)
	(symbol "antmicroCapacitorspol:C_Pol_330u_6.3V_KEMET-T520-B"
			(pin_numbers
				(hide yes)
			)
			(pin_names
				(hide yes)
			)
			(exclude_from_sim no)
			(in_bom yes)
			(on_board yes)
			(property "Reference" "C"
				(at 13.97 0 0)
				(effects
					(font
						(size 1.27 1.27)
						(thickness 0.15)
					)
					(justify left bottom)
				)
			)
			(property "Value" "C_Pol_330u_6.3V_KEMET-T520-B"
				(at 13.97 -2.54 0)
				(effects
					(font
						(size 1.27 1.27)
						(thickness 0.15)
					)
					(justify left bottom)
					(hide yes)
				)
			)
			(property "Footprint" "antmicro-footprints:C_Pol_EIA-B"
				(at 13.97 -7.62 0)
				(effects
					(font
						(size 1.27 1.27)
						(thickness 0.15)
					)
					(justify left bottom)
					(hide yes)
				)
			)
			(property "Datasheet" "https://www.kemet.com/en/us/capacitors/product/T520B337M006ATE040.html"
				(at 13.97 -10.16 0)
				(effects
					(font
						(size 1.27 1.27)
						(thickness 0.15)
					)
					(justify left bottom)
					(hide yes)
				)
			)
			(property "Description" "Tantalum Polymer Capacitor, KO-CAP®, 330 µF, ± 20%, 6.3 V, B, 0.04 ohm, 1411 [3528 Metric]"
				(at 0 0 0)
				(effects
					(font
						(size 1.27 1.27)
					)
					(hide yes)
				)
			)
			(property "Val" "330u"
				(at 13.97 -5.08 0)
				(effects
					(font
						(size 1.27 1.27)
						(thickness 0.15)
					)
					(justify left bottom)
				)
			)
			(property "MPN" "T520B337M006ATE040"
				(at 13.97 -12.7 0)
				(effects
					(font
						(size 1.27 1.27)
						(thickness 0.15)
					)
					(justify left bottom)
					(hide yes)
				)
			)
			(property "Manufacturer" "KEMET"
				(at 13.97 -15.24 0)
				(effects
					(font
						(size 1.27 1.27)
						(thickness 0.15)
					)
					(justify left bottom)
					(hide yes)
				)
			)
			(property "License" "Apache-2.0"
				(at 13.97 -17.78 0)
				(effects
					(font
						(size 1.27 1.27)
						(thickness 0.15)
					)
					(justify left bottom)
					(hide yes)
				)
			)
			(property "Author" "Antmicro"
				(at 13.97 -20.32 0)
				(effects
					(font
						(size 1.27 1.27)
						(thickness 0.15)
					)
					(justify left bottom)
					(hide yes)
				)
			)
			(property "Voltage" "6.3V"
				(at 13.97 -22.86 0)
				(effects
					(font
						(size 1.27 1.27)
					)
					(justify left bottom)
					(hide yes)
				)
			)
			(property "Dielectric" "template_dielectric"
				(at 13.97 -25.4 0)
				(effects
					(font
						(size 1.27 1.27)
					)
					(justify left bottom)
					(hide yes)
				)
			)
			(property "ki_keywords" "SMT, CAPACITOR, PASSIVE, POLARIZED, TANTALUM"
				(at 0 0 0)
				(effects
					(font
						(size 1.27 1.27)
					)
					(hide yes)
				)
			)
			(symbol "C_Pol_330u_6.3V_KEMET-T520-B_0_1"
				(polyline
					(pts
						(xy 0.9652 1.27) (xy 0.9652 1.778)
					)
					(stroke
						(width 0)
						(type default)
					)
					(fill
						(type none)
					)
				)
				(polyline
					(pts
						(xy 1.2192 1.524) (xy 0.7112 1.524)
					)
					(stroke
						(width 0)
						(type default)
					)
					(fill
						(type none)
					)
				)
				(rectangle
					(start 1.905 -1.524)
					(end 2.286 1.524)
					(stroke
						(width 0)
						(type default)
					)
					(fill
						(type none)
					)
				)
				(rectangle
					(start 2.921 -1.524)
					(end 3.302 1.524)
					(stroke
						(width 0)
						(type default)
					)
					(fill
						(type outline)
					)
				)
			)
			(symbol "C_Pol_330u_6.3V_KEMET-T520-B_1_1"
				(pin passive line
					(at 0 0 0)
					(length 1.8542)
					(name "~"
						(effects
							(font
								(size 1.27 1.27)
							)
						)
					)
					(number "1"
						(effects
							(font
								(size 1.27 1.27)
							)
						)
					)
				)
				(pin passive line
					(at 5.08 0 180)
					(length 1.8542)
					(name "~"
						(effects
							(font
								(size 1.27 1.27)
							)
						)
					)
					(number "2"
						(effects
							(font
								(size 1.27 1.27)
							)
						)
					)
				)
			)
		)
	(symbol "antmicroClockTimingClockGeneratorsPLLsFrequencySynthesizers:SI5319C-C-GM-ND"
			(exclude_from_sim no)
			(in_bom yes)
			(on_board yes)
			(property "Reference" "U"
				(at 35.56 -2.54 0)
				(effects
					(font
						(size 1.27 1.27)
						(thickness 0.15)
					)
					(justify left bottom)
				)
			)
			(property "Value" "SI5319C-C-GM-ND"
				(at 35.56 -7.62 0)
				(effects
					(font
						(size 1.27 1.27)
						(thickness 0.15)
					)
					(justify left bottom)
					(hide yes)
				)
			)
			(property "Footprint" "antmicro-footprints:QFN-36-1EP_6x6mm_P0.5mm_EP3.7x3.7mm"
				(at 35.56 -10.16 0)
				(effects
					(font
						(size 1.27 1.27)
						(thickness 0.15)
					)
					(justify left bottom)
					(hide yes)
				)
			)
			(property "Datasheet" "https://www.skyworksinc.com/-/media/Skyworks/SL/documents/public/data-sheets/Si5319.pdf"
				(at 35.56 -12.7 0)
				(effects
					(font
						(size 1.27 1.27)
						(thickness 0.15)
					)
					(justify left bottom)
					(hide yes)
				)
			)
			(property "Description" "Clock Generator 0.002MHz to 710MHz-IN 346MHz-OUT 36-Pin QFN EP"
				(at 0 0 0)
				(effects
					(font
						(size 1.27 1.27)
					)
					(hide yes)
				)
			)
			(property "MPN" "SI5319C-C-GM-ND"
				(at 35.56 -5.08 0)
				(effects
					(font
						(size 1.27 1.27)
						(thickness 0.15)
					)
					(justify left bottom)
				)
			)
			(property "Manufacturer" "Skyworks Solutions"
				(at 35.56 -15.24 0)
				(effects
					(font
						(size 1.27 1.27)
						(thickness 0.15)
					)
					(justify left bottom)
					(hide yes)
				)
			)
			(property "Author" "Antmicro"
				(at 35.56 -17.78 0)
				(effects
					(font
						(size 1.27 1.27)
						(thickness 0.15)
					)
					(justify left bottom)
					(hide yes)
				)
			)
			(property "License" "Apache-2.0"
				(at 35.56 -20.32 0)
				(effects
					(font
						(size 1.27 1.27)
						(thickness 0.15)
					)
					(justify left bottom)
					(hide yes)
				)
			)
			(property "ki_keywords" "IC, CLOCK"
				(at 0 0 0)
				(effects
					(font
						(size 1.27 1.27)
					)
					(hide yes)
				)
			)
			(symbol "SI5319C-C-GM-ND_1_1"
				(rectangle
					(start 2.54 2.54)
					(end 20.32 -55.88)
					(stroke
						(width 0.254)
						(type default)
					)
					(fill
						(type background)
					)
				)
				(pin passive line
					(at 0 0 0)
					(length 2.54)
					(hide yes)
					(name "VDD"
						(effects
							(font
								(size 1.27 1.27)
							)
						)
					)
					(number "10"
						(effects
							(font
								(size 1.27 1.27)
							)
						)
					)
				)
				(pin passive line
					(at 0 0 0)
					(length 2.54)
					(hide yes)
					(name "VDD"
						(effects
							(font
								(size 1.27 1.27)
							)
						)
					)
					(number "32"
						(effects
							(font
								(size 1.27 1.27)
							)
						)
					)
				)
				(pin power_in line
					(at 0 0 0)
					(length 2.54)
					(name "VDD"
						(effects
							(font
								(size 1.27 1.27)
							)
						)
					)
					(number "5"
						(effects
							(font
								(size 1.27 1.27)
							)
						)
					)
				)
				(pin input line
					(at 0 -2.54 0)
					(length 2.54)
					(name "~{RST}"
						(effects
							(font
								(size 1.27 1.27)
							)
						)
					)
					(number "1"
						(effects
							(font
								(size 1.27 1.27)
							)
						)
					)
				)
				(pin input line
					(at 0 -7.62 0)
					(length 2.54)
					(name "XA"
						(effects
							(font
								(size 1.27 1.27)
							)
						)
					)
					(number "6"
						(effects
							(font
								(size 1.27 1.27)
							)
						)
					)
				)
				(pin input line
					(at 0 -10.16 0)
					(length 2.54)
					(name "XB"
						(effects
							(font
								(size 1.27 1.27)
							)
						)
					)
					(number "7"
						(effects
							(font
								(size 1.27 1.27)
							)
						)
					)
				)
				(pin input line
					(at 0 -15.24 0)
					(length 2.54)
					(name "CMODE"
						(effects
							(font
								(size 1.27 1.27)
							)
						)
					)
					(number "36"
						(effects
							(font
								(size 1.27 1.27)
							)
						)
					)
				)
				(pin input line
					(at 0 -17.78 0)
					(length 2.54)
					(name "CKIN+"
						(effects
							(font
								(size 1.27 1.27)
							)
						)
					)
					(number "16"
						(effects
							(font
								(size 1.27 1.27)
							)
						)
					)
				)
				(pin input line
					(at 0 -20.32 0)
					(length 2.54)
					(name "CKIN-"
						(effects
							(font
								(size 1.27 1.27)
							)
						)
					)
					(number "17"
						(effects
							(font
								(size 1.27 1.27)
							)
						)
					)
				)
				(pin input line
					(at 0 -25.4 0)
					(length 2.54)
					(name "RATE0"
						(effects
							(font
								(size 1.27 1.27)
							)
						)
					)
					(number "11"
						(effects
							(font
								(size 1.27 1.27)
							)
						)
					)
				)
				(pin input line
					(at 0 -27.94 0)
					(length 2.54)
					(name "RATE1"
						(effects
							(font
								(size 1.27 1.27)
							)
						)
					)
					(number "15"
						(effects
							(font
								(size 1.27 1.27)
							)
						)
					)
				)
				(pin input line
					(at 0 -33.02 0)
					(length 2.54)
					(name "SDI"
						(effects
							(font
								(size 1.27 1.27)
							)
						)
					)
					(number "27"
						(effects
							(font
								(size 1.27 1.27)
							)
						)
					)
				)
				(pin input line
					(at 0 -35.56 0)
					(length 2.54)
					(name "SDA_SDO"
						(effects
							(font
								(size 1.27 1.27)
							)
						)
					)
					(number "23"
						(effects
							(font
								(size 1.27 1.27)
							)
						)
					)
				)
				(pin input line
					(at 0 -38.1 0)
					(length 2.54)
					(name "SCL"
						(effects
							(font
								(size 1.27 1.27)
							)
						)
					)
					(number "22"
						(effects
							(font
								(size 1.27 1.27)
							)
						)
					)
				)
				(pin input line
					(at 0 -43.18 0)
					(length 2.54)
					(name "A2_~{SS}"
						(effects
							(font
								(size 1.27 1.27)
							)
						)
					)
					(number "26"
						(effects
							(font
								(size 1.27 1.27)
							)
						)
					)
				)
				(pin input line
					(at 0 -45.72 0)
					(length 2.54)
					(name "A1"
						(effects
							(font
								(size 1.27 1.27)
							)
						)
					)
					(number "25"
						(effects
							(font
								(size 1.27 1.27)
							)
						)
					)
				)
				(pin input line
					(at 0 -48.26 0)
					(length 2.54)
					(name "A0"
						(effects
							(font
								(size 1.27 1.27)
							)
						)
					)
					(number "24"
						(effects
							(font
								(size 1.27 1.27)
							)
						)
					)
				)
				(pin input line
					(at 0 -50.8 0)
					(length 2.54)
					(name "CS"
						(effects
							(font
								(size 1.27 1.27)
							)
						)
					)
					(number "21"
						(effects
							(font
								(size 1.27 1.27)
							)
						)
					)
				)
				(pin passive line
					(at 0 -53.34 0)
					(length 2.54)
					(hide yes)
					(name "GND"
						(effects
							(font
								(size 1.27 1.27)
							)
						)
					)
					(number "19"
						(effects
							(font
								(size 1.27 1.27)
							)
						)
					)
				)
				(pin passive line
					(at 0 -53.34 0)
					(length 2.54)
					(hide yes)
					(name "GND"
						(effects
							(font
								(size 1.27 1.27)
							)
						)
					)
					(number "20"
						(effects
							(font
								(size 1.27 1.27)
							)
						)
					)
				)
				(pin passive line
					(at 0 -53.34 0)
					(length 2.54)
					(hide yes)
					(name "GND"
						(effects
							(font
								(size 1.27 1.27)
							)
						)
					)
					(number "31"
						(effects
							(font
								(size 1.27 1.27)
							)
						)
					)
				)
				(pin passive line
					(at 0 -53.34 0)
					(length 2.54)
					(hide yes)
					(name "GND"
						(effects
							(font
								(size 1.27 1.27)
							)
						)
					)
					(number "37"
						(effects
							(font
								(size 1.27 1.27)
							)
						)
					)
				)
				(pin power_in line
					(at 0 -53.34 0)
					(length 2.54)
					(name "GND"
						(effects
							(font
								(size 1.27 1.27)
							)
						)
					)
					(number "8"
						(effects
							(font
								(size 1.27 1.27)
							)
						)
					)
				)
				(pin no_connect line
					(at 20.32 -22.86 180)
					(length 2.54)
					(hide yes)
					(name "NC"
						(effects
							(font
								(size 1.27 1.27)
							)
						)
					)
					(number "2"
						(effects
							(font
								(size 1.27 1.27)
							)
						)
					)
				)
				(pin no_connect line
					(at 20.32 -25.4 180)
					(length 2.54)
					(hide yes)
					(name "NC"
						(effects
							(font
								(size 1.27 1.27)
							)
						)
					)
					(number "4"
						(effects
							(font
								(size 1.27 1.27)
							)
						)
					)
				)
				(pin no_connect line
					(at 20.32 -27.94 180)
					(length 2.54)
					(hide yes)
					(name "NC"
						(effects
							(font
								(size 1.27 1.27)
							)
						)
					)
					(number "9"
						(effects
							(font
								(size 1.27 1.27)
							)
						)
					)
				)
				(pin no_connect line
					(at 20.32 -30.48 180)
					(length 2.54)
					(hide yes)
					(name "NC"
						(effects
							(font
								(size 1.27 1.27)
							)
						)
					)
					(number "12"
						(effects
							(font
								(size 1.27 1.27)
							)
						)
					)
				)
				(pin no_connect line
					(at 20.32 -33.02 180)
					(length 2.54)
					(hide yes)
					(name "NC"
						(effects
							(font
								(size 1.27 1.27)
							)
						)
					)
					(number "13"
						(effects
							(font
								(size 1.27 1.27)
							)
						)
					)
				)
				(pin no_connect line
					(at 20.32 -35.56 180)
					(length 2.54)
					(hide yes)
					(name "NC"
						(effects
							(font
								(size 1.27 1.27)
							)
						)
					)
					(number "14"
						(effects
							(font
								(size 1.27 1.27)
							)
						)
					)
				)
				(pin no_connect line
					(at 20.32 -38.1 180)
					(length 2.54)
					(hide yes)
					(name "NC"
						(effects
							(font
								(size 1.27 1.27)
							)
						)
					)
					(number "30"
						(effects
							(font
								(size 1.27 1.27)
							)
						)
					)
				)
				(pin no_connect line
					(at 20.32 -40.64 180)
					(length 2.54)
					(hide yes)
					(name "NC"
						(effects
							(font
								(size 1.27 1.27)
							)
						)
					)
					(number "33"
						(effects
							(font
								(size 1.27 1.27)
							)
						)
					)
				)
				(pin no_connect line
					(at 20.32 -43.18 180)
					(length 2.54)
					(hide yes)
					(name "NC"
						(effects
							(font
								(size 1.27 1.27)
							)
						)
					)
					(number "34"
						(effects
							(font
								(size 1.27 1.27)
							)
						)
					)
				)
				(pin no_connect line
					(at 20.32 -45.72 180)
					(length 2.54)
					(hide yes)
					(name "NC"
						(effects
							(font
								(size 1.27 1.27)
							)
						)
					)
					(number "35"
						(effects
							(font
								(size 1.27 1.27)
							)
						)
					)
				)
				(pin output line
					(at 22.86 -17.78 180)
					(length 2.54)
					(name "CKOUT+"
						(effects
							(font
								(size 1.27 1.27)
							)
						)
					)
					(number "28"
						(effects
							(font
								(size 1.27 1.27)
							)
						)
					)
				)
				(pin output line
					(at 22.86 -20.32 180)
					(length 2.54)
					(name "CKOUT-"
						(effects
							(font
								(size 1.27 1.27)
							)
						)
					)
					(number "29"
						(effects
							(font
								(size 1.27 1.27)
							)
						)
					)
				)
				(pin output line
					(at 22.86 -50.8 180)
					(length 2.54)
					(name "INT_CB"
						(effects
							(font
								(size 1.27 1.27)
							)
						)
					)
					(number "3"
						(effects
							(font
								(size 1.27 1.27)
							)
						)
					)
				)
				(pin output line
					(at 22.86 -53.34 180)
					(length 2.54)
					(name "LOL"
						(effects
							(font
								(size 1.27 1.27)
							)
						)
					)
					(number "18"
						(effects
							(font
								(size 1.27 1.27)
							)
						)
					)
				)
			)
		)
	(symbol "antmicroCoaxialConnectorsRF:U_FL-R-SMT-1"
			(exclude_from_sim no)
			(in_bom yes)
			(on_board yes)
			(property "Reference" "J"
				(at 20.32 -2.54 0)
				(effects
					(font
						(size 1.27 1.27)
						(thickness 0.15)
					)
					(justify left bottom)
				)
			)
			(property "Value" "U_FL-R-SMT-1"
				(at 20.32 -7.62 0)
				(effects
					(font
						(size 1.27 1.27)
						(thickness 0.15)
					)
					(justify left bottom)
					(hide yes)
				)
			)
			(property "Footprint" "antmicro-footprints:Coax_Conn_U.FL"
				(at 20.32 -10.16 0)
				(effects
					(font
						(size 1.27 1.27)
						(thickness 0.15)
					)
					(justify left bottom)
					(hide yes)
				)
			)
			(property "Datasheet" "https://media.digikey.com/pdf/Data%20Sheets/Hirose%20PDFs/UFL%20Series.pdf"
				(at 20.32 -12.7 0)
				(effects
					(font
						(size 1.27 1.27)
						(thickness 0.15)
					)
					(justify left bottom)
					(hide yes)
				)
			)
			(property "Description" "U.FL (UMCC) Connector Receptacle, Male Pin 50Ohm Surface Mount Solder"
				(at 0 0 0)
				(effects
					(font
						(size 1.27 1.27)
					)
					(hide yes)
				)
			)
			(property "MPN" "U.FL-R-SMT-1(10)"
				(at 20.32 -5.08 0)
				(effects
					(font
						(size 1.27 1.27)
						(thickness 0.15)
					)
					(justify left bottom)
				)
			)
			(property "Manufacturer" "Hirose Electric"
				(at 20.32 -15.24 0)
				(effects
					(font
						(size 1.27 1.27)
						(thickness 0.15)
					)
					(justify left bottom)
					(hide yes)
				)
			)
			(property "Author" "Antmicro"
				(at 20.32 -17.78 0)
				(effects
					(font
						(size 1.27 1.27)
						(thickness 0.15)
					)
					(justify left bottom)
					(hide yes)
				)
			)
			(property "License" "Apache-2.0"
				(at 20.32 -20.32 0)
				(effects
					(font
						(size 1.27 1.27)
						(thickness 0.15)
					)
					(justify left bottom)
					(hide yes)
				)
			)
			(property "ki_keywords" "UFL, COAXIAL, CONNECTOR"
				(at 0 0 0)
				(effects
					(font
						(size 1.27 1.27)
					)
					(hide yes)
				)
			)
			(symbol "U_FL-R-SMT-1_0_0"
				(pin passive line
					(at 0 0 0)
					(length 3.81)
					(name "~"
						(effects
							(font
								(size 1.27 1.27)
							)
						)
					)
					(number "1"
						(effects
							(font
								(size 1.27 1.27)
							)
						)
					)
				)
				(pin passive line
					(at 6.35 -6.35 90)
					(length 3.81)
					(name "~"
						(effects
							(font
								(size 1.27 1.27)
							)
						)
					)
					(number "SH1"
						(effects
							(font
								(size 1.27 1.27)
							)
						)
					)
				)
				(pin passive line
					(at 6.35 -6.35 90)
					(length 3.81)
					(hide yes)
					(name "~"
						(effects
							(font
								(size 1.27 1.27)
							)
						)
					)
					(number "SH2"
						(effects
							(font
								(size 1.27 1.27)
							)
						)
					)
				)
			)
			(symbol "U_FL-R-SMT-1_1_1"
				(polyline
					(pts
						(xy 3.81 0) (xy 5.842 0)
					)
					(stroke
						(width 0.254)
						(type default)
					)
					(fill
						(type background)
					)
				)
				(arc
					(start 4.6063 0.5218)
					(mid 6.6063 1.8221)
					(end 8.1623 0.0138)
					(stroke
						(width 0.254)
						(type default)
					)
					(fill
						(type none)
					)
				)
				(circle
					(center 6.35 0)
					(radius 0.508)
					(stroke
						(width 0.254)
						(type default)
					)
					(fill
						(type outline)
					)
				)
				(arc
					(start 8.1623 0.0138)
					(mid 6.6063 -1.7941)
					(end 4.6063 -0.4942)
					(stroke
						(width 0.254)
						(type default)
					)
					(fill
						(type none)
					)
				)
				(polyline
					(pts
						(xy 6.35 -2.54) (xy 6.35 -1.905)
					)
					(stroke
						(width 0.254)
						(type default)
					)
					(fill
						(type background)
					)
				)
			)
		)
	(symbol "antmicroDCDCConverters:MP8796B"
			(exclude_from_sim no)
			(in_bom yes)
			(on_board yes)
			(property "Reference" "U"
				(at 38.1 -2.54 0)
				(effects
					(font
						(size 1.27 1.27)
						(thickness 0.15)
					)
					(justify left bottom)
				)
			)
			(property "Value" "MP8796B"
				(at 38.1 -10.16 0)
				(effects
					(font
						(size 1.27 1.27)
						(thickness 0.15)
					)
					(justify left bottom)
					(hide yes)
				)
			)
			(property "Footprint" "antmicro-footprints:TQFN-25_4x5mm"
				(at 38.1 -12.7 0)
				(effects
					(font
						(size 1.27 1.27)
						(thickness 0.15)
					)
					(justify left bottom)
					(hide yes)
				)
			)
			(property "Datasheet" "https://www.monolithicpower.com/en/documentview/productdocument/index/version/2/document_type/Datasheet/lang/en/sku/MP8796B/"
				(at 38.1 -15.24 0)
				(effects
					(font
						(size 1.27 1.27)
						(thickness 0.15)
					)
					(justify left bottom)
					(hide yes)
				)
			)
			(property "Description" "16V, 30A, Scalable, Digital, Synchronous Step-Down Converter with PMBus"
				(at 0 0 0)
				(effects
					(font
						(size 1.27 1.27)
					)
					(hide yes)
				)
			)
			(property "MPN" "MP8796BGVT-0000-Z"
				(at 38.1 -5.08 0)
				(effects
					(font
						(size 1.27 1.27)
						(thickness 0.15)
					)
					(justify left bottom)
				)
			)
			(property "Manufacturer" "Monolithic Power Systems"
				(at 38.1 -7.62 0)
				(effects
					(font
						(size 1.27 1.27)
						(thickness 0.15)
					)
					(justify left bottom)
					(hide yes)
				)
			)
			(property "Author" "Antmicro"
				(at 38.1 -17.78 0)
				(effects
					(font
						(size 1.27 1.27)
						(thickness 0.15)
					)
					(justify left bottom)
					(hide yes)
				)
			)
			(property "License" "Apache-2.0"
				(at 38.1 -20.32 0)
				(effects
					(font
						(size 1.27 1.27)
						(thickness 0.15)
					)
					(justify left bottom)
					(hide yes)
				)
			)
			(property "ki_keywords" "SMT, PMIC, IC, VOLTAGE, DC-DC"
				(at 0 0 0)
				(effects
					(font
						(size 1.27 1.27)
					)
					(hide yes)
				)
			)
			(symbol "MP8796B_1_1"
				(rectangle
					(start 2.54 2.54)
					(end 22.86 -38.1)
					(stroke
						(width 0.254)
						(type default)
					)
					(fill
						(type background)
					)
				)
				(pin power_in line
					(at 0 0 0)
					(length 2.54)
					(name "IN"
						(effects
							(font
								(size 1.27 1.27)
							)
						)
					)
					(number "1"
						(effects
							(font
								(size 1.27 1.27)
							)
						)
					)
				)
				(pin passive line
					(at 0 0 0)
					(length 2.54)
					(hide yes)
					(name "IN"
						(effects
							(font
								(size 1.27 1.27)
							)
						)
					)
					(number "16"
						(effects
							(font
								(size 1.27 1.27)
							)
						)
					)
				)
				(pin input line
					(at 0 -5.08 0)
					(length 2.54)
					(name "TAKE"
						(effects
							(font
								(size 1.27 1.27)
							)
						)
					)
					(number "12"
						(effects
							(font
								(size 1.27 1.27)
							)
						)
					)
				)
				(pin output line
					(at 0 -7.62 0)
					(length 2.54)
					(name "PASS"
						(effects
							(font
								(size 1.27 1.27)
							)
						)
					)
					(number "11"
						(effects
							(font
								(size 1.27 1.27)
							)
						)
					)
				)
				(pin bidirectional line
					(at 0 -10.16 0)
					(length 2.54)
					(name "SET"
						(effects
							(font
								(size 1.27 1.27)
							)
						)
					)
					(number "13"
						(effects
							(font
								(size 1.27 1.27)
							)
						)
					)
				)
				(pin input line
					(at 0 -12.7 0)
					(length 2.54)
					(name "CTRL"
						(effects
							(font
								(size 1.27 1.27)
							)
						)
					)
					(number "9"
						(effects
							(font
								(size 1.27 1.27)
							)
						)
					)
				)
				(pin open_collector line
					(at 0 -15.24 0)
					(length 2.54)
					(name "PG"
						(effects
							(font
								(size 1.27 1.27)
							)
						)
					)
					(number "10"
						(effects
							(font
								(size 1.27 1.27)
							)
						)
					)
				)
				(pin power_out line
					(at 0 -20.32 0)
					(length 2.54)
					(name "V_{CC}"
						(effects
							(font
								(size 1.27 1.27)
							)
						)
					)
					(number "24"
						(effects
							(font
								(size 1.27 1.27)
							)
						)
					)
				)
				(pin passive line
					(at 0 -25.4 0)
					(length 2.54)
					(name "~{PS}"
						(effects
							(font
								(size 1.27 1.27)
							)
						)
					)
					(number "17"
						(effects
							(font
								(size 1.27 1.27)
							)
						)
					)
				)
				(pin open_collector line
					(at 0 -30.48 0)
					(length 2.54)
					(name "~{ALT}"
						(effects
							(font
								(size 1.27 1.27)
							)
						)
					)
					(number "8"
						(effects
							(font
								(size 1.27 1.27)
							)
						)
					)
				)
				(pin open_collector line
					(at 0 -33.02 0)
					(length 2.54)
					(name "SDA"
						(effects
							(font
								(size 1.27 1.27)
							)
						)
					)
					(number "7"
						(effects
							(font
								(size 1.27 1.27)
							)
						)
					)
				)
				(pin open_collector line
					(at 0 -35.56 0)
					(length 2.54)
					(name "SCL"
						(effects
							(font
								(size 1.27 1.27)
							)
						)
					)
					(number "6"
						(effects
							(font
								(size 1.27 1.27)
							)
						)
					)
				)
				(pin passive line
					(at 25.4 0 180)
					(length 2.54)
					(name "BST"
						(effects
							(font
								(size 1.27 1.27)
							)
						)
					)
					(number "25"
						(effects
							(font
								(size 1.27 1.27)
							)
						)
					)
				)
				(pin passive line
					(at 25.4 -5.08 180)
					(length 2.54)
					(name "SW"
						(effects
							(font
								(size 1.27 1.27)
							)
						)
					)
					(number "2"
						(effects
							(font
								(size 1.27 1.27)
							)
						)
					)
				)
				(pin passive line
					(at 25.4 -5.08 180)
					(length 2.54)
					(hide yes)
					(name "SW"
						(effects
							(font
								(size 1.27 1.27)
							)
						)
					)
					(number "3"
						(effects
							(font
								(size 1.27 1.27)
							)
						)
					)
				)
				(pin passive line
					(at 25.4 -7.62 180)
					(length 2.54)
					(name "V_{OSNS}+"
						(effects
							(font
								(size 1.27 1.27)
							)
						)
					)
					(number "22"
						(effects
							(font
								(size 1.27 1.27)
							)
						)
					)
				)
				(pin passive line
					(at 25.4 -15.24 180)
					(length 2.54)
					(name "V_{OSNS}-"
						(effects
							(font
								(size 1.27 1.27)
							)
						)
					)
					(number "21"
						(effects
							(font
								(size 1.27 1.27)
							)
						)
					)
				)
				(pin passive line
					(at 25.4 -17.78 180)
					(length 2.54)
					(name "I_{SUM}"
						(effects
							(font
								(size 1.27 1.27)
							)
						)
					)
					(number "19"
						(effects
							(font
								(size 1.27 1.27)
							)
						)
					)
				)
				(pin passive line
					(at 25.4 -22.86 180)
					(length 2.54)
					(name "V_{DRV}"
						(effects
							(font
								(size 1.27 1.27)
							)
						)
					)
					(number "5"
						(effects
							(font
								(size 1.27 1.27)
							)
						)
					)
				)
				(pin passive line
					(at 25.4 -25.4 180)
					(length 2.54)
					(name "ADDR"
						(effects
							(font
								(size 1.27 1.27)
							)
						)
					)
					(number "18"
						(effects
							(font
								(size 1.27 1.27)
							)
						)
					)
				)
				(pin passive line
					(at 25.4 -27.94 180)
					(length 2.54)
					(name "I_{REF}"
						(effects
							(font
								(size 1.27 1.27)
							)
						)
					)
					(number "20"
						(effects
							(font
								(size 1.27 1.27)
							)
						)
					)
				)
				(pin power_in line
					(at 25.4 -33.02 180)
					(length 2.54)
					(name "P_{GND}"
						(effects
							(font
								(size 1.27 1.27)
							)
						)
					)
					(number "14"
						(effects
							(font
								(size 1.27 1.27)
							)
						)
					)
				)
				(pin passive line
					(at 25.4 -33.02 180)
					(length 2.54)
					(hide yes)
					(name "P_{GND}"
						(effects
							(font
								(size 1.27 1.27)
							)
						)
					)
					(number "15"
						(effects
							(font
								(size 1.27 1.27)
							)
						)
					)
				)
				(pin passive line
					(at 25.4 -33.02 180)
					(length 2.54)
					(hide yes)
					(name "P_{GND}"
						(effects
							(font
								(size 1.27 1.27)
							)
						)
					)
					(number "4"
						(effects
							(font
								(size 1.27 1.27)
							)
						)
					)
				)
				(pin power_in line
					(at 25.4 -35.56 180)
					(length 2.54)
					(name "A_{GND}"
						(effects
							(font
								(size 1.27 1.27)
							)
						)
					)
					(number "23"
						(effects
							(font
								(size 1.27 1.27)
							)
						)
					)
				)
			)
		)
	(symbol "antmicroDataAcquisitionDigitaltoAnalogConvertersDAC:MCP4726A0T_DFN"
			(exclude_from_sim no)
			(in_bom yes)
			(on_board yes)
			(property "Reference" "U"
				(at 33.02 -2.54 0)
				(effects
					(font
						(size 1.27 1.27)
						(thickness 0.15)
					)
					(justify left bottom)
				)
			)
			(property "Value" "MCP4726A0T_DFN"
				(at 33.02 -7.62 0)
				(effects
					(font
						(size 1.27 1.27)
						(thickness 0.15)
					)
					(justify left bottom)
					(hide yes)
				)
			)
			(property "Footprint" "antmicro-footprints:DFN-6-1EP_2x2mm_P0.65mm_EP1x1.6mm"
				(at 33.02 -10.16 0)
				(effects
					(font
						(size 1.27 1.27)
						(thickness 0.15)
					)
					(justify left bottom)
					(hide yes)
				)
			)
			(property "Datasheet" "https://ww1.microchip.com/downloads/en/DeviceDoc/22272C.pdf"
				(at 33.02 -12.7 0)
				(effects
					(font
						(size 1.27 1.27)
						(thickness 0.15)
					)
					(justify left bottom)
					(hide yes)
				)
			)
			(property "Description" "12-Bit Voltage Output Digital-to-Analog Converter with EEPROM and I2C Interface"
				(at 0 0 0)
				(effects
					(font
						(size 1.27 1.27)
					)
					(hide yes)
				)
			)
			(property "MPN" "MCP4726A0T-E/MAY"
				(at 33.02 -5.08 0)
				(effects
					(font
						(size 1.27 1.27)
						(thickness 0.15)
					)
					(justify left bottom)
				)
			)
			(property "Manufacturer" "Microchip Technology"
				(at 33.02 -15.24 0)
				(effects
					(font
						(size 1.27 1.27)
						(thickness 0.15)
					)
					(justify left bottom)
					(hide yes)
				)
			)
			(property "Author" "Antmicro"
				(at 33.02 -17.78 0)
				(effects
					(font
						(size 1.27 1.27)
						(thickness 0.15)
					)
					(justify left bottom)
					(hide yes)
				)
			)
			(property "License" "Apache-2.0"
				(at 33.02 -20.32 0)
				(effects
					(font
						(size 1.27 1.27)
						(thickness 0.15)
					)
					(justify left bottom)
					(hide yes)
				)
			)
			(property "ki_keywords" "DAC, SMT, I2C"
				(at 0 0 0)
				(effects
					(font
						(size 1.27 1.27)
					)
					(hide yes)
				)
			)
			(property "ki_fp_filters" "DFN6_2x2MC_MCH DFN6_2x2MC_MCH-M DFN6_2x2MC_MCH-L"
				(at 0 0 0)
				(effects
					(font
						(size 1.27 1.27)
					)
					(hide yes)
				)
			)
			(symbol "MCP4726A0T_DFN_1_1"
				(rectangle
					(start 2.54 2.54)
					(end 16.51 -10.16)
					(stroke
						(width 0.254)
						(type default)
					)
					(fill
						(type background)
					)
				)
				(pin power_in line
					(at 0 0 0)
					(length 2.54)
					(name "VDD"
						(effects
							(font
								(size 1.27 1.27)
							)
						)
					)
					(number "4"
						(effects
							(font
								(size 1.27 1.27)
							)
						)
					)
				)
				(pin input line
					(at 0 -2.54 0)
					(length 2.54)
					(name "SCL"
						(effects
							(font
								(size 1.27 1.27)
							)
						)
					)
					(number "2"
						(effects
							(font
								(size 1.27 1.27)
							)
						)
					)
				)
				(pin bidirectional line
					(at 0 -5.08 0)
					(length 2.54)
					(name "SDA"
						(effects
							(font
								(size 1.27 1.27)
							)
						)
					)
					(number "3"
						(effects
							(font
								(size 1.27 1.27)
							)
						)
					)
				)
				(pin output line
					(at 19.05 0 180)
					(length 2.54)
					(name "VOUT"
						(effects
							(font
								(size 1.27 1.27)
							)
						)
					)
					(number "6"
						(effects
							(font
								(size 1.27 1.27)
							)
						)
					)
				)
				(pin power_in line
					(at 19.05 -2.54 180)
					(length 2.54)
					(name "VREF"
						(effects
							(font
								(size 1.27 1.27)
							)
						)
					)
					(number "1"
						(effects
							(font
								(size 1.27 1.27)
							)
						)
					)
				)
				(pin power_in line
					(at 19.05 -5.08 180)
					(length 2.54)
					(name "GND"
						(effects
							(font
								(size 1.27 1.27)
							)
						)
					)
					(number "5"
						(effects
							(font
								(size 1.27 1.27)
							)
						)
					)
				)
				(pin power_in line
					(at 19.05 -7.62 180)
					(length 2.54)
					(name "SH"
						(effects
							(font
								(size 1.27 1.27)
							)
						)
					)
					(number "7"
						(effects
							(font
								(size 1.27 1.27)
							)
						)
					)
				)
			)
		)
	(symbol "antmicroDiodesRectifiersSingle:BAT54-02V-G3-08"
			(pin_numbers
				(hide yes)
			)
			(pin_names
				(hide yes)
			)
			(exclude_from_sim no)
			(in_bom yes)
			(on_board yes)
			(property "Reference" "D"
				(at 21.59 -5.08 0)
				(effects
					(font
						(size 1.27 1.27)
						(thickness 0.15)
					)
					(justify left bottom)
				)
			)
			(property "Value" "BAT54-02V-G3-08"
				(at 21.59 -15.24 0)
				(effects
					(font
						(size 1.27 1.27)
						(thickness 0.15)
					)
					(justify left bottom)
					(hide yes)
				)
			)
			(property "Footprint" "antmicro-footprints:SOD-523"
				(at 21.59 -10.16 0)
				(effects
					(font
						(size 1.27 1.27)
						(thickness 0.15)
					)
					(justify left bottom)
					(hide yes)
				)
			)
			(property "Datasheet" "https://www.vishay.com/docs/85633/bat5402v.pdf"
				(at 21.59 -12.7 0)
				(effects
					(font
						(size 1.27 1.27)
						(thickness 0.15)
					)
					(justify left bottom)
					(hide yes)
				)
			)
			(property "Description" "Small Signal Schottky Diode, Single, 30 V, 200 mA, 800 mV, 600 mA, 125 °C"
				(at 0 0 0)
				(effects
					(font
						(size 1.27 1.27)
					)
					(hide yes)
				)
			)
			(property "MPN" "BAT54-02V-G3-08"
				(at 21.59 -7.62 0)
				(effects
					(font
						(size 1.27 1.27)
						(thickness 0.15)
					)
					(justify left bottom)
				)
			)
			(property "Manufacturer" "Vishay"
				(at 21.59 -17.78 0)
				(effects
					(font
						(size 1.27 1.27)
						(thickness 0.15)
					)
					(justify left bottom)
					(hide yes)
				)
			)
			(property "Author" "Antmicro"
				(at 21.59 -20.32 0)
				(effects
					(font
						(size 1.27 1.27)
						(thickness 0.15)
					)
					(justify left bottom)
					(hide yes)
				)
			)
			(property "License" "Apache-2.0"
				(at 21.59 -22.86 0)
				(effects
					(font
						(size 1.27 1.27)
						(thickness 0.15)
					)
					(justify left bottom)
					(hide yes)
				)
			)
			(property "ki_keywords" "SMT, SEMICONDUCTOR, DIODE, SCHOTTKY"
				(at 0 0 0)
				(effects
					(font
						(size 1.27 1.27)
					)
					(hide yes)
				)
			)
			(symbol "BAT54-02V-G3-08_0_1"
				(polyline
					(pts
						(xy 1.905 0) (xy 0.635 0)
					)
					(stroke
						(width 0)
						(type default)
					)
					(fill
						(type none)
					)
				)
				(polyline
					(pts
						(xy 4.445 0) (xy 3.175 0)
					)
					(stroke
						(width 0)
						(type default)
					)
					(fill
						(type none)
					)
				)
			)
			(symbol "BAT54-02V-G3-08_1_1"
				(polyline
					(pts
						(xy 1.778 1.016) (xy 1.778 -1.016)
					)
					(stroke
						(width 0.254)
						(type default)
					)
					(fill
						(type none)
					)
				)
				(polyline
					(pts
						(xy 1.778 1.016) (xy 1.397 1.016) (xy 1.397 0.762)
					)
					(stroke
						(width 0.254)
						(type default)
					)
					(fill
						(type none)
					)
				)
				(polyline
					(pts
						(xy 1.778 -1.016) (xy 2.159 -1.016) (xy 2.159 -0.762)
					)
					(stroke
						(width 0.254)
						(type default)
					)
					(fill
						(type none)
					)
				)
				(polyline
					(pts
						(xy 3.302 1.016) (xy 3.302 -1.016) (xy 1.778 0) (xy 3.302 1.016)
					)
					(stroke
						(width 0.254)
						(type default)
					)
					(fill
						(type outline)
					)
				)
				(pin passive line
					(at 0 0 0)
					(length 0.635)
					(name "C"
						(effects
							(font
								(size 1.27 1.27)
							)
						)
					)
					(number "1"
						(effects
							(font
								(size 1.27 1.27)
							)
						)
					)
				)
				(pin passive line
					(at 5.08 0 180)
					(length 0.635)
					(name "A"
						(effects
							(font
								(size 1.27 1.27)
							)
						)
					)
					(number "2"
						(effects
							(font
								(size 1.27 1.27)
							)
						)
					)
				)
			)
		)
	(symbol "antmicroEdgeConnectors:PCB-Edge_PCIexpress_x8"
			(exclude_from_sim no)
			(in_bom no)
			(on_board yes)
			(property "Reference" "J"
				(at 48.26 -5.08 0)
				(effects
					(font
						(size 1.27 1.27)
						(thickness 0.15)
					)
					(justify left bottom)
				)
			)
			(property "Value" "PCB-Edge_PCIexpress_x8"
				(at 48.26 -7.62 0)
				(effects
					(font
						(size 1.27 1.27)
						(thickness 0.15)
					)
					(justify left bottom)
				)
			)
			(property "Footprint" "antmicro-footprints:PCB-Edge_PCIexpress_x8"
				(at 48.26 -10.16 0)
				(effects
					(font
						(size 1.27 1.27)
						(thickness 0.15)
					)
					(justify left bottom)
					(hide yes)
				)
			)
			(property "Datasheet" ""
				(at 48.26 -12.7 0)
				(effects
					(font
						(size 1.27 1.27)
						(thickness 0.15)
					)
					(justify left bottom)
					(hide yes)
				)
			)
			(property "Description" "PCIe x8 edge connector"
				(at 0 0 0)
				(effects
					(font
						(size 1.27 1.27)
					)
					(hide yes)
				)
			)
			(property "Author" "Antmicro"
				(at 48.26 -12.7 0)
				(effects
					(font
						(size 1.27 1.27)
						(thickness 0.15)
					)
					(justify left bottom)
					(hide yes)
				)
			)
			(property "License" "Apache-2.0"
				(at 48.26 -15.24 0)
				(effects
					(font
						(size 1.27 1.27)
						(thickness 0.15)
					)
					(justify left bottom)
					(hide yes)
				)
			)
			(property "ki_keywords" "PCIE, CONNECTOR, EDGE"
				(at 0 0 0)
				(effects
					(font
						(size 1.27 1.27)
					)
					(hide yes)
				)
			)
			(symbol "PCB-Edge_PCIexpress_x8_1_1"
				(rectangle
					(start 3.81 2.54)
					(end 29.21 -106.68)
					(stroke
						(width 0.254)
						(type default)
					)
					(fill
						(type background)
					)
				)
				(polyline
					(pts
						(xy 3.81 -76.2) (xy 29.21 -76.2)
					)
					(stroke
						(width 0.254)
						(type default)
					)
					(fill
						(type background)
					)
				)
				(polyline
					(pts
						(xy 29.21 -36.83) (xy 3.81 -36.83)
					)
					(stroke
						(width 0.254)
						(type default)
					)
					(fill
						(type background)
					)
				)
				(polyline
					(pts
						(xy 29.21 -53.34) (xy 3.81 -53.34)
					)
					(stroke
						(width 0.254)
						(type default)
					)
					(fill
						(type background)
					)
				)
				(text "PCIe_x1"
					(at 12.7 -52.07 0)
					(effects
						(font
							(size 1.27 1.27)
							(thickness 0.15)
						)
						(justify left bottom)
					)
				)
				(text "PCIe_x4"
					(at 12.7 -74.93 0)
					(effects
						(font
							(size 1.27 1.27)
							(thickness 0.15)
						)
						(justify left bottom)
					)
				)
				(text "PCIe_x8"
					(at 12.7 -105.41 0)
					(effects
						(font
							(size 1.27 1.27)
							(thickness 0.15)
						)
						(justify left bottom)
					)
				)
				(pin power_in line
					(at 0 0 0)
					(length 3.81)
					(name "12V"
						(effects
							(font
								(size 1.27 1.27)
							)
						)
					)
					(number "A2"
						(effects
							(font
								(size 1.27 1.27)
							)
						)
					)
				)
				(pin passive line
					(at 0 0 0)
					(length 3.81)
					(hide yes)
					(name "12V"
						(effects
							(font
								(size 1.27 1.27)
							)
						)
					)
					(number "A3"
						(effects
							(font
								(size 1.27 1.27)
							)
						)
					)
				)
				(pin passive line
					(at 0 0 0)
					(length 3.81)
					(hide yes)
					(name "12V"
						(effects
							(font
								(size 1.27 1.27)
							)
						)
					)
					(number "B1"
						(effects
							(font
								(size 1.27 1.27)
							)
						)
					)
				)
				(pin passive line
					(at 0 0 0)
					(length 3.81)
					(hide yes)
					(name "12V"
						(effects
							(font
								(size 1.27 1.27)
							)
						)
					)
					(number "B2"
						(effects
							(font
								(size 1.27 1.27)
							)
						)
					)
				)
				(pin passive line
					(at 0 0 0)
					(length 3.81)
					(hide yes)
					(name "12V"
						(effects
							(font
								(size 1.27 1.27)
							)
						)
					)
					(number "B3"
						(effects
							(font
								(size 1.27 1.27)
							)
						)
					)
				)
				(pin power_in line
					(at 0 -2.54 0)
					(length 3.81)
					(name "3V3"
						(effects
							(font
								(size 1.27 1.27)
							)
						)
					)
					(number "A10"
						(effects
							(font
								(size 1.27 1.27)
							)
						)
					)
				)
				(pin passive line
					(at 0 -2.54 0)
					(length 3.81)
					(hide yes)
					(name "3V3"
						(effects
							(font
								(size 1.27 1.27)
							)
						)
					)
					(number "A9"
						(effects
							(font
								(size 1.27 1.27)
							)
						)
					)
				)
				(pin passive line
					(at 0 -2.54 0)
					(length 3.81)
					(hide yes)
					(name "3V3"
						(effects
							(font
								(size 1.27 1.27)
							)
						)
					)
					(number "B8"
						(effects
							(font
								(size 1.27 1.27)
							)
						)
					)
				)
				(pin power_in line
					(at 0 -5.08 0)
					(length 3.81)
					(name "3V3AUX"
						(effects
							(font
								(size 1.27 1.27)
							)
						)
					)
					(number "B10"
						(effects
							(font
								(size 1.27 1.27)
							)
						)
					)
				)
				(pin input line
					(at 0 -20.32 0)
					(length 3.81)
					(name "TCK"
						(effects
							(font
								(size 1.27 1.27)
							)
						)
					)
					(number "A5"
						(effects
							(font
								(size 1.27 1.27)
							)
						)
					)
				)
				(pin input line
					(at 0 -22.86 0)
					(length 3.81)
					(name "TDI"
						(effects
							(font
								(size 1.27 1.27)
							)
						)
					)
					(number "A6"
						(effects
							(font
								(size 1.27 1.27)
							)
						)
					)
				)
				(pin output line
					(at 0 -25.4 0)
					(length 3.81)
					(name "TDO"
						(effects
							(font
								(size 1.27 1.27)
							)
						)
					)
					(number "A7"
						(effects
							(font
								(size 1.27 1.27)
							)
						)
					)
				)
				(pin input line
					(at 0 -27.94 0)
					(length 3.81)
					(name "TMS"
						(effects
							(font
								(size 1.27 1.27)
							)
						)
					)
					(number "A8"
						(effects
							(font
								(size 1.27 1.27)
							)
						)
					)
				)
				(pin power_in line
					(at 0 -33.02 0)
					(length 3.81)
					(name "GND"
						(effects
							(font
								(size 1.27 1.27)
							)
						)
					)
					(number "A12"
						(effects
							(font
								(size 1.27 1.27)
							)
						)
					)
				)
				(pin passive line
					(at 0 -33.02 0)
					(length 3.81)
					(hide yes)
					(name "GND"
						(effects
							(font
								(size 1.27 1.27)
							)
						)
					)
					(number "A15"
						(effects
							(font
								(size 1.27 1.27)
							)
						)
					)
				)
				(pin passive line
					(at 0 -33.02 0)
					(length 3.81)
					(hide yes)
					(name "GND"
						(effects
							(font
								(size 1.27 1.27)
							)
						)
					)
					(number "A18"
						(effects
							(font
								(size 1.27 1.27)
							)
						)
					)
				)
				(pin passive line
					(at 0 -33.02 0)
					(length 3.81)
					(hide yes)
					(name "GND"
						(effects
							(font
								(size 1.27 1.27)
							)
						)
					)
					(number "A20"
						(effects
							(font
								(size 1.27 1.27)
							)
						)
					)
				)
				(pin passive line
					(at 0 -33.02 0)
					(length 3.81)
					(hide yes)
					(name "GND"
						(effects
							(font
								(size 1.27 1.27)
							)
						)
					)
					(number "A23"
						(effects
							(font
								(size 1.27 1.27)
							)
						)
					)
				)
				(pin passive line
					(at 0 -33.02 0)
					(length 3.81)
					(hide yes)
					(name "GND"
						(effects
							(font
								(size 1.27 1.27)
							)
						)
					)
					(number "A24"
						(effects
							(font
								(size 1.27 1.27)
							)
						)
					)
				)
				(pin passive line
					(at 0 -33.02 0)
					(length 3.81)
					(hide yes)
					(name "GND"
						(effects
							(font
								(size 1.27 1.27)
							)
						)
					)
					(number "A27"
						(effects
							(font
								(size 1.27 1.27)
							)
						)
					)
				)
				(pin passive line
					(at 0 -33.02 0)
					(length 3.81)
					(hide yes)
					(name "GND"
						(effects
							(font
								(size 1.27 1.27)
							)
						)
					)
					(number "A28"
						(effects
							(font
								(size 1.27 1.27)
							)
						)
					)
				)
				(pin passive line
					(at 0 -33.02 0)
					(length 3.81)
					(hide yes)
					(name "GND"
						(effects
							(font
								(size 1.27 1.27)
							)
						)
					)
					(number "A31"
						(effects
							(font
								(size 1.27 1.27)
							)
						)
					)
				)
				(pin passive line
					(at 0 -33.02 0)
					(length 3.81)
					(hide yes)
					(name "GND"
						(effects
							(font
								(size 1.27 1.27)
							)
						)
					)
					(number "A34"
						(effects
							(font
								(size 1.27 1.27)
							)
						)
					)
				)
				(pin passive line
					(at 0 -33.02 0)
					(length 3.81)
					(hide yes)
					(name "GND"
						(effects
							(font
								(size 1.27 1.27)
							)
						)
					)
					(number "A37"
						(effects
							(font
								(size 1.27 1.27)
							)
						)
					)
				)
				(pin passive line
					(at 0 -33.02 0)
					(length 3.81)
					(hide yes)
					(name "GND"
						(effects
							(font
								(size 1.27 1.27)
							)
						)
					)
					(number "A38"
						(effects
							(font
								(size 1.27 1.27)
							)
						)
					)
				)
				(pin passive line
					(at 0 -33.02 0)
					(length 3.81)
					(hide yes)
					(name "GND"
						(effects
							(font
								(size 1.27 1.27)
							)
						)
					)
					(number "A4"
						(effects
							(font
								(size 1.27 1.27)
							)
						)
					)
				)
				(pin passive line
					(at 0 -33.02 0)
					(length 3.81)
					(hide yes)
					(name "GND"
						(effects
							(font
								(size 1.27 1.27)
							)
						)
					)
					(number "A41"
						(effects
							(font
								(size 1.27 1.27)
							)
						)
					)
				)
				(pin passive line
					(at 0 -33.02 0)
					(length 3.81)
					(hide yes)
					(name "GND"
						(effects
							(font
								(size 1.27 1.27)
							)
						)
					)
					(number "A42"
						(effects
							(font
								(size 1.27 1.27)
							)
						)
					)
				)
				(pin passive line
					(at 0 -33.02 0)
					(length 3.81)
					(hide yes)
					(name "GND"
						(effects
							(font
								(size 1.27 1.27)
							)
						)
					)
					(number "A45"
						(effects
							(font
								(size 1.27 1.27)
							)
						)
					)
				)
				(pin passive line
					(at 0 -33.02 0)
					(length 3.81)
					(hide yes)
					(name "GND"
						(effects
							(font
								(size 1.27 1.27)
							)
						)
					)
					(number "A46"
						(effects
							(font
								(size 1.27 1.27)
							)
						)
					)
				)
				(pin passive line
					(at 0 -33.02 0)
					(length 3.81)
					(hide yes)
					(name "GND"
						(effects
							(font
								(size 1.27 1.27)
							)
						)
					)
					(number "A49"
						(effects
							(font
								(size 1.27 1.27)
							)
						)
					)
				)
				(pin passive line
					(at 0 -33.02 0)
					(length 3.81)
					(hide yes)
					(name "GND"
						(effects
							(font
								(size 1.27 1.27)
							)
						)
					)
					(number "B13"
						(effects
							(font
								(size 1.27 1.27)
							)
						)
					)
				)
				(pin passive line
					(at 0 -33.02 0)
					(length 3.81)
					(hide yes)
					(name "GND"
						(effects
							(font
								(size 1.27 1.27)
							)
						)
					)
					(number "B16"
						(effects
							(font
								(size 1.27 1.27)
							)
						)
					)
				)
				(pin passive line
					(at 0 -33.02 0)
					(length 3.81)
					(hide yes)
					(name "GND"
						(effects
							(font
								(size 1.27 1.27)
							)
						)
					)
					(number "B18"
						(effects
							(font
								(size 1.27 1.27)
							)
						)
					)
				)
				(pin passive line
					(at 0 -33.02 0)
					(length 3.81)
					(hide yes)
					(name "GND"
						(effects
							(font
								(size 1.27 1.27)
							)
						)
					)
					(number "B21"
						(effects
							(font
								(size 1.27 1.27)
							)
						)
					)
				)
				(pin passive line
					(at 0 -33.02 0)
					(length 3.81)
					(hide yes)
					(name "GND"
						(effects
							(font
								(size 1.27 1.27)
							)
						)
					)
					(number "B22"
						(effects
							(font
								(size 1.27 1.27)
							)
						)
					)
				)
				(pin passive line
					(at 0 -33.02 0)
					(length 3.81)
					(hide yes)
					(name "GND"
						(effects
							(font
								(size 1.27 1.27)
							)
						)
					)
					(number "B25"
						(effects
							(font
								(size 1.27 1.27)
							)
						)
					)
				)
				(pin passive line
					(at 0 -33.02 0)
					(length 3.81)
					(hide yes)
					(name "GND"
						(effects
							(font
								(size 1.27 1.27)
							)
						)
					)
					(number "B26"
						(effects
							(font
								(size 1.27 1.27)
							)
						)
					)
				)
				(pin passive line
					(at 0 -33.02 0)
					(length 3.81)
					(hide yes)
					(name "GND"
						(effects
							(font
								(size 1.27 1.27)
							)
						)
					)
					(number "B29"
						(effects
							(font
								(size 1.27 1.27)
							)
						)
					)
				)
				(pin passive line
					(at 0 -33.02 0)
					(length 3.81)
					(hide yes)
					(name "GND"
						(effects
							(font
								(size 1.27 1.27)
							)
						)
					)
					(number "B32"
						(effects
							(font
								(size 1.27 1.27)
							)
						)
					)
				)
				(pin passive line
					(at 0 -33.02 0)
					(length 3.81)
					(hide yes)
					(name "GND"
						(effects
							(font
								(size 1.27 1.27)
							)
						)
					)
					(number "B35"
						(effects
							(font
								(size 1.27 1.27)
							)
						)
					)
				)
				(pin passive line
					(at 0 -33.02 0)
					(length 3.81)
					(hide yes)
					(name "GND"
						(effects
							(font
								(size 1.27 1.27)
							)
						)
					)
					(number "B36"
						(effects
							(font
								(size 1.27 1.27)
							)
						)
					)
				)
				(pin passive line
					(at 0 -33.02 0)
					(length 3.81)
					(hide yes)
					(name "GND"
						(effects
							(font
								(size 1.27 1.27)
							)
						)
					)
					(number "B39"
						(effects
							(font
								(size 1.27 1.27)
							)
						)
					)
				)
				(pin passive line
					(at 0 -33.02 0)
					(length 3.81)
					(hide yes)
					(name "GND"
						(effects
							(font
								(size 1.27 1.27)
							)
						)
					)
					(number "B4"
						(effects
							(font
								(size 1.27 1.27)
							)
						)
					)
				)
				(pin passive line
					(at 0 -33.02 0)
					(length 3.81)
					(hide yes)
					(name "GND"
						(effects
							(font
								(size 1.27 1.27)
							)
						)
					)
					(number "B40"
						(effects
							(font
								(size 1.27 1.27)
							)
						)
					)
				)
				(pin passive line
					(at 0 -33.02 0)
					(length 3.81)
					(hide yes)
					(name "GND"
						(effects
							(font
								(size 1.27 1.27)
							)
						)
					)
					(number "B43"
						(effects
							(font
								(size 1.27 1.27)
							)
						)
					)
				)
				(pin passive line
					(at 0 -33.02 0)
					(length 3.81)
					(hide yes)
					(name "GND"
						(effects
							(font
								(size 1.27 1.27)
							)
						)
					)
					(number "B44"
						(effects
							(font
								(size 1.27 1.27)
							)
						)
					)
				)
				(pin passive line
					(at 0 -33.02 0)
					(length 3.81)
					(hide yes)
					(name "GND"
						(effects
							(font
								(size 1.27 1.27)
							)
						)
					)
					(number "B47"
						(effects
							(font
								(size 1.27 1.27)
							)
						)
					)
				)
				(pin passive line
					(at 0 -33.02 0)
					(length 3.81)
					(hide yes)
					(name "GND"
						(effects
							(font
								(size 1.27 1.27)
							)
						)
					)
					(number "B49"
						(effects
							(font
								(size 1.27 1.27)
							)
						)
					)
				)
				(pin passive line
					(at 0 -33.02 0)
					(length 3.81)
					(hide yes)
					(name "GND"
						(effects
							(font
								(size 1.27 1.27)
							)
						)
					)
					(number "B7"
						(effects
							(font
								(size 1.27 1.27)
							)
						)
					)
				)
				(pin input line
					(at 0 -40.64 0)
					(length 3.81)
					(name "REFCLK_p"
						(effects
							(font
								(size 1.27 1.27)
							)
						)
					)
					(number "A13"
						(effects
							(font
								(size 1.27 1.27)
							)
						)
					)
				)
				(pin input line
					(at 0 -43.18 0)
					(length 3.81)
					(name "REFCLK_n"
						(effects
							(font
								(size 1.27 1.27)
							)
						)
					)
					(number "A14"
						(effects
							(font
								(size 1.27 1.27)
							)
						)
					)
				)
				(pin input line
					(at 0 -48.26 0)
					(length 3.81)
					(name "HSO0_p"
						(effects
							(font
								(size 1.27 1.27)
							)
						)
					)
					(number "B14"
						(effects
							(font
								(size 1.27 1.27)
							)
						)
					)
				)
				(pin input line
					(at 0 -50.8 0)
					(length 3.81)
					(name "HSO0_n"
						(effects
							(font
								(size 1.27 1.27)
							)
						)
					)
					(number "B15"
						(effects
							(font
								(size 1.27 1.27)
							)
						)
					)
				)
				(pin input line
					(at 0 -55.88 0)
					(length 3.81)
					(name "HSO1_p"
						(effects
							(font
								(size 1.27 1.27)
							)
						)
					)
					(number "B19"
						(effects
							(font
								(size 1.27 1.27)
							)
						)
					)
				)
				(pin input line
					(at 0 -58.42 0)
					(length 3.81)
					(name "HSO1_n"
						(effects
							(font
								(size 1.27 1.27)
							)
						)
					)
					(number "B20"
						(effects
							(font
								(size 1.27 1.27)
							)
						)
					)
				)
				(pin input line
					(at 0 -63.5 0)
					(length 3.81)
					(name "HSO2_p"
						(effects
							(font
								(size 1.27 1.27)
							)
						)
					)
					(number "B23"
						(effects
							(font
								(size 1.27 1.27)
							)
						)
					)
				)
				(pin input line
					(at 0 -66.04 0)
					(length 3.81)
					(name "HSO2_n"
						(effects
							(font
								(size 1.27 1.27)
							)
						)
					)
					(number "B24"
						(effects
							(font
								(size 1.27 1.27)
							)
						)
					)
				)
				(pin input line
					(at 0 -71.12 0)
					(length 3.81)
					(name "HSO3_p"
						(effects
							(font
								(size 1.27 1.27)
							)
						)
					)
					(number "B27"
						(effects
							(font
								(size 1.27 1.27)
							)
						)
					)
				)
				(pin input line
					(at 0 -73.66 0)
					(length 3.81)
					(name "HSO3_n"
						(effects
							(font
								(size 1.27 1.27)
							)
						)
					)
					(number "B28"
						(effects
							(font
								(size 1.27 1.27)
							)
						)
					)
				)
				(pin input line
					(at 0 -78.74 0)
					(length 3.81)
					(name "HSO4_p"
						(effects
							(font
								(size 1.27 1.27)
							)
						)
					)
					(number "B33"
						(effects
							(font
								(size 1.27 1.27)
							)
						)
					)
				)
				(pin input line
					(at 0 -81.28 0)
					(length 3.81)
					(name "HSO4_n"
						(effects
							(font
								(size 1.27 1.27)
							)
						)
					)
					(number "B34"
						(effects
							(font
								(size 1.27 1.27)
							)
						)
					)
				)
				(pin input line
					(at 0 -86.36 0)
					(length 3.81)
					(name "HSO5_p"
						(effects
							(font
								(size 1.27 1.27)
							)
						)
					)
					(number "B37"
						(effects
							(font
								(size 1.27 1.27)
							)
						)
					)
				)
				(pin input line
					(at 0 -88.9 0)
					(length 3.81)
					(name "HSO5_n"
						(effects
							(font
								(size 1.27 1.27)
							)
						)
					)
					(number "B38"
						(effects
							(font
								(size 1.27 1.27)
							)
						)
					)
				)
				(pin input line
					(at 0 -93.98 0)
					(length 3.81)
					(name "HSO6_p"
						(effects
							(font
								(size 1.27 1.27)
							)
						)
					)
					(number "B41"
						(effects
							(font
								(size 1.27 1.27)
							)
						)
					)
				)
				(pin input line
					(at 0 -96.52 0)
					(length 3.81)
					(name "HSO6_n"
						(effects
							(font
								(size 1.27 1.27)
							)
						)
					)
					(number "B42"
						(effects
							(font
								(size 1.27 1.27)
							)
						)
					)
				)
				(pin input line
					(at 0 -101.6 0)
					(length 3.81)
					(name "HSO7_p"
						(effects
							(font
								(size 1.27 1.27)
							)
						)
					)
					(number "B45"
						(effects
							(font
								(size 1.27 1.27)
							)
						)
					)
				)
				(pin input line
					(at 0 -104.14 0)
					(length 3.81)
					(name "HSO7_n"
						(effects
							(font
								(size 1.27 1.27)
							)
						)
					)
					(number "B46"
						(effects
							(font
								(size 1.27 1.27)
							)
						)
					)
				)
				(pin no_connect line
					(at 3.81 -7.62 0)
					(length 3.81)
					(hide yes)
					(name "NC"
						(effects
							(font
								(size 1.27 1.27)
							)
						)
					)
					(number "A19"
						(effects
							(font
								(size 1.27 1.27)
							)
						)
					)
				)
				(pin no_connect line
					(at 3.81 -10.16 0)
					(length 3.81)
					(hide yes)
					(name "NC"
						(effects
							(font
								(size 1.27 1.27)
							)
						)
					)
					(number "A32"
						(effects
							(font
								(size 1.27 1.27)
							)
						)
					)
				)
				(pin no_connect line
					(at 3.81 -12.7 0)
					(length 3.81)
					(hide yes)
					(name "NC"
						(effects
							(font
								(size 1.27 1.27)
							)
						)
					)
					(number "A33"
						(effects
							(font
								(size 1.27 1.27)
							)
						)
					)
				)
				(pin passive line
					(at 33.02 0 180)
					(length 3.81)
					(name "~{PRSNT1}"
						(effects
							(font
								(size 1.27 1.27)
							)
						)
					)
					(number "A1"
						(effects
							(font
								(size 1.27 1.27)
							)
						)
					)
				)
				(pin passive line
					(at 33.02 -2.54 180)
					(length 3.81)
					(name "~{PRSNT2_x1}"
						(effects
							(font
								(size 1.27 1.27)
							)
						)
					)
					(number "B17"
						(effects
							(font
								(size 1.27 1.27)
							)
						)
					)
				)
				(pin passive line
					(at 33.02 -5.08 180)
					(length 3.81)
					(name "~{PRSNT2_x4}"
						(effects
							(font
								(size 1.27 1.27)
							)
						)
					)
					(number "B31"
						(effects
							(font
								(size 1.27 1.27)
							)
						)
					)
				)
				(pin passive line
					(at 33.02 -7.62 180)
					(length 3.81)
					(name "~{PRSNT2_x8}"
						(effects
							(font
								(size 1.27 1.27)
							)
						)
					)
					(number "B48"
						(effects
							(font
								(size 1.27 1.27)
							)
						)
					)
				)
				(pin input line
					(at 33.02 -20.32 180)
					(length 3.81)
					(name "~{TRST}"
						(effects
							(font
								(size 1.27 1.27)
							)
						)
					)
					(number "B9"
						(effects
							(font
								(size 1.27 1.27)
							)
						)
					)
				)
				(pin open_collector line
					(at 33.02 -22.86 180)
					(length 3.81)
					(name "~{WAKE}"
						(effects
							(font
								(size 1.27 1.27)
							)
						)
					)
					(number "B11"
						(effects
							(font
								(size 1.27 1.27)
							)
						)
					)
				)
				(pin open_collector line
					(at 33.02 -25.4 180)
					(length 3.81)
					(name "~{CLKREQ}"
						(effects
							(font
								(size 1.27 1.27)
							)
						)
					)
					(number "B12"
						(effects
							(font
								(size 1.27 1.27)
							)
						)
					)
				)
				(pin open_collector line
					(at 33.02 -27.94 180)
					(length 3.81)
					(name "~{PERST}"
						(effects
							(font
								(size 1.27 1.27)
							)
						)
					)
					(number "A11"
						(effects
							(font
								(size 1.27 1.27)
							)
						)
					)
				)
				(pin open_collector line
					(at 33.02 -30.48 180)
					(length 3.81)
					(name "~{PWRBRK}"
						(effects
							(font
								(size 1.27 1.27)
							)
						)
					)
					(number "B30"
						(effects
							(font
								(size 1.27 1.27)
							)
						)
					)
				)
				(pin open_collector line
					(at 33.02 -40.64 180)
					(length 3.81)
					(name "SMCLK"
						(effects
							(font
								(size 1.27 1.27)
							)
						)
					)
					(number "B5"
						(effects
							(font
								(size 1.27 1.27)
							)
						)
					)
				)
				(pin open_collector line
					(at 33.02 -43.18 180)
					(length 3.81)
					(name "SMDAT"
						(effects
							(font
								(size 1.27 1.27)
							)
						)
					)
					(number "B6"
						(effects
							(font
								(size 1.27 1.27)
							)
						)
					)
				)
				(pin output line
					(at 33.02 -48.26 180)
					(length 3.81)
					(name "HSI0_p"
						(effects
							(font
								(size 1.27 1.27)
							)
						)
					)
					(number "A16"
						(effects
							(font
								(size 1.27 1.27)
							)
						)
					)
				)
				(pin output line
					(at 33.02 -50.8 180)
					(length 3.81)
					(name "HSI0_n"
						(effects
							(font
								(size 1.27 1.27)
							)
						)
					)
					(number "A17"
						(effects
							(font
								(size 1.27 1.27)
							)
						)
					)
				)
				(pin output line
					(at 33.02 -55.88 180)
					(length 3.81)
					(name "HSI1_p"
						(effects
							(font
								(size 1.27 1.27)
							)
						)
					)
					(number "A21"
						(effects
							(font
								(size 1.27 1.27)
							)
						)
					)
				)
				(pin output line
					(at 33.02 -58.42 180)
					(length 3.81)
					(name "HSI1_n"
						(effects
							(font
								(size 1.27 1.27)
							)
						)
					)
					(number "A22"
						(effects
							(font
								(size 1.27 1.27)
							)
						)
					)
				)
				(pin output line
					(at 33.02 -63.5 180)
					(length 3.81)
					(name "HSI2_p"
						(effects
							(font
								(size 1.27 1.27)
							)
						)
					)
					(number "A25"
						(effects
							(font
								(size 1.27 1.27)
							)
						)
					)
				)
				(pin output line
					(at 33.02 -66.04 180)
					(length 3.81)
					(name "HSI2_n"
						(effects
							(font
								(size 1.27 1.27)
							)
						)
					)
					(number "A26"
						(effects
							(font
								(size 1.27 1.27)
							)
						)
					)
				)
				(pin output line
					(at 33.02 -71.12 180)
					(length 3.81)
					(name "HSI3_p"
						(effects
							(font
								(size 1.27 1.27)
							)
						)
					)
					(number "A29"
						(effects
							(font
								(size 1.27 1.27)
							)
						)
					)
				)
				(pin output line
					(at 33.02 -73.66 180)
					(length 3.81)
					(name "HSI3_n"
						(effects
							(font
								(size 1.27 1.27)
							)
						)
					)
					(number "A30"
						(effects
							(font
								(size 1.27 1.27)
							)
						)
					)
				)
				(pin output line
					(at 33.02 -78.74 180)
					(length 3.81)
					(name "HSI4_p"
						(effects
							(font
								(size 1.27 1.27)
							)
						)
					)
					(number "A35"
						(effects
							(font
								(size 1.27 1.27)
							)
						)
					)
				)
				(pin output line
					(at 33.02 -81.28 180)
					(length 3.81)
					(name "HSI4_n"
						(effects
							(font
								(size 1.27 1.27)
							)
						)
					)
					(number "A36"
						(effects
							(font
								(size 1.27 1.27)
							)
						)
					)
				)
				(pin output line
					(at 33.02 -86.36 180)
					(length 3.81)
					(name "HSI5_p"
						(effects
							(font
								(size 1.27 1.27)
							)
						)
					)
					(number "A39"
						(effects
							(font
								(size 1.27 1.27)
							)
						)
					)
				)
				(pin output line
					(at 33.02 -88.9 180)
					(length 3.81)
					(name "HSI5_n"
						(effects
							(font
								(size 1.27 1.27)
							)
						)
					)
					(number "A40"
						(effects
							(font
								(size 1.27 1.27)
							)
						)
					)
				)
				(pin output line
					(at 33.02 -93.98 180)
					(length 3.81)
					(name "HSI6_p"
						(effects
							(font
								(size 1.27 1.27)
							)
						)
					)
					(number "A43"
						(effects
							(font
								(size 1.27 1.27)
							)
						)
					)
				)
				(pin output line
					(at 33.02 -96.52 180)
					(length 3.81)
					(name "HSI6_n"
						(effects
							(font
								(size 1.27 1.27)
							)
						)
					)
					(number "A44"
						(effects
							(font
								(size 1.27 1.27)
							)
						)
					)
				)
				(pin output line
					(at 33.02 -101.6 180)
					(length 3.81)
					(name "HSI7_p"
						(effects
							(font
								(size 1.27 1.27)
							)
						)
					)
					(number "A47"
						(effects
							(font
								(size 1.27 1.27)
							)
						)
					)
				)
				(pin output line
					(at 33.02 -104.14 180)
					(length 3.81)
					(name "HSI7_n"
						(effects
							(font
								(size 1.27 1.27)
							)
						)
					)
					(number "A48"
						(effects
							(font
								(size 1.27 1.27)
							)
						)
					)
				)
			)
		)
	(symbol "antmicroFPGAChips:XCAU25P-2FFVB676I"
			(exclude_from_sim no)
			(in_bom yes)
			(on_board yes)
			(property "Reference" "U"
				(at 63.5 0 0)
				(effects
					(font
						(size 1.27 1.27)
						(thickness 0.15)
					)
					(justify left bottom)
				)
			)
			(property "Value" "XCAU25P-2FFVB676I"
				(at 63.5 -5.08 0)
				(effects
					(font
						(size 1.27 1.27)
						(thickness 0.15)
					)
					(justify left bottom)
					(hide yes)
				)
			)
			(property "Footprint" "antmicro-footprints:BGA-676_27x27mm_Layout26x26_P1x1mm_FFVB676"
				(at 63.5 -7.62 0)
				(effects
					(font
						(size 1.27 1.27)
						(thickness 0.15)
					)
					(justify left bottom)
					(hide yes)
				)
			)
			(property "Datasheet" "https://docs.xilinx.com/viewer/book-attachment/2PXOpPtpaABIt0fkzeBLnw/hvbsEUaOT0OxFhln7VEVyA"
				(at 63.5 -10.16 0)
				(effects
					(font
						(size 1.27 1.27)
						(thickness 0.15)
					)
					(justify left bottom)
					(hide yes)
				)
			)
			(property "Description" "Artix UltraScale+ Field Programmable Gate Array"
				(at 0 0 0)
				(effects
					(font
						(size 1.27 1.27)
					)
					(hide yes)
				)
			)
			(property "MPN" "XCAU25P-2FFVB676I"
				(at 63.5 -2.54 0)
				(effects
					(font
						(size 1.27 1.27)
						(thickness 0.15)
					)
					(justify left bottom)
				)
			)
			(property "Manufacturer" "AMD-Xilinx"
				(at 63.5 -12.7 0)
				(effects
					(font
						(size 1.27 1.27)
						(thickness 0.15)
					)
					(justify left bottom)
					(hide yes)
				)
			)
			(property "Author" "Antmicro"
				(at 63.5 -15.24 0)
				(effects
					(font
						(size 1.27 1.27)
						(thickness 0.15)
					)
					(justify left bottom)
					(hide yes)
				)
			)
			(property "License" "Apache-2.0"
				(at 63.5 -17.78 0)
				(effects
					(font
						(size 1.27 1.27)
						(thickness 0.15)
					)
					(justify left bottom)
					(hide yes)
				)
			)
			(property "ki_locked" ""
				(at 0 0 0)
				(effects
					(font
						(size 1.27 1.27)
					)
				)
			)
			(property "ki_keywords" "FPGA, LVDS, MIPI, CMOS, BGA, ETHERNET, VIDEO, DSP, BRIDGE"
				(at 0 0 0)
				(effects
					(font
						(size 1.27 1.27)
					)
					(hide yes)
				)
			)
			(symbol "XCAU25P-2FFVB676I_1_1"
				(rectangle
					(start 5.08 2.54)
					(end 25.4 -87.63)
					(stroke
						(width 0.254)
						(type default)
					)
					(fill
						(type background)
					)
				)
				(polyline
					(pts
						(xy 15.24 -3.81) (xy 22.86 -3.81) (xy 22.86 -83.82) (xy 15.24 -83.82)
					)
					(stroke
						(width 0.254)
						(type default)
					)
					(fill
						(type background)
					)
				)
				(text "CFG"
					(at 15.24 -3.81 0)
					(effects
						(font
							(size 1.27 1.27)
							(thickness 0.15)
						)
						(justify left bottom)
					)
				)
				(text ""
					(at 50.8 -31.75 0)
					(effects
						(font
							(size 1.27 1.27)
							(thickness 0.15)
						)
						(justify left bottom)
					)
				)
				(text ""
					(at 50.8 -31.75 0)
					(effects
						(font
							(size 1.27 1.27)
							(thickness 0.15)
						)
						(justify left bottom)
					)
				)
				(pin power_in line
					(at 0 0 0)
					(length 5.08)
					(name "VCCO_0"
						(effects
							(font
								(size 1.27 1.27)
							)
						)
					)
					(number "AA11"
						(effects
							(font
								(size 1.27 1.27)
							)
						)
					)
				)
				(pin passive line
					(at 0 0 0)
					(length 5.08)
					(hide yes)
					(name "VCCO_0"
						(effects
							(font
								(size 1.27 1.27)
							)
						)
					)
					(number "AD12"
						(effects
							(font
								(size 1.27 1.27)
							)
						)
					)
				)
				(pin bidirectional line
					(at 0 -5.08 0)
					(length 5.08)
					(name "DONE_0"
						(effects
							(font
								(size 1.27 1.27)
							)
						)
					)
					(number "AB11"
						(effects
							(font
								(size 1.27 1.27)
							)
						)
					)
				)
				(pin bidirectional line
					(at 0 -7.62 0)
					(length 5.08)
					(name "INIT_B_0"
						(effects
							(font
								(size 1.27 1.27)
							)
						)
					)
					(number "W10"
						(effects
							(font
								(size 1.27 1.27)
							)
						)
					)
				)
				(pin input line
					(at 0 -10.16 0)
					(length 5.08)
					(name "PROGRAM_B_0"
						(effects
							(font
								(size 1.27 1.27)
							)
						)
					)
					(number "AB9"
						(effects
							(font
								(size 1.27 1.27)
							)
						)
					)
				)
				(pin bidirectional line
					(at 0 -12.7 0)
					(length 5.08)
					(name "RDWR_FCS_B_0"
						(effects
							(font
								(size 1.27 1.27)
							)
						)
					)
					(number "AA12"
						(effects
							(font
								(size 1.27 1.27)
							)
						)
					)
				)
				(pin bidirectional line
					(at 0 -17.78 0)
					(length 5.08)
					(name "CCLK_0"
						(effects
							(font
								(size 1.27 1.27)
							)
						)
					)
					(number "Y11"
						(effects
							(font
								(size 1.27 1.27)
							)
						)
					)
				)
				(pin input line
					(at 0 -20.32 0)
					(length 5.08)
					(name "M0_0"
						(effects
							(font
								(size 1.27 1.27)
							)
						)
					)
					(number "AA10"
						(effects
							(font
								(size 1.27 1.27)
							)
						)
					)
				)
				(pin input line
					(at 0 -22.86 0)
					(length 5.08)
					(name "M1_0"
						(effects
							(font
								(size 1.27 1.27)
							)
						)
					)
					(number "AA9"
						(effects
							(font
								(size 1.27 1.27)
							)
						)
					)
				)
				(pin input line
					(at 0 -25.4 0)
					(length 5.08)
					(name "M2_0"
						(effects
							(font
								(size 1.27 1.27)
							)
						)
					)
					(number "AF12"
						(effects
							(font
								(size 1.27 1.27)
							)
						)
					)
				)
				(pin input line
					(at 0 -30.48 0)
					(length 5.08)
					(name "TCK_0"
						(effects
							(font
								(size 1.27 1.27)
							)
						)
					)
					(number "AE12"
						(effects
							(font
								(size 1.27 1.27)
							)
						)
					)
				)
				(pin input line
					(at 0 -33.02 0)
					(length 5.08)
					(name "TDI_0"
						(effects
							(font
								(size 1.27 1.27)
							)
						)
					)
					(number "AB12"
						(effects
							(font
								(size 1.27 1.27)
							)
						)
					)
				)
				(pin output line
					(at 0 -35.56 0)
					(length 5.08)
					(name "TDO_0"
						(effects
							(font
								(size 1.27 1.27)
							)
						)
					)
					(number "Y10"
						(effects
							(font
								(size 1.27 1.27)
							)
						)
					)
				)
				(pin input line
					(at 0 -38.1 0)
					(length 5.08)
					(name "TMS_0"
						(effects
							(font
								(size 1.27 1.27)
							)
						)
					)
					(number "AB10"
						(effects
							(font
								(size 1.27 1.27)
							)
						)
					)
				)
				(pin bidirectional line
					(at 0 -43.18 0)
					(length 5.08)
					(name "D00_MOSI_0"
						(effects
							(font
								(size 1.27 1.27)
							)
						)
					)
					(number "AD11"
						(effects
							(font
								(size 1.27 1.27)
							)
						)
					)
				)
				(pin bidirectional line
					(at 0 -45.72 0)
					(length 5.08)
					(name "D01_DIN_0"
						(effects
							(font
								(size 1.27 1.27)
							)
						)
					)
					(number "AC12"
						(effects
							(font
								(size 1.27 1.27)
							)
						)
					)
				)
				(pin bidirectional line
					(at 0 -48.26 0)
					(length 5.08)
					(name "D02_0"
						(effects
							(font
								(size 1.27 1.27)
							)
						)
					)
					(number "AC11"
						(effects
							(font
								(size 1.27 1.27)
							)
						)
					)
				)
				(pin bidirectional line
					(at 0 -50.8 0)
					(length 5.08)
					(name "D03_0"
						(effects
							(font
								(size 1.27 1.27)
							)
						)
					)
					(number "AE11"
						(effects
							(font
								(size 1.27 1.27)
							)
						)
					)
				)
				(pin input line
					(at 0 -55.88 0)
					(length 5.08)
					(name "VP"
						(effects
							(font
								(size 1.27 1.27)
							)
						)
					)
					(number "P14"
						(effects
							(font
								(size 1.27 1.27)
							)
						)
					)
				)
				(pin input line
					(at 0 -58.42 0)
					(length 5.08)
					(name "VN"
						(effects
							(font
								(size 1.27 1.27)
							)
						)
					)
					(number "R13"
						(effects
							(font
								(size 1.27 1.27)
							)
						)
					)
				)
				(pin input line
					(at 0 -63.5 0)
					(length 5.08)
					(name "VREFP"
						(effects
							(font
								(size 1.27 1.27)
							)
						)
					)
					(number "R14"
						(effects
							(font
								(size 1.27 1.27)
							)
						)
					)
				)
				(pin input line
					(at 0 -66.04 0)
					(length 5.08)
					(name "VREFN"
						(effects
							(font
								(size 1.27 1.27)
							)
						)
					)
					(number "P13"
						(effects
							(font
								(size 1.27 1.27)
							)
						)
					)
				)
				(pin passive line
					(at 0 -71.12 0)
					(length 5.08)
					(name "DXP"
						(effects
							(font
								(size 1.27 1.27)
							)
						)
					)
					(number "T14"
						(effects
							(font
								(size 1.27 1.27)
							)
						)
					)
				)
				(pin passive line
					(at 0 -73.66 0)
					(length 5.08)
					(name "DXN"
						(effects
							(font
								(size 1.27 1.27)
							)
						)
					)
					(number "T13"
						(effects
							(font
								(size 1.27 1.27)
							)
						)
					)
				)
				(pin input line
					(at 0 -78.74 0)
					(length 5.08)
					(name "POR_OVERRIDE"
						(effects
							(font
								(size 1.27 1.27)
							)
						)
					)
					(number "Y12"
						(effects
							(font
								(size 1.27 1.27)
							)
						)
					)
				)
				(pin input line
					(at 0 -81.28 0)
					(length 5.08)
					(name "PUDC_B_0"
						(effects
							(font
								(size 1.27 1.27)
							)
						)
					)
					(number "W9"
						(effects
							(font
								(size 1.27 1.27)
							)
						)
					)
				)
			)
			(symbol "XCAU25P-2FFVB676I_2_1"
				(rectangle
					(start 5.08 2.54)
					(end 43.18 -142.24)
					(stroke
						(width 0.254)
						(type default)
					)
					(fill
						(type background)
					)
				)
				(polyline
					(pts
						(xy 30.48 -6.35) (xy 39.37 -6.35) (xy 39.37 -138.43) (xy 31.75 -138.43)
					)
					(stroke
						(width 0.254)
						(type default)
					)
					(fill
						(type background)
					)
				)
				(text "BANK 64"
					(at 30.48 -5.08 0)
					(effects
						(font
							(size 1.27 1.27)
							(thickness 0.15)
						)
						(justify left bottom)
					)
				)
				(text ""
					(at 50.8 -31.75 0)
					(effects
						(font
							(size 1.27 1.27)
							(thickness 0.15)
						)
						(justify left bottom)
					)
				)
				(text ""
					(at 50.8 -31.75 0)
					(effects
						(font
							(size 1.27 1.27)
							(thickness 0.15)
						)
						(justify left bottom)
					)
				)
				(pin power_in line
					(at 0 0 0)
					(length 5.08)
					(name "VCCO_64"
						(effects
							(font
								(size 1.27 1.27)
							)
						)
					)
					(number "AA21"
						(effects
							(font
								(size 1.27 1.27)
							)
						)
					)
				)
				(pin passive line
					(at 0 0 0)
					(length 5.08)
					(hide yes)
					(name "VCCO_64"
						(effects
							(font
								(size 1.27 1.27)
							)
						)
					)
					(number "AB18"
						(effects
							(font
								(size 1.27 1.27)
							)
						)
					)
				)
				(pin passive line
					(at 0 0 0)
					(length 5.08)
					(hide yes)
					(name "VCCO_64"
						(effects
							(font
								(size 1.27 1.27)
							)
						)
					)
					(number "AD22"
						(effects
							(font
								(size 1.27 1.27)
							)
						)
					)
				)
				(pin input line
					(at 0 -2.54 0)
					(length 5.08)
					(name "VREF_64"
						(effects
							(font
								(size 1.27 1.27)
							)
						)
					)
					(number "W18"
						(effects
							(font
								(size 1.27 1.27)
							)
						)
					)
				)
				(pin bidirectional line
					(at 0 -7.62 0)
					(length 5.08)
					(name "IO_L1P_T0L_N0_DBC_64"
						(effects
							(font
								(size 1.27 1.27)
							)
						)
					)
					(number "AE25"
						(effects
							(font
								(size 1.27 1.27)
							)
						)
					)
				)
				(pin bidirectional line
					(at 0 -10.16 0)
					(length 5.08)
					(name "IO_L1N_T0L_N1_DBC_64"
						(effects
							(font
								(size 1.27 1.27)
							)
						)
					)
					(number "AE26"
						(effects
							(font
								(size 1.27 1.27)
							)
						)
					)
				)
				(pin bidirectional line
					(at 0 -12.7 0)
					(length 5.08)
					(name "IO_L2P_T0L_N2_64"
						(effects
							(font
								(size 1.27 1.27)
							)
						)
					)
					(number "AB25"
						(effects
							(font
								(size 1.27 1.27)
							)
						)
					)
				)
				(pin bidirectional line
					(at 0 -15.24 0)
					(length 5.08)
					(name "IO_L2N_T0L_N3_64"
						(effects
							(font
								(size 1.27 1.27)
							)
						)
					)
					(number "AB26"
						(effects
							(font
								(size 1.27 1.27)
							)
						)
					)
				)
				(pin bidirectional line
					(at 0 -17.78 0)
					(length 5.08)
					(name "IO_L3P_T0L_N4_AD15P_64"
						(effects
							(font
								(size 1.27 1.27)
							)
						)
					)
					(number "AF24"
						(effects
							(font
								(size 1.27 1.27)
							)
						)
					)
				)
				(pin bidirectional line
					(at 0 -20.32 0)
					(length 5.08)
					(name "IO_L3N_T0L_N5_AD15N_64"
						(effects
							(font
								(size 1.27 1.27)
							)
						)
					)
					(number "AF25"
						(effects
							(font
								(size 1.27 1.27)
							)
						)
					)
				)
				(pin bidirectional line
					(at 0 -22.86 0)
					(length 5.08)
					(name "IO_L4P_T0U_N6_DBC_AD7P_64"
						(effects
							(font
								(size 1.27 1.27)
							)
						)
					)
					(number "AC26"
						(effects
							(font
								(size 1.27 1.27)
							)
						)
					)
				)
				(pin bidirectional line
					(at 0 -25.4 0)
					(length 5.08)
					(name "IO_L4N_T0U_N7_DBC_AD7N_64"
						(effects
							(font
								(size 1.27 1.27)
							)
						)
					)
					(number "AD26"
						(effects
							(font
								(size 1.27 1.27)
							)
						)
					)
				)
				(pin bidirectional line
					(at 0 -27.94 0)
					(length 5.08)
					(name "IO_L5P_T0U_N8_AD14P_64"
						(effects
							(font
								(size 1.27 1.27)
							)
						)
					)
					(number "AD24"
						(effects
							(font
								(size 1.27 1.27)
							)
						)
					)
				)
				(pin bidirectional line
					(at 0 -30.48 0)
					(length 5.08)
					(name "IO_L5N_T0U_N9_AD14N_64"
						(effects
							(font
								(size 1.27 1.27)
							)
						)
					)
					(number "AD25"
						(effects
							(font
								(size 1.27 1.27)
							)
						)
					)
				)
				(pin bidirectional line
					(at 0 -33.02 0)
					(length 5.08)
					(name "IO_L6P_T0U_N10_AD6P_64"
						(effects
							(font
								(size 1.27 1.27)
							)
						)
					)
					(number "AB24"
						(effects
							(font
								(size 1.27 1.27)
							)
						)
					)
				)
				(pin bidirectional line
					(at 0 -35.56 0)
					(length 5.08)
					(name "IO_L6N_T0U_N11_AD6N_64"
						(effects
							(font
								(size 1.27 1.27)
							)
						)
					)
					(number "AC24"
						(effects
							(font
								(size 1.27 1.27)
							)
						)
					)
				)
				(pin bidirectional line
					(at 0 -38.1 0)
					(length 5.08)
					(name "IO_T0U_N12_VRP_64"
						(effects
							(font
								(size 1.27 1.27)
							)
						)
					)
					(number "AF23"
						(effects
							(font
								(size 1.27 1.27)
							)
						)
					)
				)
				(pin bidirectional line
					(at 0 -40.64 0)
					(length 5.08)
					(name "IO_L7P_T1L_N0_QBC_AD13P_64"
						(effects
							(font
								(size 1.27 1.27)
							)
						)
					)
					(number "AE22"
						(effects
							(font
								(size 1.27 1.27)
							)
						)
					)
				)
				(pin bidirectional line
					(at 0 -43.18 0)
					(length 5.08)
					(name "IO_L7N_T1L_N1_QBC_AD13N_64"
						(effects
							(font
								(size 1.27 1.27)
							)
						)
					)
					(number "AF22"
						(effects
							(font
								(size 1.27 1.27)
							)
						)
					)
				)
				(pin bidirectional line
					(at 0 -45.72 0)
					(length 5.08)
					(name "IO_L8P_T1L_N2_AD5P_64"
						(effects
							(font
								(size 1.27 1.27)
							)
						)
					)
					(number "AD23"
						(effects
							(font
								(size 1.27 1.27)
							)
						)
					)
				)
				(pin bidirectional line
					(at 0 -48.26 0)
					(length 5.08)
					(name "IO_L8N_T1L_N3_AD5N_64"
						(effects
							(font
								(size 1.27 1.27)
							)
						)
					)
					(number "AE23"
						(effects
							(font
								(size 1.27 1.27)
							)
						)
					)
				)
				(pin bidirectional line
					(at 0 -50.8 0)
					(length 5.08)
					(name "IO_L9P_T1L_N4_AD12P_64"
						(effects
							(font
								(size 1.27 1.27)
							)
						)
					)
					(number "AC22"
						(effects
							(font
								(size 1.27 1.27)
							)
						)
					)
				)
				(pin bidirectional line
					(at 0 -53.34 0)
					(length 5.08)
					(name "IO_L9N_T1L_N5_AD12N_64"
						(effects
							(font
								(size 1.27 1.27)
							)
						)
					)
					(number "AC23"
						(effects
							(font
								(size 1.27 1.27)
							)
						)
					)
				)
				(pin bidirectional line
					(at 0 -55.88 0)
					(length 5.08)
					(name "IO_L10P_T1U_N6_QBC_AD4P_64"
						(effects
							(font
								(size 1.27 1.27)
							)
						)
					)
					(number "AA22"
						(effects
							(font
								(size 1.27 1.27)
							)
						)
					)
				)
				(pin bidirectional line
					(at 0 -58.42 0)
					(length 5.08)
					(name "IO_L10N_T1U_N7_QBC_AD4N_64"
						(effects
							(font
								(size 1.27 1.27)
							)
						)
					)
					(number "AB22"
						(effects
							(font
								(size 1.27 1.27)
							)
						)
					)
				)
				(pin bidirectional line
					(at 0 -60.96 0)
					(length 5.08)
					(name "IO_L11P_T1U_N8_GC_64"
						(effects
							(font
								(size 1.27 1.27)
							)
						)
					)
					(number "AD21"
						(effects
							(font
								(size 1.27 1.27)
							)
						)
					)
				)
				(pin bidirectional line
					(at 0 -63.5 0)
					(length 5.08)
					(name "IO_L11N_T1U_N9_GC_64"
						(effects
							(font
								(size 1.27 1.27)
							)
						)
					)
					(number "AE21"
						(effects
							(font
								(size 1.27 1.27)
							)
						)
					)
				)
				(pin bidirectional line
					(at 0 -66.04 0)
					(length 5.08)
					(name "IO_L12P_T1U_N10_GC_64"
						(effects
							(font
								(size 1.27 1.27)
							)
						)
					)
					(number "AB21"
						(effects
							(font
								(size 1.27 1.27)
							)
						)
					)
				)
				(pin bidirectional line
					(at 0 -68.58 0)
					(length 5.08)
					(name "IO_L12N_T1U_N11_GC_64"
						(effects
							(font
								(size 1.27 1.27)
							)
						)
					)
					(number "AC21"
						(effects
							(font
								(size 1.27 1.27)
							)
						)
					)
				)
				(pin bidirectional line
					(at 0 -71.12 0)
					(length 5.08)
					(name "IO_T1U_N12_64"
						(effects
							(font
								(size 1.27 1.27)
							)
						)
					)
					(number "AF20"
						(effects
							(font
								(size 1.27 1.27)
							)
						)
					)
				)
				(pin bidirectional line
					(at 0 -73.66 0)
					(length 5.08)
					(name "IO_L13P_T2L_N0_GC_QBC_64"
						(effects
							(font
								(size 1.27 1.27)
							)
						)
					)
					(number "AD20"
						(effects
							(font
								(size 1.27 1.27)
							)
						)
					)
				)
				(pin bidirectional line
					(at 0 -76.2 0)
					(length 5.08)
					(name "IO_L13N_T2L_N1_GC_QBC_64"
						(effects
							(font
								(size 1.27 1.27)
							)
						)
					)
					(number "AE20"
						(effects
							(font
								(size 1.27 1.27)
							)
						)
					)
				)
				(pin bidirectional line
					(at 0 -78.74 0)
					(length 5.08)
					(name "IO_L14P_T2L_N2_GC_64"
						(effects
							(font
								(size 1.27 1.27)
							)
						)
					)
					(number "AC19"
						(effects
							(font
								(size 1.27 1.27)
							)
						)
					)
				)
				(pin bidirectional line
					(at 0 -81.28 0)
					(length 5.08)
					(name "IO_L14N_T2L_N3_GC_64"
						(effects
							(font
								(size 1.27 1.27)
							)
						)
					)
					(number "AD19"
						(effects
							(font
								(size 1.27 1.27)
							)
						)
					)
				)
				(pin bidirectional line
					(at 0 -83.82 0)
					(length 5.08)
					(name "IO_L15P_T2L_N4_AD11P_64"
						(effects
							(font
								(size 1.27 1.27)
							)
						)
					)
					(number "AF18"
						(effects
							(font
								(size 1.27 1.27)
							)
						)
					)
				)
				(pin bidirectional line
					(at 0 -86.36 0)
					(length 5.08)
					(name "IO_L15N_T2L_N5_AD11N_64"
						(effects
							(font
								(size 1.27 1.27)
							)
						)
					)
					(number "AF19"
						(effects
							(font
								(size 1.27 1.27)
							)
						)
					)
				)
				(pin bidirectional line
					(at 0 -88.9 0)
					(length 5.08)
					(name "IO_L16P_T2U_N6_QBC_AD3P_64"
						(effects
							(font
								(size 1.27 1.27)
							)
						)
					)
					(number "AC18"
						(effects
							(font
								(size 1.27 1.27)
							)
						)
					)
				)
				(pin bidirectional line
					(at 0 -91.44 0)
					(length 5.08)
					(name "IO_L16N_T2U_N7_QBC_AD3N_64"
						(effects
							(font
								(size 1.27 1.27)
							)
						)
					)
					(number "AD18"
						(effects
							(font
								(size 1.27 1.27)
							)
						)
					)
				)
				(pin bidirectional line
					(at 0 -93.98 0)
					(length 5.08)
					(name "IO_L17P_T2U_N8_AD10P_64"
						(effects
							(font
								(size 1.27 1.27)
							)
						)
					)
					(number "AE17"
						(effects
							(font
								(size 1.27 1.27)
							)
						)
					)
				)
				(pin bidirectional line
					(at 0 -96.52 0)
					(length 5.08)
					(name "IO_L17N_T2U_N9_AD10N_64"
						(effects
							(font
								(size 1.27 1.27)
							)
						)
					)
					(number "AF17"
						(effects
							(font
								(size 1.27 1.27)
							)
						)
					)
				)
				(pin bidirectional line
					(at 0 -99.06 0)
					(length 5.08)
					(name "IO_L18P_T2U_N10_AD2P_64"
						(effects
							(font
								(size 1.27 1.27)
							)
						)
					)
					(number "AD16"
						(effects
							(font
								(size 1.27 1.27)
							)
						)
					)
				)
				(pin bidirectional line
					(at 0 -101.6 0)
					(length 5.08)
					(name "IO_L18N_T2U_N11_AD2N_64"
						(effects
							(font
								(size 1.27 1.27)
							)
						)
					)
					(number "AE16"
						(effects
							(font
								(size 1.27 1.27)
							)
						)
					)
				)
				(pin bidirectional line
					(at 0 -104.14 0)
					(length 5.08)
					(name "IO_T2U_N12_64"
						(effects
							(font
								(size 1.27 1.27)
							)
						)
					)
					(number "AE18"
						(effects
							(font
								(size 1.27 1.27)
							)
						)
					)
				)
				(pin bidirectional line
					(at 0 -106.68 0)
					(length 5.08)
					(name "IO_L19P_T3L_N0_DBC_AD9P_64"
						(effects
							(font
								(size 1.27 1.27)
							)
						)
					)
					(number "Y20"
						(effects
							(font
								(size 1.27 1.27)
							)
						)
					)
				)
				(pin bidirectional line
					(at 0 -109.22 0)
					(length 5.08)
					(name "IO_L19N_T3L_N1_DBC_AD9N_64"
						(effects
							(font
								(size 1.27 1.27)
							)
						)
					)
					(number "Y21"
						(effects
							(font
								(size 1.27 1.27)
							)
						)
					)
				)
				(pin bidirectional line
					(at 0 -111.76 0)
					(length 5.08)
					(name "IO_L20P_T3L_N2_AD1P_64"
						(effects
							(font
								(size 1.27 1.27)
							)
						)
					)
					(number "AA19"
						(effects
							(font
								(size 1.27 1.27)
							)
						)
					)
				)
				(pin bidirectional line
					(at 0 -114.3 0)
					(length 5.08)
					(name "IO_L20N_T3L_N3_AD1N_64"
						(effects
							(font
								(size 1.27 1.27)
							)
						)
					)
					(number "AB19"
						(effects
							(font
								(size 1.27 1.27)
							)
						)
					)
				)
				(pin bidirectional line
					(at 0 -116.84 0)
					(length 5.08)
					(name "IO_L21P_T3L_N4_AD8P_64"
						(effects
							(font
								(size 1.27 1.27)
							)
						)
					)
					(number "AA20"
						(effects
							(font
								(size 1.27 1.27)
							)
						)
					)
				)
				(pin bidirectional line
					(at 0 -119.38 0)
					(length 5.08)
					(name "IO_L21N_T3L_N5_AD8N_64"
						(effects
							(font
								(size 1.27 1.27)
							)
						)
					)
					(number "AB20"
						(effects
							(font
								(size 1.27 1.27)
							)
						)
					)
				)
				(pin bidirectional line
					(at 0 -121.92 0)
					(length 5.08)
					(name "IO_L22P_T3U_N6_DBC_AD0P_64"
						(effects
							(font
								(size 1.27 1.27)
							)
						)
					)
					(number "AB17"
						(effects
							(font
								(size 1.27 1.27)
							)
						)
					)
				)
				(pin bidirectional line
					(at 0 -124.46 0)
					(length 5.08)
					(name "IO_L22N_T3U_N7_DBC_AD0N_64"
						(effects
							(font
								(size 1.27 1.27)
							)
						)
					)
					(number "AC17"
						(effects
							(font
								(size 1.27 1.27)
							)
						)
					)
				)
				(pin bidirectional line
					(at 0 -127 0)
					(length 5.08)
					(name "IO_L23P_T3U_N8_64"
						(effects
							(font
								(size 1.27 1.27)
							)
						)
					)
					(number "Y17"
						(effects
							(font
								(size 1.27 1.27)
							)
						)
					)
				)
				(pin bidirectional line
					(at 0 -129.54 0)
					(length 5.08)
					(name "IO_L23N_T3U_N9_64"
						(effects
							(font
								(size 1.27 1.27)
							)
						)
					)
					(number "AA17"
						(effects
							(font
								(size 1.27 1.27)
							)
						)
					)
				)
				(pin bidirectional line
					(at 0 -132.08 0)
					(length 5.08)
					(name "IO_L24P_T3U_N10_64"
						(effects
							(font
								(size 1.27 1.27)
							)
						)
					)
					(number "Y18"
						(effects
							(font
								(size 1.27 1.27)
							)
						)
					)
				)
				(pin bidirectional line
					(at 0 -134.62 0)
					(length 5.08)
					(name "IO_L24N_T3U_N11_64"
						(effects
							(font
								(size 1.27 1.27)
							)
						)
					)
					(number "AA18"
						(effects
							(font
								(size 1.27 1.27)
							)
						)
					)
				)
				(pin bidirectional line
					(at 0 -137.16 0)
					(length 5.08)
					(name "IO_T3U_N12_64"
						(effects
							(font
								(size 1.27 1.27)
							)
						)
					)
					(number "AC16"
						(effects
							(font
								(size 1.27 1.27)
							)
						)
					)
				)
			)
			(symbol "XCAU25P-2FFVB676I_3_1"
				(rectangle
					(start 5.08 2.54)
					(end 50.8 -142.24)
					(stroke
						(width 0.254)
						(type default)
					)
					(fill
						(type background)
					)
				)
				(polyline
					(pts
						(xy 36.83 -5.08) (xy 44.45 -5.08) (xy 44.45 -138.43) (xy 36.83 -138.43)
					)
					(stroke
						(width 0.254)
						(type default)
					)
					(fill
						(type background)
					)
				)
				(text "BANK 65"
					(at 36.83 -3.81 0)
					(effects
						(font
							(size 1.27 1.27)
							(thickness 0.15)
						)
						(justify left bottom)
					)
				)
				(text ""
					(at 50.8 -31.75 0)
					(effects
						(font
							(size 1.27 1.27)
							(thickness 0.15)
						)
						(justify left bottom)
					)
				)
				(text ""
					(at 50.8 -31.75 0)
					(effects
						(font
							(size 1.27 1.27)
							(thickness 0.15)
						)
						(justify left bottom)
					)
				)
				(pin power_in line
					(at 0 0 0)
					(length 5.08)
					(name "VCCO_65"
						(effects
							(font
								(size 1.27 1.27)
							)
						)
					)
					(number "P22"
						(effects
							(font
								(size 1.27 1.27)
							)
						)
					)
				)
				(pin passive line
					(at 0 0 0)
					(length 5.08)
					(hide yes)
					(name "VCCO_65"
						(effects
							(font
								(size 1.27 1.27)
							)
						)
					)
					(number "U23"
						(effects
							(font
								(size 1.27 1.27)
							)
						)
					)
				)
				(pin passive line
					(at 0 0 0)
					(length 5.08)
					(hide yes)
					(name "VCCO_65"
						(effects
							(font
								(size 1.27 1.27)
							)
						)
					)
					(number "Y24"
						(effects
							(font
								(size 1.27 1.27)
							)
						)
					)
				)
				(pin input line
					(at 0 -2.54 0)
					(length 5.08)
					(name "VREF_65"
						(effects
							(font
								(size 1.27 1.27)
							)
						)
					)
					(number "V18"
						(effects
							(font
								(size 1.27 1.27)
							)
						)
					)
				)
				(pin bidirectional line
					(at 0 -7.62 0)
					(length 5.08)
					(name "IO_L1P_T0L_N0_DBC_RS0_65"
						(effects
							(font
								(size 1.27 1.27)
							)
						)
					)
					(number "U19"
						(effects
							(font
								(size 1.27 1.27)
							)
						)
					)
				)
				(pin bidirectional line
					(at 0 -10.16 0)
					(length 5.08)
					(name "IO_L1N_T0L_N1_DBC_RS1_65"
						(effects
							(font
								(size 1.27 1.27)
							)
						)
					)
					(number "V19"
						(effects
							(font
								(size 1.27 1.27)
							)
						)
					)
				)
				(pin bidirectional line
					(at 0 -12.7 0)
					(length 5.08)
					(name "IO_L2P_T0L_N2_FOE_B_65"
						(effects
							(font
								(size 1.27 1.27)
							)
						)
					)
					(number "U21"
						(effects
							(font
								(size 1.27 1.27)
							)
						)
					)
				)
				(pin bidirectional line
					(at 0 -15.24 0)
					(length 5.08)
					(name "IO_L2N_T0L_N3_FWE_FCS2_B_65"
						(effects
							(font
								(size 1.27 1.27)
							)
						)
					)
					(number "U22"
						(effects
							(font
								(size 1.27 1.27)
							)
						)
					)
				)
				(pin bidirectional line
					(at 0 -17.78 0)
					(length 5.08)
					(name "IO_L3P_T0L_N4_AD15P_A26_65"
						(effects
							(font
								(size 1.27 1.27)
							)
						)
					)
					(number "T20"
						(effects
							(font
								(size 1.27 1.27)
							)
						)
					)
				)
				(pin bidirectional line
					(at 0 -20.32 0)
					(length 5.08)
					(name "IO_L3N_T0L_N5_AD15N_A27_65"
						(effects
							(font
								(size 1.27 1.27)
							)
						)
					)
					(number "U20"
						(effects
							(font
								(size 1.27 1.27)
							)
						)
					)
				)
				(pin bidirectional line
					(at 0 -22.86 0)
					(length 5.08)
					(name "IO_L4P_T0U_N6_DBC_AD7P_A24_65"
						(effects
							(font
								(size 1.27 1.27)
							)
						)
					)
					(number "V21"
						(effects
							(font
								(size 1.27 1.27)
							)
						)
					)
				)
				(pin bidirectional line
					(at 0 -25.4 0)
					(length 5.08)
					(name "IO_L4N_T0U_N7_DBC_AD7N_A25_65"
						(effects
							(font
								(size 1.27 1.27)
							)
						)
					)
					(number "V22"
						(effects
							(font
								(size 1.27 1.27)
							)
						)
					)
				)
				(pin bidirectional line
					(at 0 -27.94 0)
					(length 5.08)
					(name "IO_L5P_T0U_N8_AD14P_A22_65"
						(effects
							(font
								(size 1.27 1.27)
							)
						)
					)
					(number "T22"
						(effects
							(font
								(size 1.27 1.27)
							)
						)
					)
				)
				(pin bidirectional line
					(at 0 -30.48 0)
					(length 5.08)
					(name "IO_L5N_T0U_N9_AD14N_A23_65"
						(effects
							(font
								(size 1.27 1.27)
							)
						)
					)
					(number "T23"
						(effects
							(font
								(size 1.27 1.27)
							)
						)
					)
				)
				(pin bidirectional line
					(at 0 -33.02 0)
					(length 5.08)
					(name "IO_L6P_T0U_N10_AD6P_A20_65"
						(effects
							(font
								(size 1.27 1.27)
							)
						)
					)
					(number "W19"
						(effects
							(font
								(size 1.27 1.27)
							)
						)
					)
				)
				(pin bidirectional line
					(at 0 -35.56 0)
					(length 5.08)
					(name "IO_L6N_T0U_N11_AD6N_A21_65"
						(effects
							(font
								(size 1.27 1.27)
							)
						)
					)
					(number "W20"
						(effects
							(font
								(size 1.27 1.27)
							)
						)
					)
				)
				(pin bidirectional line
					(at 0 -38.1 0)
					(length 5.08)
					(name "IO_T0U_N12_VRP_A28_65"
						(effects
							(font
								(size 1.27 1.27)
							)
						)
					)
					(number "W21"
						(effects
							(font
								(size 1.27 1.27)
							)
						)
					)
				)
				(pin bidirectional line
					(at 0 -40.64 0)
					(length 5.08)
					(name "IO_L7P_T1L_N0_QBC_AD13P_A18_65"
						(effects
							(font
								(size 1.27 1.27)
							)
						)
					)
					(number "Y22"
						(effects
							(font
								(size 1.27 1.27)
							)
						)
					)
				)
				(pin bidirectional line
					(at 0 -43.18 0)
					(length 5.08)
					(name "IO_L7N_T1L_N1_QBC_AD13N_A19_65"
						(effects
							(font
								(size 1.27 1.27)
							)
						)
					)
					(number "Y23"
						(effects
							(font
								(size 1.27 1.27)
							)
						)
					)
				)
				(pin bidirectional line
					(at 0 -45.72 0)
					(length 5.08)
					(name "IO_L8P_T1L_N2_AD5P_A16_65"
						(effects
							(font
								(size 1.27 1.27)
							)
						)
					)
					(number "Y25"
						(effects
							(font
								(size 1.27 1.27)
							)
						)
					)
				)
				(pin bidirectional line
					(at 0 -48.26 0)
					(length 5.08)
					(name "IO_L8N_T1L_N3_AD5N_A17_65"
						(effects
							(font
								(size 1.27 1.27)
							)
						)
					)
					(number "Y26"
						(effects
							(font
								(size 1.27 1.27)
							)
						)
					)
				)
				(pin bidirectional line
					(at 0 -50.8 0)
					(length 5.08)
					(name "IO_L9P_T1L_N4_AD12P_A14_D30_65"
						(effects
							(font
								(size 1.27 1.27)
							)
						)
					)
					(number "AA24"
						(effects
							(font
								(size 1.27 1.27)
							)
						)
					)
				)
				(pin bidirectional line
					(at 0 -53.34 0)
					(length 5.08)
					(name "IO_L9N_T1L_N5_AD12N_A15_D31_65"
						(effects
							(font
								(size 1.27 1.27)
							)
						)
					)
					(number "AA25"
						(effects
							(font
								(size 1.27 1.27)
							)
						)
					)
				)
				(pin bidirectional line
					(at 0 -55.88 0)
					(length 5.08)
					(name "IO_L10P_T1U_N6_QBC_AD4P_A12_D28_65"
						(effects
							(font
								(size 1.27 1.27)
							)
						)
					)
					(number "W25"
						(effects
							(font
								(size 1.27 1.27)
							)
						)
					)
				)
				(pin bidirectional line
					(at 0 -58.42 0)
					(length 5.08)
					(name "IO_L10N_T1U_N7_QBC_AD4N_A13_D29_65"
						(effects
							(font
								(size 1.27 1.27)
							)
						)
					)
					(number "W26"
						(effects
							(font
								(size 1.27 1.27)
							)
						)
					)
				)
				(pin bidirectional line
					(at 0 -60.96 0)
					(length 5.08)
					(name "IO_L11P_T1U_N8_GC_A10_D26_65"
						(effects
							(font
								(size 1.27 1.27)
							)
						)
					)
					(number "V23"
						(effects
							(font
								(size 1.27 1.27)
							)
						)
					)
				)
				(pin bidirectional line
					(at 0 -63.5 0)
					(length 5.08)
					(name "IO_L11N_T1U_N9_GC_A11_D27_65"
						(effects
							(font
								(size 1.27 1.27)
							)
						)
					)
					(number "W23"
						(effects
							(font
								(size 1.27 1.27)
							)
						)
					)
				)
				(pin bidirectional line
					(at 0 -66.04 0)
					(length 5.08)
					(name "IO_L12P_T1U_N10_GC_A08_D24_65"
						(effects
							(font
								(size 1.27 1.27)
							)
						)
					)
					(number "V24"
						(effects
							(font
								(size 1.27 1.27)
							)
						)
					)
				)
				(pin bidirectional line
					(at 0 -68.58 0)
					(length 5.08)
					(name "IO_L12N_T1U_N11_GC_A09_D25_65"
						(effects
							(font
								(size 1.27 1.27)
							)
						)
					)
					(number "W24"
						(effects
							(font
								(size 1.27 1.27)
							)
						)
					)
				)
				(pin bidirectional line
					(at 0 -71.12 0)
					(length 5.08)
					(name "IO_T1U_N12_SMBALERT_65"
						(effects
							(font
								(size 1.27 1.27)
							)
						)
					)
					(number "AA23"
						(effects
							(font
								(size 1.27 1.27)
							)
						)
					)
				)
				(pin bidirectional line
					(at 0 -73.66 0)
					(length 5.08)
					(name "IO_L13P_T2L_N0_GC_QBC_A06_D22_65"
						(effects
							(font
								(size 1.27 1.27)
							)
						)
					)
					(number "T24"
						(effects
							(font
								(size 1.27 1.27)
							)
						)
					)
				)
				(pin bidirectional line
					(at 0 -76.2 0)
					(length 5.08)
					(name "IO_L13N_T2L_N1_GC_QBC_A07_D23_65"
						(effects
							(font
								(size 1.27 1.27)
							)
						)
					)
					(number "U24"
						(effects
							(font
								(size 1.27 1.27)
							)
						)
					)
				)
				(pin bidirectional line
					(at 0 -78.74 0)
					(length 5.08)
					(name "IO_L14P_T2L_N2_GC_A04_D20_65"
						(effects
							(font
								(size 1.27 1.27)
							)
						)
					)
					(number "T25"
						(effects
							(font
								(size 1.27 1.27)
							)
						)
					)
				)
				(pin bidirectional line
					(at 0 -81.28 0)
					(length 5.08)
					(name "IO_L14N_T2L_N3_GC_A05_D21_65"
						(effects
							(font
								(size 1.27 1.27)
							)
						)
					)
					(number "U25"
						(effects
							(font
								(size 1.27 1.27)
							)
						)
					)
				)
				(pin bidirectional line
					(at 0 -83.82 0)
					(length 5.08)
					(name "IO_L15P_T2L_N4_AD11P_A02_D18_65"
						(effects
							(font
								(size 1.27 1.27)
							)
						)
					)
					(number "N24"
						(effects
							(font
								(size 1.27 1.27)
							)
						)
					)
				)
				(pin bidirectional line
					(at 0 -86.36 0)
					(length 5.08)
					(name "IO_L15N_T2L_N5_AD11N_A03_D19_65"
						(effects
							(font
								(size 1.27 1.27)
							)
						)
					)
					(number "P24"
						(effects
							(font
								(size 1.27 1.27)
							)
						)
					)
				)
				(pin bidirectional line
					(at 0 -88.9 0)
					(length 5.08)
					(name "IO_L16P_T2U_N6_QBC_AD3P_A00_D16_65"
						(effects
							(font
								(size 1.27 1.27)
							)
						)
					)
					(number "U26"
						(effects
							(font
								(size 1.27 1.27)
							)
						)
					)
				)
				(pin bidirectional line
					(at 0 -91.44 0)
					(length 5.08)
					(name "IO_L16N_T2U_N7_QBC_AD3N_A01_D17_65"
						(effects
							(font
								(size 1.27 1.27)
							)
						)
					)
					(number "V26"
						(effects
							(font
								(size 1.27 1.27)
							)
						)
					)
				)
				(pin bidirectional line
					(at 0 -93.98 0)
					(length 5.08)
					(name "IO_L17P_T2U_N8_AD10P_D14_65"
						(effects
							(font
								(size 1.27 1.27)
							)
						)
					)
					(number "P25"
						(effects
							(font
								(size 1.27 1.27)
							)
						)
					)
				)
				(pin bidirectional line
					(at 0 -96.52 0)
					(length 5.08)
					(name "IO_L17N_T2U_N9_AD10N_D15_65"
						(effects
							(font
								(size 1.27 1.27)
							)
						)
					)
					(number "P26"
						(effects
							(font
								(size 1.27 1.27)
							)
						)
					)
				)
				(pin bidirectional line
					(at 0 -99.06 0)
					(length 5.08)
					(name "IO_L18P_T2U_N10_AD2P_D12_65"
						(effects
							(font
								(size 1.27 1.27)
							)
						)
					)
					(number "R25"
						(effects
							(font
								(size 1.27 1.27)
							)
						)
					)
				)
				(pin bidirectional line
					(at 0 -101.6 0)
					(length 5.08)
					(name "IO_L18N_T2U_N11_AD2N_D13_65"
						(effects
							(font
								(size 1.27 1.27)
							)
						)
					)
					(number "R26"
						(effects
							(font
								(size 1.27 1.27)
							)
						)
					)
				)
				(pin bidirectional line
					(at 0 -104.14 0)
					(length 5.08)
					(name "IO_T2U_N12_CSI_ADV_B_65"
						(effects
							(font
								(size 1.27 1.27)
							)
						)
					)
					(number "N26"
						(effects
							(font
								(size 1.27 1.27)
							)
						)
					)
				)
				(pin bidirectional line
					(at 0 -106.68 0)
					(length 5.08)
					(name "IO_L19P_T3L_N0_DBC_AD9P_D10_65"
						(effects
							(font
								(size 1.27 1.27)
							)
						)
					)
					(number "R22"
						(effects
							(font
								(size 1.27 1.27)
							)
						)
					)
				)
				(pin bidirectional line
					(at 0 -109.22 0)
					(length 5.08)
					(name "IO_L19N_T3L_N1_DBC_AD9N_D11_65"
						(effects
							(font
								(size 1.27 1.27)
							)
						)
					)
					(number "R23"
						(effects
							(font
								(size 1.27 1.27)
							)
						)
					)
				)
				(pin bidirectional line
					(at 0 -111.76 0)
					(length 5.08)
					(name "IO_L20P_T3L_N2_AD1P_D08_65"
						(effects
							(font
								(size 1.27 1.27)
							)
						)
					)
					(number "P20"
						(effects
							(font
								(size 1.27 1.27)
							)
						)
					)
				)
				(pin bidirectional line
					(at 0 -114.3 0)
					(length 5.08)
					(name "IO_L20N_T3L_N3_AD1N_D09_65"
						(effects
							(font
								(size 1.27 1.27)
							)
						)
					)
					(number "P21"
						(effects
							(font
								(size 1.27 1.27)
							)
						)
					)
				)
				(pin bidirectional line
					(at 0 -116.84 0)
					(length 5.08)
					(name "IO_L21P_T3L_N4_AD8P_D06_65"
						(effects
							(font
								(size 1.27 1.27)
							)
						)
					)
					(number "R20"
						(effects
							(font
								(size 1.27 1.27)
							)
						)
					)
				)
				(pin bidirectional line
					(at 0 -119.38 0)
					(length 5.08)
					(name "IO_L21N_T3L_N5_AD8N_D07_65"
						(effects
							(font
								(size 1.27 1.27)
							)
						)
					)
					(number "R21"
						(effects
							(font
								(size 1.27 1.27)
							)
						)
					)
				)
				(pin bidirectional line
					(at 0 -121.92 0)
					(length 5.08)
					(name "IO_L22P_T3U_N6_DBC_AD0P_D04_65"
						(effects
							(font
								(size 1.27 1.27)
							)
						)
					)
					(number "N23"
						(effects
							(font
								(size 1.27 1.27)
							)
						)
					)
				)
				(pin bidirectional line
					(at 0 -124.46 0)
					(length 5.08)
					(name "IO_L22N_T3U_N7_DBC_AD0N_D05_65"
						(effects
							(font
								(size 1.27 1.27)
							)
						)
					)
					(number "P23"
						(effects
							(font
								(size 1.27 1.27)
							)
						)
					)
				)
				(pin bidirectional line
					(at 0 -127 0)
					(length 5.08)
					(name "IO_L23P_T3U_N8_I2C_SCLK_65"
						(effects
							(font
								(size 1.27 1.27)
							)
						)
					)
					(number "N19"
						(effects
							(font
								(size 1.27 1.27)
							)
						)
					)
				)
				(pin bidirectional line
					(at 0 -129.54 0)
					(length 5.08)
					(name "IO_L23N_T3U_N9_PERSTN1_I2C_SDA_65"
						(effects
							(font
								(size 1.27 1.27)
							)
						)
					)
					(number "P19"
						(effects
							(font
								(size 1.27 1.27)
							)
						)
					)
				)
				(pin bidirectional line
					(at 0 -132.08 0)
					(length 5.08)
					(name "IO_L24P_T3U_N10_EMCCLK_65"
						(effects
							(font
								(size 1.27 1.27)
							)
						)
					)
					(number "N21"
						(effects
							(font
								(size 1.27 1.27)
							)
						)
					)
				)
				(pin bidirectional line
					(at 0 -134.62 0)
					(length 5.08)
					(name "IO_L24N_T3U_N11_DOUT_CSO_B_65"
						(effects
							(font
								(size 1.27 1.27)
							)
						)
					)
					(number "N22"
						(effects
							(font
								(size 1.27 1.27)
							)
						)
					)
				)
				(pin bidirectional line
					(at 0 -137.16 0)
					(length 5.08)
					(name "IO_T3U_N12_PERSTN0_65"
						(effects
							(font
								(size 1.27 1.27)
							)
						)
					)
					(number "T19"
						(effects
							(font
								(size 1.27 1.27)
							)
						)
					)
				)
			)
			(symbol "XCAU25P-2FFVB676I_4_1"
				(rectangle
					(start 5.08 2.54)
					(end 43.18 -142.24)
					(stroke
						(width 0.254)
						(type default)
					)
					(fill
						(type background)
					)
				)
				(polyline
					(pts
						(xy 30.48 -6.35) (xy 39.37 -6.35) (xy 39.37 -138.43) (xy 31.75 -138.43)
					)
					(stroke
						(width 0.254)
						(type default)
					)
					(fill
						(type background)
					)
				)
				(text "BANK 66"
					(at 30.48 -5.08 0)
					(effects
						(font
							(size 1.27 1.27)
							(thickness 0.15)
						)
						(justify left bottom)
					)
				)
				(text ""
					(at 50.8 -31.75 0)
					(effects
						(font
							(size 1.27 1.27)
							(thickness 0.15)
						)
						(justify left bottom)
					)
				)
				(text ""
					(at 50.8 -31.75 0)
					(effects
						(font
							(size 1.27 1.27)
							(thickness 0.15)
						)
						(justify left bottom)
					)
				)
				(pin power_in line
					(at 0 0 0)
					(length 5.08)
					(name "VCCO_66"
						(effects
							(font
								(size 1.27 1.27)
							)
						)
					)
					(number "E24"
						(effects
							(font
								(size 1.27 1.27)
							)
						)
					)
				)
				(pin passive line
					(at 0 0 0)
					(length 5.08)
					(hide yes)
					(name "VCCO_66"
						(effects
							(font
								(size 1.27 1.27)
							)
						)
					)
					(number "H25"
						(effects
							(font
								(size 1.27 1.27)
							)
						)
					)
				)
				(pin passive line
					(at 0 0 0)
					(length 5.08)
					(hide yes)
					(name "VCCO_66"
						(effects
							(font
								(size 1.27 1.27)
							)
						)
					)
					(number "J22"
						(effects
							(font
								(size 1.27 1.27)
							)
						)
					)
				)
				(pin input line
					(at 0 -2.54 0)
					(length 5.08)
					(name "VREF_66"
						(effects
							(font
								(size 1.27 1.27)
							)
						)
					)
					(number "J18"
						(effects
							(font
								(size 1.27 1.27)
							)
						)
					)
				)
				(pin bidirectional line
					(at 0 -7.62 0)
					(length 5.08)
					(name "IO_L1P_T0L_N0_DBC_66"
						(effects
							(font
								(size 1.27 1.27)
							)
						)
					)
					(number "L18"
						(effects
							(font
								(size 1.27 1.27)
							)
						)
					)
				)
				(pin bidirectional line
					(at 0 -10.16 0)
					(length 5.08)
					(name "IO_L1N_T0L_N1_DBC_66"
						(effects
							(font
								(size 1.27 1.27)
							)
						)
					)
					(number "K18"
						(effects
							(font
								(size 1.27 1.27)
							)
						)
					)
				)
				(pin bidirectional line
					(at 0 -12.7 0)
					(length 5.08)
					(name "IO_L2P_T0L_N2_66"
						(effects
							(font
								(size 1.27 1.27)
							)
						)
					)
					(number "M20"
						(effects
							(font
								(size 1.27 1.27)
							)
						)
					)
				)
				(pin bidirectional line
					(at 0 -15.24 0)
					(length 5.08)
					(name "IO_L2N_T0L_N3_66"
						(effects
							(font
								(size 1.27 1.27)
							)
						)
					)
					(number "M21"
						(effects
							(font
								(size 1.27 1.27)
							)
						)
					)
				)
				(pin bidirectional line
					(at 0 -17.78 0)
					(length 5.08)
					(name "IO_L3P_T0L_N4_AD15P_66"
						(effects
							(font
								(size 1.27 1.27)
							)
						)
					)
					(number "J19"
						(effects
							(font
								(size 1.27 1.27)
							)
						)
					)
				)
				(pin bidirectional line
					(at 0 -20.32 0)
					(length 5.08)
					(name "IO_L3N_T0L_N5_AD15N_66"
						(effects
							(font
								(size 1.27 1.27)
							)
						)
					)
					(number "J20"
						(effects
							(font
								(size 1.27 1.27)
							)
						)
					)
				)
				(pin bidirectional line
					(at 0 -22.86 0)
					(length 5.08)
					(name "IO_L4P_T0U_N6_DBC_AD7P_66"
						(effects
							(font
								(size 1.27 1.27)
							)
						)
					)
					(number "M19"
						(effects
							(font
								(size 1.27 1.27)
							)
						)
					)
				)
				(pin bidirectional line
					(at 0 -25.4 0)
					(length 5.08)
					(name "IO_L4N_T0U_N7_DBC_AD7N_66"
						(effects
							(font
								(size 1.27 1.27)
							)
						)
					)
					(number "L19"
						(effects
							(font
								(size 1.27 1.27)
							)
						)
					)
				)
				(pin bidirectional line
					(at 0 -27.94 0)
					(length 5.08)
					(name "IO_L5P_T0U_N8_AD14P_66"
						(effects
							(font
								(size 1.27 1.27)
							)
						)
					)
					(number "K21"
						(effects
							(font
								(size 1.27 1.27)
							)
						)
					)
				)
				(pin bidirectional line
					(at 0 -30.48 0)
					(length 5.08)
					(name "IO_L5N_T0U_N9_AD14N_66"
						(effects
							(font
								(size 1.27 1.27)
							)
						)
					)
					(number "J21"
						(effects
							(font
								(size 1.27 1.27)
							)
						)
					)
				)
				(pin bidirectional line
					(at 0 -33.02 0)
					(length 5.08)
					(name "IO_L6P_T0U_N10_AD6P_66"
						(effects
							(font
								(size 1.27 1.27)
							)
						)
					)
					(number "L20"
						(effects
							(font
								(size 1.27 1.27)
							)
						)
					)
				)
				(pin bidirectional line
					(at 0 -35.56 0)
					(length 5.08)
					(name "IO_L6N_T0U_N11_AD6N_66"
						(effects
							(font
								(size 1.27 1.27)
							)
						)
					)
					(number "K20"
						(effects
							(font
								(size 1.27 1.27)
							)
						)
					)
				)
				(pin bidirectional line
					(at 0 -38.1 0)
					(length 5.08)
					(name "IO_T0U_N12_VRP_66"
						(effects
							(font
								(size 1.27 1.27)
							)
						)
					)
					(number "M22"
						(effects
							(font
								(size 1.27 1.27)
							)
						)
					)
				)
				(pin bidirectional line
					(at 0 -40.64 0)
					(length 5.08)
					(name "IO_L7P_T1L_N0_QBC_AD13P_66"
						(effects
							(font
								(size 1.27 1.27)
							)
						)
					)
					(number "L22"
						(effects
							(font
								(size 1.27 1.27)
							)
						)
					)
				)
				(pin bidirectional line
					(at 0 -43.18 0)
					(length 5.08)
					(name "IO_L7N_T1L_N1_QBC_AD13N_66"
						(effects
							(font
								(size 1.27 1.27)
							)
						)
					)
					(number "L23"
						(effects
							(font
								(size 1.27 1.27)
							)
						)
					)
				)
				(pin bidirectional line
					(at 0 -45.72 0)
					(length 5.08)
					(name "IO_L8P_T1L_N2_AD5P_66"
						(effects
							(font
								(size 1.27 1.27)
							)
						)
					)
					(number "M25"
						(effects
							(font
								(size 1.27 1.27)
							)
						)
					)
				)
				(pin bidirectional line
					(at 0 -48.26 0)
					(length 5.08)
					(name "IO_L8N_T1L_N3_AD5N_66"
						(effects
							(font
								(size 1.27 1.27)
							)
						)
					)
					(number "M26"
						(effects
							(font
								(size 1.27 1.27)
							)
						)
					)
				)
				(pin bidirectional line
					(at 0 -50.8 0)
					(length 5.08)
					(name "IO_L9P_T1L_N4_AD12P_66"
						(effects
							(font
								(size 1.27 1.27)
							)
						)
					)
					(number "K25"
						(effects
							(font
								(size 1.27 1.27)
							)
						)
					)
				)
				(pin bidirectional line
					(at 0 -53.34 0)
					(length 5.08)
					(name "IO_L9N_T1L_N5_AD12N_66"
						(effects
							(font
								(size 1.27 1.27)
							)
						)
					)
					(number "K26"
						(effects
							(font
								(size 1.27 1.27)
							)
						)
					)
				)
				(pin bidirectional line
					(at 0 -55.88 0)
					(length 5.08)
					(name "IO_L10P_T1U_N6_QBC_AD4P_66"
						(effects
							(font
								(size 1.27 1.27)
							)
						)
					)
					(number "L24"
						(effects
							(font
								(size 1.27 1.27)
							)
						)
					)
				)
				(pin bidirectional line
					(at 0 -58.42 0)
					(length 5.08)
					(name "IO_L10N_T1U_N7_QBC_AD4N_66"
						(effects
							(font
								(size 1.27 1.27)
							)
						)
					)
					(number "L25"
						(effects
							(font
								(size 1.27 1.27)
							)
						)
					)
				)
				(pin bidirectional line
					(at 0 -60.96 0)
					(length 5.08)
					(name "IO_L11P_T1U_N8_GC_66"
						(effects
							(font
								(size 1.27 1.27)
							)
						)
					)
					(number "K22"
						(effects
							(font
								(size 1.27 1.27)
							)
						)
					)
				)
				(pin bidirectional line
					(at 0 -63.5 0)
					(length 5.08)
					(name "IO_L11N_T1U_N9_GC_66"
						(effects
							(font
								(size 1.27 1.27)
							)
						)
					)
					(number "K23"
						(effects
							(font
								(size 1.27 1.27)
							)
						)
					)
				)
				(pin bidirectional line
					(at 0 -66.04 0)
					(length 5.08)
					(name "IO_L12P_T1U_N10_GC_66"
						(effects
							(font
								(size 1.27 1.27)
							)
						)
					)
					(number "J23"
						(effects
							(font
								(size 1.27 1.27)
							)
						)
					)
				)
				(pin bidirectional line
					(at 0 -68.58 0)
					(length 5.08)
					(name "IO_L12N_T1U_N11_GC_66"
						(effects
							(font
								(size 1.27 1.27)
							)
						)
					)
					(number "J24"
						(effects
							(font
								(size 1.27 1.27)
							)
						)
					)
				)
				(pin bidirectional line
					(at 0 -71.12 0)
					(length 5.08)
					(name "IO_T1U_N12_66"
						(effects
							(font
								(size 1.27 1.27)
							)
						)
					)
					(number "M24"
						(effects
							(font
								(size 1.27 1.27)
							)
						)
					)
				)
				(pin bidirectional line
					(at 0 -73.66 0)
					(length 5.08)
					(name "IO_L13P_T2L_N0_GC_QBC_66"
						(effects
							(font
								(size 1.27 1.27)
							)
						)
					)
					(number "G24"
						(effects
							(font
								(size 1.27 1.27)
							)
						)
					)
				)
				(pin bidirectional line
					(at 0 -76.2 0)
					(length 5.08)
					(name "IO_L13N_T2L_N1_GC_QBC_66"
						(effects
							(font
								(size 1.27 1.27)
							)
						)
					)
					(number "G25"
						(effects
							(font
								(size 1.27 1.27)
							)
						)
					)
				)
				(pin bidirectional line
					(at 0 -78.74 0)
					(length 5.08)
					(name "IO_L14P_T2L_N2_GC_66"
						(effects
							(font
								(size 1.27 1.27)
							)
						)
					)
					(number "H23"
						(effects
							(font
								(size 1.27 1.27)
							)
						)
					)
				)
				(pin bidirectional line
					(at 0 -81.28 0)
					(length 5.08)
					(name "IO_L14N_T2L_N3_GC_66"
						(effects
							(font
								(size 1.27 1.27)
							)
						)
					)
					(number "H24"
						(effects
							(font
								(size 1.27 1.27)
							)
						)
					)
				)
				(pin bidirectional line
					(at 0 -83.82 0)
					(length 5.08)
					(name "IO_L15P_T2L_N4_AD11P_66"
						(effects
							(font
								(size 1.27 1.27)
							)
						)
					)
					(number "J25"
						(effects
							(font
								(size 1.27 1.27)
							)
						)
					)
				)
				(pin bidirectional line
					(at 0 -86.36 0)
					(length 5.08)
					(name "IO_L15N_T2L_N5_AD11N_66"
						(effects
							(font
								(size 1.27 1.27)
							)
						)
					)
					(number "J26"
						(effects
							(font
								(size 1.27 1.27)
							)
						)
					)
				)
				(pin bidirectional line
					(at 0 -88.9 0)
					(length 5.08)
					(name "IO_L16P_T2U_N6_QBC_AD3P_66"
						(effects
							(font
								(size 1.27 1.27)
							)
						)
					)
					(number "F24"
						(effects
							(font
								(size 1.27 1.27)
							)
						)
					)
				)
				(pin bidirectional line
					(at 0 -91.44 0)
					(length 5.08)
					(name "IO_L16N_T2U_N7_QBC_AD3N_66"
						(effects
							(font
								(size 1.27 1.27)
							)
						)
					)
					(number "F25"
						(effects
							(font
								(size 1.27 1.27)
							)
						)
					)
				)
				(pin bidirectional line
					(at 0 -93.98 0)
					(length 5.08)
					(name "IO_L17P_T2U_N8_AD10P_66"
						(effects
							(font
								(size 1.27 1.27)
							)
						)
					)
					(number "H26"
						(effects
							(font
								(size 1.27 1.27)
							)
						)
					)
				)
				(pin bidirectional line
					(at 0 -96.52 0)
					(length 5.08)
					(name "IO_L17N_T2U_N9_AD10N_66"
						(effects
							(font
								(size 1.27 1.27)
							)
						)
					)
					(number "G26"
						(effects
							(font
								(size 1.27 1.27)
							)
						)
					)
				)
				(pin bidirectional line
					(at 0 -99.06 0)
					(length 5.08)
					(name "IO_L18P_T2U_N10_AD2P_66"
						(effects
							(font
								(size 1.27 1.27)
							)
						)
					)
					(number "H21"
						(effects
							(font
								(size 1.27 1.27)
							)
						)
					)
				)
				(pin bidirectional line
					(at 0 -101.6 0)
					(length 5.08)
					(name "IO_L18N_T2U_N11_AD2N_66"
						(effects
							(font
								(size 1.27 1.27)
							)
						)
					)
					(number "H22"
						(effects
							(font
								(size 1.27 1.27)
							)
						)
					)
				)
				(pin bidirectional line
					(at 0 -104.14 0)
					(length 5.08)
					(name "IO_T2U_N12_66"
						(effects
							(font
								(size 1.27 1.27)
							)
						)
					)
					(number "G22"
						(effects
							(font
								(size 1.27 1.27)
							)
						)
					)
				)
				(pin bidirectional line
					(at 0 -106.68 0)
					(length 5.08)
					(name "IO_L19P_T3L_N0_DBC_AD9P_66"
						(effects
							(font
								(size 1.27 1.27)
							)
						)
					)
					(number "E25"
						(effects
							(font
								(size 1.27 1.27)
							)
						)
					)
				)
				(pin bidirectional line
					(at 0 -109.22 0)
					(length 5.08)
					(name "IO_L19N_T3L_N1_DBC_AD9N_66"
						(effects
							(font
								(size 1.27 1.27)
							)
						)
					)
					(number "E26"
						(effects
							(font
								(size 1.27 1.27)
							)
						)
					)
				)
				(pin bidirectional line
					(at 0 -111.76 0)
					(length 5.08)
					(name "IO_L20P_T3L_N2_AD1P_66"
						(effects
							(font
								(size 1.27 1.27)
							)
						)
					)
					(number "F23"
						(effects
							(font
								(size 1.27 1.27)
							)
						)
					)
				)
				(pin bidirectional line
					(at 0 -114.3 0)
					(length 5.08)
					(name "IO_L20N_T3L_N3_AD1N_66"
						(effects
							(font
								(size 1.27 1.27)
							)
						)
					)
					(number "E23"
						(effects
							(font
								(size 1.27 1.27)
							)
						)
					)
				)
				(pin bidirectional line
					(at 0 -116.84 0)
					(length 5.08)
					(name "IO_L21P_T3L_N4_AD8P_66"
						(effects
							(font
								(size 1.27 1.27)
							)
						)
					)
					(number "D24"
						(effects
							(font
								(size 1.27 1.27)
							)
						)
					)
				)
				(pin bidirectional line
					(at 0 -119.38 0)
					(length 5.08)
					(name "IO_L21N_T3L_N5_AD8N_66"
						(effects
							(font
								(size 1.27 1.27)
							)
						)
					)
					(number "D25"
						(effects
							(font
								(size 1.27 1.27)
							)
						)
					)
				)
				(pin bidirectional line
					(at 0 -121.92 0)
					(length 5.08)
					(name "IO_L22P_T3U_N6_DBC_AD0P_66"
						(effects
							(font
								(size 1.27 1.27)
							)
						)
					)
					(number "D23"
						(effects
							(font
								(size 1.27 1.27)
							)
						)
					)
				)
				(pin bidirectional line
					(at 0 -124.46 0)
					(length 5.08)
					(name "IO_L22N_T3U_N7_DBC_AD0N_66"
						(effects
							(font
								(size 1.27 1.27)
							)
						)
					)
					(number "C24"
						(effects
							(font
								(size 1.27 1.27)
							)
						)
					)
				)
				(pin bidirectional line
					(at 0 -127 0)
					(length 5.08)
					(name "IO_L23P_T3U_N8_66"
						(effects
							(font
								(size 1.27 1.27)
							)
						)
					)
					(number "D26"
						(effects
							(font
								(size 1.27 1.27)
							)
						)
					)
				)
				(pin bidirectional line
					(at 0 -129.54 0)
					(length 5.08)
					(name "IO_L23N_T3U_N9_66"
						(effects
							(font
								(size 1.27 1.27)
							)
						)
					)
					(number "C26"
						(effects
							(font
								(size 1.27 1.27)
							)
						)
					)
				)
				(pin bidirectional line
					(at 0 -132.08 0)
					(length 5.08)
					(name "IO_L24P_T3U_N10_66"
						(effects
							(font
								(size 1.27 1.27)
							)
						)
					)
					(number "B25"
						(effects
							(font
								(size 1.27 1.27)
							)
						)
					)
				)
				(pin bidirectional line
					(at 0 -134.62 0)
					(length 5.08)
					(name "IO_L24N_T3U_N11_66"
						(effects
							(font
								(size 1.27 1.27)
							)
						)
					)
					(number "B26"
						(effects
							(font
								(size 1.27 1.27)
							)
						)
					)
				)
				(pin bidirectional line
					(at 0 -137.16 0)
					(length 5.08)
					(name "IO_T3U_N12_66"
						(effects
							(font
								(size 1.27 1.27)
							)
						)
					)
					(number "F22"
						(effects
							(font
								(size 1.27 1.27)
							)
						)
					)
				)
			)
			(symbol "XCAU25P-2FFVB676I_5_1"
				(rectangle
					(start 5.08 2.54)
					(end 43.18 -142.24)
					(stroke
						(width 0.254)
						(type default)
					)
					(fill
						(type background)
					)
				)
				(polyline
					(pts
						(xy 30.48 -6.35) (xy 39.37 -6.35) (xy 39.37 -138.43) (xy 31.75 -138.43)
					)
					(stroke
						(width 0.254)
						(type default)
					)
					(fill
						(type background)
					)
				)
				(text "BANK 67"
					(at 30.48 -5.08 0)
					(effects
						(font
							(size 1.27 1.27)
							(thickness 0.15)
						)
						(justify left bottom)
					)
				)
				(text ""
					(at 50.8 -31.75 0)
					(effects
						(font
							(size 1.27 1.27)
							(thickness 0.15)
						)
						(justify left bottom)
					)
				)
				(text ""
					(at 50.8 -31.75 0)
					(effects
						(font
							(size 1.27 1.27)
							(thickness 0.15)
						)
						(justify left bottom)
					)
				)
				(pin power_in line
					(at 0 0 0)
					(length 5.08)
					(name "VCCO_67"
						(effects
							(font
								(size 1.27 1.27)
							)
						)
					)
					(number "C20"
						(effects
							(font
								(size 1.27 1.27)
							)
						)
					)
				)
				(pin passive line
					(at 0 0 0)
					(length 5.08)
					(hide yes)
					(name "VCCO_67"
						(effects
							(font
								(size 1.27 1.27)
							)
						)
					)
					(number "D17"
						(effects
							(font
								(size 1.27 1.27)
							)
						)
					)
				)
				(pin passive line
					(at 0 0 0)
					(length 5.08)
					(hide yes)
					(name "VCCO_67"
						(effects
							(font
								(size 1.27 1.27)
							)
						)
					)
					(number "G18"
						(effects
							(font
								(size 1.27 1.27)
							)
						)
					)
				)
				(pin input line
					(at 0 -2.54 0)
					(length 5.08)
					(name "VREF_67"
						(effects
							(font
								(size 1.27 1.27)
							)
						)
					)
					(number "J16"
						(effects
							(font
								(size 1.27 1.27)
							)
						)
					)
				)
				(pin bidirectional line
					(at 0 -7.62 0)
					(length 5.08)
					(name "IO_L1P_T0L_N0_DBC_67"
						(effects
							(font
								(size 1.27 1.27)
							)
						)
					)
					(number "G15"
						(effects
							(font
								(size 1.27 1.27)
							)
						)
					)
				)
				(pin bidirectional line
					(at 0 -10.16 0)
					(length 5.08)
					(name "IO_L1N_T0L_N1_DBC_67"
						(effects
							(font
								(size 1.27 1.27)
							)
						)
					)
					(number "F15"
						(effects
							(font
								(size 1.27 1.27)
							)
						)
					)
				)
				(pin bidirectional line
					(at 0 -12.7 0)
					(length 5.08)
					(name "IO_L2P_T0L_N2_67"
						(effects
							(font
								(size 1.27 1.27)
							)
						)
					)
					(number "H17"
						(effects
							(font
								(size 1.27 1.27)
							)
						)
					)
				)
				(pin bidirectional line
					(at 0 -15.24 0)
					(length 5.08)
					(name "IO_L2N_T0L_N3_67"
						(effects
							(font
								(size 1.27 1.27)
							)
						)
					)
					(number "G17"
						(effects
							(font
								(size 1.27 1.27)
							)
						)
					)
				)
				(pin bidirectional line
					(at 0 -17.78 0)
					(length 5.08)
					(name "IO_L3P_T0L_N4_AD15P_67"
						(effects
							(font
								(size 1.27 1.27)
							)
						)
					)
					(number "E15"
						(effects
							(font
								(size 1.27 1.27)
							)
						)
					)
				)
				(pin bidirectional line
					(at 0 -20.32 0)
					(length 5.08)
					(name "IO_L3N_T0L_N5_AD15N_67"
						(effects
							(font
								(size 1.27 1.27)
							)
						)
					)
					(number "D15"
						(effects
							(font
								(size 1.27 1.27)
							)
						)
					)
				)
				(pin bidirectional line
					(at 0 -22.86 0)
					(length 5.08)
					(name "IO_L4P_T0U_N6_DBC_AD7P_67"
						(effects
							(font
								(size 1.27 1.27)
							)
						)
					)
					(number "E16"
						(effects
							(font
								(size 1.27 1.27)
							)
						)
					)
				)
				(pin bidirectional line
					(at 0 -25.4 0)
					(length 5.08)
					(name "IO_L4N_T0U_N7_DBC_AD7N_67"
						(effects
							(font
								(size 1.27 1.27)
							)
						)
					)
					(number "E17"
						(effects
							(font
								(size 1.27 1.27)
							)
						)
					)
				)
				(pin bidirectional line
					(at 0 -27.94 0)
					(length 5.08)
					(name "IO_L5P_T0U_N8_AD14P_67"
						(effects
							(font
								(size 1.27 1.27)
							)
						)
					)
					(number "H16"
						(effects
							(font
								(size 1.27 1.27)
							)
						)
					)
				)
				(pin bidirectional line
					(at 0 -30.48 0)
					(length 5.08)
					(name "IO_L5N_T0U_N9_AD14N_67"
						(effects
							(font
								(size 1.27 1.27)
							)
						)
					)
					(number "G16"
						(effects
							(font
								(size 1.27 1.27)
							)
						)
					)
				)
				(pin bidirectional line
					(at 0 -33.02 0)
					(length 5.08)
					(name "IO_L6P_T0U_N10_AD6P_67"
						(effects
							(font
								(size 1.27 1.27)
							)
						)
					)
					(number "D16"
						(effects
							(font
								(size 1.27 1.27)
							)
						)
					)
				)
				(pin bidirectional line
					(at 0 -35.56 0)
					(length 5.08)
					(name "IO_L6N_T0U_N11_AD6N_67"
						(effects
							(font
								(size 1.27 1.27)
							)
						)
					)
					(number "C16"
						(effects
							(font
								(size 1.27 1.27)
							)
						)
					)
				)
				(pin bidirectional line
					(at 0 -38.1 0)
					(length 5.08)
					(name "IO_T0U_N12_VRP_67"
						(effects
							(font
								(size 1.27 1.27)
							)
						)
					)
					(number "F17"
						(effects
							(font
								(size 1.27 1.27)
							)
						)
					)
				)
				(pin bidirectional line
					(at 0 -40.64 0)
					(length 5.08)
					(name "IO_L7P_T1L_N0_QBC_AD13P_67"
						(effects
							(font
								(size 1.27 1.27)
							)
						)
					)
					(number "H18"
						(effects
							(font
								(size 1.27 1.27)
							)
						)
					)
				)
				(pin bidirectional line
					(at 0 -43.18 0)
					(length 5.08)
					(name "IO_L7N_T1L_N1_QBC_AD13N_67"
						(effects
							(font
								(size 1.27 1.27)
							)
						)
					)
					(number "H19"
						(effects
							(font
								(size 1.27 1.27)
							)
						)
					)
				)
				(pin bidirectional line
					(at 0 -45.72 0)
					(length 5.08)
					(name "IO_L8P_T1L_N2_AD5P_67"
						(effects
							(font
								(size 1.27 1.27)
							)
						)
					)
					(number "F18"
						(effects
							(font
								(size 1.27 1.27)
							)
						)
					)
				)
				(pin bidirectional line
					(at 0 -48.26 0)
					(length 5.08)
					(name "IO_L8N_T1L_N3_AD5N_67"
						(effects
							(font
								(size 1.27 1.27)
							)
						)
					)
					(number "F19"
						(effects
							(font
								(size 1.27 1.27)
							)
						)
					)
				)
				(pin bidirectional line
					(at 0 -50.8 0)
					(length 5.08)
					(name "IO_L9P_T1L_N4_AD12P_67"
						(effects
							(font
								(size 1.27 1.27)
							)
						)
					)
					(number "G20"
						(effects
							(font
								(size 1.27 1.27)
							)
						)
					)
				)
				(pin bidirectional line
					(at 0 -53.34 0)
					(length 5.08)
					(name "IO_L9N_T1L_N5_AD12N_67"
						(effects
							(font
								(size 1.27 1.27)
							)
						)
					)
					(number "G21"
						(effects
							(font
								(size 1.27 1.27)
							)
						)
					)
				)
				(pin bidirectional line
					(at 0 -55.88 0)
					(length 5.08)
					(name "IO_L10P_T1U_N6_QBC_AD4P_67"
						(effects
							(font
								(size 1.27 1.27)
							)
						)
					)
					(number "F20"
						(effects
							(font
								(size 1.27 1.27)
							)
						)
					)
				)
				(pin bidirectional line
					(at 0 -58.42 0)
					(length 5.08)
					(name "IO_L10N_T1U_N7_QBC_AD4N_67"
						(effects
							(font
								(size 1.27 1.27)
							)
						)
					)
					(number "E20"
						(effects
							(font
								(size 1.27 1.27)
							)
						)
					)
				)
				(pin bidirectional line
					(at 0 -60.96 0)
					(length 5.08)
					(name "IO_L11P_T1U_N8_GC_67"
						(effects
							(font
								(size 1.27 1.27)
							)
						)
					)
					(number "E18"
						(effects
							(font
								(size 1.27 1.27)
							)
						)
					)
				)
				(pin bidirectional line
					(at 0 -63.5 0)
					(length 5.08)
					(name "IO_L11N_T1U_N9_GC_67"
						(effects
							(font
								(size 1.27 1.27)
							)
						)
					)
					(number "D18"
						(effects
							(font
								(size 1.27 1.27)
							)
						)
					)
				)
				(pin bidirectional line
					(at 0 -66.04 0)
					(length 5.08)
					(name "IO_L12P_T1U_N10_GC_67"
						(effects
							(font
								(size 1.27 1.27)
							)
						)
					)
					(number "D19"
						(effects
							(font
								(size 1.27 1.27)
							)
						)
					)
				)
				(pin bidirectional line
					(at 0 -68.58 0)
					(length 5.08)
					(name "IO_L12N_T1U_N11_GC_67"
						(effects
							(font
								(size 1.27 1.27)
							)
						)
					)
					(number "D20"
						(effects
							(font
								(size 1.27 1.27)
							)
						)
					)
				)
				(pin bidirectional line
					(at 0 -71.12 0)
					(length 5.08)
					(name "IO_T1U_N12_67"
						(effects
							(font
								(size 1.27 1.27)
							)
						)
					)
					(number "G19"
						(effects
							(font
								(size 1.27 1.27)
							)
						)
					)
				)
				(pin bidirectional line
					(at 0 -73.66 0)
					(length 5.08)
					(name "IO_L13P_T2L_N0_GC_QBC_67"
						(effects
							(font
								(size 1.27 1.27)
							)
						)
					)
					(number "C18"
						(effects
							(font
								(size 1.27 1.27)
							)
						)
					)
				)
				(pin bidirectional line
					(at 0 -76.2 0)
					(length 5.08)
					(name "IO_L13N_T2L_N1_GC_QBC_67"
						(effects
							(font
								(size 1.27 1.27)
							)
						)
					)
					(number "C19"
						(effects
							(font
								(size 1.27 1.27)
							)
						)
					)
				)
				(pin bidirectional line
					(at 0 -78.74 0)
					(length 5.08)
					(name "IO_L14P_T2L_N2_GC_67"
						(effects
							(font
								(size 1.27 1.27)
							)
						)
					)
					(number "B19"
						(effects
							(font
								(size 1.27 1.27)
							)
						)
					)
				)
				(pin bidirectional line
					(at 0 -81.28 0)
					(length 5.08)
					(name "IO_L14N_T2L_N3_GC_67"
						(effects
							(font
								(size 1.27 1.27)
							)
						)
					)
					(number "B20"
						(effects
							(font
								(size 1.27 1.27)
							)
						)
					)
				)
				(pin bidirectional line
					(at 0 -83.82 0)
					(length 5.08)
					(name "IO_L15P_T2L_N4_AD11P_67"
						(effects
							(font
								(size 1.27 1.27)
							)
						)
					)
					(number "C17"
						(effects
							(font
								(size 1.27 1.27)
							)
						)
					)
				)
				(pin bidirectional line
					(at 0 -86.36 0)
					(length 5.08)
					(name "IO_L15N_T2L_N5_AD11N_67"
						(effects
							(font
								(size 1.27 1.27)
							)
						)
					)
					(number "B17"
						(effects
							(font
								(size 1.27 1.27)
							)
						)
					)
				)
				(pin bidirectional line
					(at 0 -88.9 0)
					(length 5.08)
					(name "IO_L16P_T2U_N6_QBC_AD3P_67"
						(effects
							(font
								(size 1.27 1.27)
							)
						)
					)
					(number "A17"
						(effects
							(font
								(size 1.27 1.27)
							)
						)
					)
				)
				(pin bidirectional line
					(at 0 -91.44 0)
					(length 5.08)
					(name "IO_L16N_T2U_N7_QBC_AD3N_67"
						(effects
							(font
								(size 1.27 1.27)
							)
						)
					)
					(number "A18"
						(effects
							(font
								(size 1.27 1.27)
							)
						)
					)
				)
				(pin bidirectional line
					(at 0 -93.98 0)
					(length 5.08)
					(name "IO_L17P_T2U_N8_AD10P_67"
						(effects
							(font
								(size 1.27 1.27)
							)
						)
					)
					(number "B15"
						(effects
							(font
								(size 1.27 1.27)
							)
						)
					)
				)
				(pin bidirectional line
					(at 0 -96.52 0)
					(length 5.08)
					(name "IO_L17N_T2U_N9_AD10N_67"
						(effects
							(font
								(size 1.27 1.27)
							)
						)
					)
					(number "A15"
						(effects
							(font
								(size 1.27 1.27)
							)
						)
					)
				)
				(pin bidirectional line
					(at 0 -99.06 0)
					(length 5.08)
					(name "IO_L18P_T2U_N10_AD2P_67"
						(effects
							(font
								(size 1.27 1.27)
							)
						)
					)
					(number "A19"
						(effects
							(font
								(size 1.27 1.27)
							)
						)
					)
				)
				(pin bidirectional line
					(at 0 -101.6 0)
					(length 5.08)
					(name "IO_L18N_T2U_N11_AD2N_67"
						(effects
							(font
								(size 1.27 1.27)
							)
						)
					)
					(number "A20"
						(effects
							(font
								(size 1.27 1.27)
							)
						)
					)
				)
				(pin bidirectional line
					(at 0 -104.14 0)
					(length 5.08)
					(name "IO_T2U_N12_67"
						(effects
							(font
								(size 1.27 1.27)
							)
						)
					)
					(number "B16"
						(effects
							(font
								(size 1.27 1.27)
							)
						)
					)
				)
				(pin bidirectional line
					(at 0 -106.68 0)
					(length 5.08)
					(name "IO_L19P_T3L_N0_DBC_AD9P_67"
						(effects
							(font
								(size 1.27 1.27)
							)
						)
					)
					(number "A22"
						(effects
							(font
								(size 1.27 1.27)
							)
						)
					)
				)
				(pin bidirectional line
					(at 0 -109.22 0)
					(length 5.08)
					(name "IO_L19N_T3L_N1_DBC_AD9N_67"
						(effects
							(font
								(size 1.27 1.27)
							)
						)
					)
					(number "A23"
						(effects
							(font
								(size 1.27 1.27)
							)
						)
					)
				)
				(pin bidirectional line
					(at 0 -111.76 0)
					(length 5.08)
					(name "IO_L20P_T3L_N2_AD1P_67"
						(effects
							(font
								(size 1.27 1.27)
							)
						)
					)
					(number "E21"
						(effects
							(font
								(size 1.27 1.27)
							)
						)
					)
				)
				(pin bidirectional line
					(at 0 -114.3 0)
					(length 5.08)
					(name "IO_L20N_T3L_N3_AD1N_67"
						(effects
							(font
								(size 1.27 1.27)
							)
						)
					)
					(number "D21"
						(effects
							(font
								(size 1.27 1.27)
							)
						)
					)
				)
				(pin bidirectional line
					(at 0 -116.84 0)
					(length 5.08)
					(name "IO_L21P_T3L_N4_AD8P_67"
						(effects
							(font
								(size 1.27 1.27)
							)
						)
					)
					(number "C23"
						(effects
							(font
								(size 1.27 1.27)
							)
						)
					)
				)
				(pin bidirectional line
					(at 0 -119.38 0)
					(length 5.08)
					(name "IO_L21N_T3L_N5_AD8N_67"
						(effects
							(font
								(size 1.27 1.27)
							)
						)
					)
					(number "B24"
						(effects
							(font
								(size 1.27 1.27)
							)
						)
					)
				)
				(pin bidirectional line
					(at 0 -121.92 0)
					(length 5.08)
					(name "IO_L22P_T3U_N6_DBC_AD0P_67"
						(effects
							(font
								(size 1.27 1.27)
							)
						)
					)
					(number "C21"
						(effects
							(font
								(size 1.27 1.27)
							)
						)
					)
				)
				(pin bidirectional line
					(at 0 -124.46 0)
					(length 5.08)
					(name "IO_L22N_T3U_N7_DBC_AD0N_67"
						(effects
							(font
								(size 1.27 1.27)
							)
						)
					)
					(number "B21"
						(effects
							(font
								(size 1.27 1.27)
							)
						)
					)
				)
				(pin bidirectional line
					(at 0 -127 0)
					(length 5.08)
					(name "IO_L23P_T3U_N8_67"
						(effects
							(font
								(size 1.27 1.27)
							)
						)
					)
					(number "A24"
						(effects
							(font
								(size 1.27 1.27)
							)
						)
					)
				)
				(pin bidirectional line
					(at 0 -129.54 0)
					(length 5.08)
					(name "IO_L23N_T3U_N9_67"
						(effects
							(font
								(size 1.27 1.27)
							)
						)
					)
					(number "A25"
						(effects
							(font
								(size 1.27 1.27)
							)
						)
					)
				)
				(pin bidirectional line
					(at 0 -132.08 0)
					(length 5.08)
					(name "IO_L24P_T3U_N10_67"
						(effects
							(font
								(size 1.27 1.27)
							)
						)
					)
					(number "C22"
						(effects
							(font
								(size 1.27 1.27)
							)
						)
					)
				)
				(pin bidirectional line
					(at 0 -134.62 0)
					(length 5.08)
					(name "IO_L24N_T3U_N11_67"
						(effects
							(font
								(size 1.27 1.27)
							)
						)
					)
					(number "B22"
						(effects
							(font
								(size 1.27 1.27)
							)
						)
					)
				)
				(pin bidirectional line
					(at 0 -137.16 0)
					(length 5.08)
					(name "IO_T3U_N12_67"
						(effects
							(font
								(size 1.27 1.27)
							)
						)
					)
					(number "E22"
						(effects
							(font
								(size 1.27 1.27)
							)
						)
					)
				)
			)
			(symbol "XCAU25P-2FFVB676I_6_1"
				(rectangle
					(start 5.08 2.54)
					(end 33.02 -68.58)
					(stroke
						(width 0.254)
						(type default)
					)
					(fill
						(type background)
					)
				)
				(polyline
					(pts
						(xy 22.86 -3.81) (xy 30.48 -3.81) (xy 30.48 -64.77) (xy 22.86 -64.77)
					)
					(stroke
						(width 0.254)
						(type default)
					)
					(fill
						(type background)
					)
				)
				(text "BANK 84"
					(at 22.86 -2.54 0)
					(effects
						(font
							(size 1.27 1.27)
							(thickness 0.15)
						)
						(justify left bottom)
					)
				)
				(text ""
					(at 50.8 -31.75 0)
					(effects
						(font
							(size 1.27 1.27)
							(thickness 0.15)
						)
						(justify left bottom)
					)
				)
				(text ""
					(at 50.8 -31.75 0)
					(effects
						(font
							(size 1.27 1.27)
							(thickness 0.15)
						)
						(justify left bottom)
					)
				)
				(pin power_in line
					(at 0 0 0)
					(length 5.08)
					(name "VCCO_84"
						(effects
							(font
								(size 1.27 1.27)
							)
						)
					)
					(number "AC15"
						(effects
							(font
								(size 1.27 1.27)
							)
						)
					)
				)
				(pin passive line
					(at 0 0 0)
					(length 5.08)
					(hide yes)
					(name "VCCO_84"
						(effects
							(font
								(size 1.27 1.27)
							)
						)
					)
					(number "Y14"
						(effects
							(font
								(size 1.27 1.27)
							)
						)
					)
				)
				(pin bidirectional line
					(at 0 -5.08 0)
					(length 5.08)
					(name "IO_L1P_AD11P_84"
						(effects
							(font
								(size 1.27 1.27)
							)
						)
					)
					(number "AF14"
						(effects
							(font
								(size 1.27 1.27)
							)
						)
					)
				)
				(pin bidirectional line
					(at 0 -7.62 0)
					(length 5.08)
					(name "IO_L1N_AD11N_84"
						(effects
							(font
								(size 1.27 1.27)
							)
						)
					)
					(number "AF15"
						(effects
							(font
								(size 1.27 1.27)
							)
						)
					)
				)
				(pin bidirectional line
					(at 0 -10.16 0)
					(length 5.08)
					(name "IO_L2P_AD10P_84"
						(effects
							(font
								(size 1.27 1.27)
							)
						)
					)
					(number "AE13"
						(effects
							(font
								(size 1.27 1.27)
							)
						)
					)
				)
				(pin bidirectional line
					(at 0 -12.7 0)
					(length 5.08)
					(name "IO_L2N_AD10N_84"
						(effects
							(font
								(size 1.27 1.27)
							)
						)
					)
					(number "AF13"
						(effects
							(font
								(size 1.27 1.27)
							)
						)
					)
				)
				(pin bidirectional line
					(at 0 -15.24 0)
					(length 5.08)
					(name "IO_L3P_AD9P_84"
						(effects
							(font
								(size 1.27 1.27)
							)
						)
					)
					(number "AD15"
						(effects
							(font
								(size 1.27 1.27)
							)
						)
					)
				)
				(pin bidirectional line
					(at 0 -17.78 0)
					(length 5.08)
					(name "IO_L3N_AD9N_84"
						(effects
							(font
								(size 1.27 1.27)
							)
						)
					)
					(number "AE15"
						(effects
							(font
								(size 1.27 1.27)
							)
						)
					)
				)
				(pin bidirectional line
					(at 0 -20.32 0)
					(length 5.08)
					(name "IO_L4P_AD8P_84"
						(effects
							(font
								(size 1.27 1.27)
							)
						)
					)
					(number "AD13"
						(effects
							(font
								(size 1.27 1.27)
							)
						)
					)
				)
				(pin bidirectional line
					(at 0 -22.86 0)
					(length 5.08)
					(name "IO_L4N_AD8N_84"
						(effects
							(font
								(size 1.27 1.27)
							)
						)
					)
					(number "AD14"
						(effects
							(font
								(size 1.27 1.27)
							)
						)
					)
				)
				(pin bidirectional line
					(at 0 -25.4 0)
					(length 5.08)
					(name "IO_L5P_HDGC_AD7P_84"
						(effects
							(font
								(size 1.27 1.27)
							)
						)
					)
					(number "AC13"
						(effects
							(font
								(size 1.27 1.27)
							)
						)
					)
				)
				(pin bidirectional line
					(at 0 -27.94 0)
					(length 5.08)
					(name "IO_L5N_HDGC_AD7N_84"
						(effects
							(font
								(size 1.27 1.27)
							)
						)
					)
					(number "AC14"
						(effects
							(font
								(size 1.27 1.27)
							)
						)
					)
				)
				(pin bidirectional line
					(at 0 -30.48 0)
					(length 5.08)
					(name "IO_L6P_HDGC_AD6P_84"
						(effects
							(font
								(size 1.27 1.27)
							)
						)
					)
					(number "AB15"
						(effects
							(font
								(size 1.27 1.27)
							)
						)
					)
				)
				(pin bidirectional line
					(at 0 -33.02 0)
					(length 5.08)
					(name "IO_L6N_HDGC_AD6N_84"
						(effects
							(font
								(size 1.27 1.27)
							)
						)
					)
					(number "AB16"
						(effects
							(font
								(size 1.27 1.27)
							)
						)
					)
				)
				(pin bidirectional line
					(at 0 -35.56 0)
					(length 5.08)
					(name "IO_L7P_HDGC_AD5P_84"
						(effects
							(font
								(size 1.27 1.27)
							)
						)
					)
					(number "Y15"
						(effects
							(font
								(size 1.27 1.27)
							)
						)
					)
				)
				(pin bidirectional line
					(at 0 -38.1 0)
					(length 5.08)
					(name "IO_L7N_HDGC_AD5N_84"
						(effects
							(font
								(size 1.27 1.27)
							)
						)
					)
					(number "AA15"
						(effects
							(font
								(size 1.27 1.27)
							)
						)
					)
				)
				(pin bidirectional line
					(at 0 -40.64 0)
					(length 5.08)
					(name "IO_L8P_HDGC_AD4P_84"
						(effects
							(font
								(size 1.27 1.27)
							)
						)
					)
					(number "AA14"
						(effects
							(font
								(size 1.27 1.27)
							)
						)
					)
				)
				(pin bidirectional line
					(at 0 -43.18 0)
					(length 5.08)
					(name "IO_L8N_HDGC_AD4N_84"
						(effects
							(font
								(size 1.27 1.27)
							)
						)
					)
					(number "AB14"
						(effects
							(font
								(size 1.27 1.27)
							)
						)
					)
				)
				(pin bidirectional line
					(at 0 -45.72 0)
					(length 5.08)
					(name "IO_L9P_AD3P_84"
						(effects
							(font
								(size 1.27 1.27)
							)
						)
					)
					(number "W16"
						(effects
							(font
								(size 1.27 1.27)
							)
						)
					)
				)
				(pin bidirectional line
					(at 0 -48.26 0)
					(length 5.08)
					(name "IO_L9N_AD3N_84"
						(effects
							(font
								(size 1.27 1.27)
							)
						)
					)
					(number "Y16"
						(effects
							(font
								(size 1.27 1.27)
							)
						)
					)
				)
				(pin bidirectional line
					(at 0 -50.8 0)
					(length 5.08)
					(name "IO_L10P_AD2P_84"
						(effects
							(font
								(size 1.27 1.27)
							)
						)
					)
					(number "W14"
						(effects
							(font
								(size 1.27 1.27)
							)
						)
					)
				)
				(pin bidirectional line
					(at 0 -53.34 0)
					(length 5.08)
					(name "IO_L10N_AD2N_84"
						(effects
							(font
								(size 1.27 1.27)
							)
						)
					)
					(number "W15"
						(effects
							(font
								(size 1.27 1.27)
							)
						)
					)
				)
				(pin bidirectional line
					(at 0 -55.88 0)
					(length 5.08)
					(name "IO_L11P_AD1P_84"
						(effects
							(font
								(size 1.27 1.27)
							)
						)
					)
					(number "Y13"
						(effects
							(font
								(size 1.27 1.27)
							)
						)
					)
				)
				(pin bidirectional line
					(at 0 -58.42 0)
					(length 5.08)
					(name "IO_L11N_AD1N_84"
						(effects
							(font
								(size 1.27 1.27)
							)
						)
					)
					(number "AA13"
						(effects
							(font
								(size 1.27 1.27)
							)
						)
					)
				)
				(pin bidirectional line
					(at 0 -60.96 0)
					(length 5.08)
					(name "IO_L12P_AD0P_84"
						(effects
							(font
								(size 1.27 1.27)
							)
						)
					)
					(number "W12"
						(effects
							(font
								(size 1.27 1.27)
							)
						)
					)
				)
				(pin bidirectional line
					(at 0 -63.5 0)
					(length 5.08)
					(name "IO_L12N_AD0N_84"
						(effects
							(font
								(size 1.27 1.27)
							)
						)
					)
					(number "W13"
						(effects
							(font
								(size 1.27 1.27)
							)
						)
					)
				)
			)
			(symbol "XCAU25P-2FFVB676I_7_1"
				(rectangle
					(start 5.08 2.54)
					(end 33.02 -68.58)
					(stroke
						(width 0.254)
						(type default)
					)
					(fill
						(type background)
					)
				)
				(polyline
					(pts
						(xy 22.86 -3.81) (xy 30.48 -3.81) (xy 30.48 -64.77) (xy 22.86 -64.77)
					)
					(stroke
						(width 0.254)
						(type default)
					)
					(fill
						(type background)
					)
				)
				(text "BANK 86"
					(at 22.86 -2.54 0)
					(effects
						(font
							(size 1.27 1.27)
							(thickness 0.15)
						)
						(justify left bottom)
					)
				)
				(text ""
					(at 50.8 -31.75 0)
					(effects
						(font
							(size 1.27 1.27)
							(thickness 0.15)
						)
						(justify left bottom)
					)
				)
				(text ""
					(at 50.8 -31.75 0)
					(effects
						(font
							(size 1.27 1.27)
							(thickness 0.15)
						)
						(justify left bottom)
					)
				)
				(pin power_in line
					(at 0 0 0)
					(length 5.08)
					(name "VCCO_86"
						(effects
							(font
								(size 1.27 1.27)
							)
						)
					)
					(number "E9"
						(effects
							(font
								(size 1.27 1.27)
							)
						)
					)
				)
				(pin passive line
					(at 0 0 0)
					(length 5.08)
					(hide yes)
					(name "VCCO_86"
						(effects
							(font
								(size 1.27 1.27)
							)
						)
					)
					(number "H10"
						(effects
							(font
								(size 1.27 1.27)
							)
						)
					)
				)
				(pin bidirectional line
					(at 0 -5.08 0)
					(length 5.08)
					(name "IO_L1P_AD11P_86"
						(effects
							(font
								(size 1.27 1.27)
							)
						)
					)
					(number "K10"
						(effects
							(font
								(size 1.27 1.27)
							)
						)
					)
				)
				(pin bidirectional line
					(at 0 -7.62 0)
					(length 5.08)
					(name "IO_L1N_AD11N_86"
						(effects
							(font
								(size 1.27 1.27)
							)
						)
					)
					(number "K9"
						(effects
							(font
								(size 1.27 1.27)
							)
						)
					)
				)
				(pin bidirectional line
					(at 0 -10.16 0)
					(length 5.08)
					(name "IO_L2P_AD10P_86"
						(effects
							(font
								(size 1.27 1.27)
							)
						)
					)
					(number "J11"
						(effects
							(font
								(size 1.27 1.27)
							)
						)
					)
				)
				(pin bidirectional line
					(at 0 -12.7 0)
					(length 5.08)
					(name "IO_L2N_AD10N_86"
						(effects
							(font
								(size 1.27 1.27)
							)
						)
					)
					(number "J10"
						(effects
							(font
								(size 1.27 1.27)
							)
						)
					)
				)
				(pin bidirectional line
					(at 0 -15.24 0)
					(length 5.08)
					(name "IO_L3P_AD9P_86"
						(effects
							(font
								(size 1.27 1.27)
							)
						)
					)
					(number "J9"
						(effects
							(font
								(size 1.27 1.27)
							)
						)
					)
				)
				(pin bidirectional line
					(at 0 -17.78 0)
					(length 5.08)
					(name "IO_L3N_AD9N_86"
						(effects
							(font
								(size 1.27 1.27)
							)
						)
					)
					(number "H9"
						(effects
							(font
								(size 1.27 1.27)
							)
						)
					)
				)
				(pin bidirectional line
					(at 0 -20.32 0)
					(length 5.08)
					(name "IO_L4P_AD8P_86"
						(effects
							(font
								(size 1.27 1.27)
							)
						)
					)
					(number "H11"
						(effects
							(font
								(size 1.27 1.27)
							)
						)
					)
				)
				(pin bidirectional line
					(at 0 -22.86 0)
					(length 5.08)
					(name "IO_L4N_AD8N_86"
						(effects
							(font
								(size 1.27 1.27)
							)
						)
					)
					(number "G11"
						(effects
							(font
								(size 1.27 1.27)
							)
						)
					)
				)
				(pin bidirectional line
					(at 0 -25.4 0)
					(length 5.08)
					(name "IO_L5P_HDGC_AD7P_86"
						(effects
							(font
								(size 1.27 1.27)
							)
						)
					)
					(number "G10"
						(effects
							(font
								(size 1.27 1.27)
							)
						)
					)
				)
				(pin bidirectional line
					(at 0 -27.94 0)
					(length 5.08)
					(name "IO_L5N_HDGC_AD7N_86"
						(effects
							(font
								(size 1.27 1.27)
							)
						)
					)
					(number "G9"
						(effects
							(font
								(size 1.27 1.27)
							)
						)
					)
				)
				(pin bidirectional line
					(at 0 -30.48 0)
					(length 5.08)
					(name "IO_L6P_HDGC_AD6P_86"
						(effects
							(font
								(size 1.27 1.27)
							)
						)
					)
					(number "F10"
						(effects
							(font
								(size 1.27 1.27)
							)
						)
					)
				)
				(pin bidirectional line
					(at 0 -33.02 0)
					(length 5.08)
					(name "IO_L6N_HDGC_AD6N_86"
						(effects
							(font
								(size 1.27 1.27)
							)
						)
					)
					(number "F9"
						(effects
							(font
								(size 1.27 1.27)
							)
						)
					)
				)
				(pin bidirectional line
					(at 0 -35.56 0)
					(length 5.08)
					(name "IO_L7P_HDGC_AD5P_86"
						(effects
							(font
								(size 1.27 1.27)
							)
						)
					)
					(number "E11"
						(effects
							(font
								(size 1.27 1.27)
							)
						)
					)
				)
				(pin bidirectional line
					(at 0 -38.1 0)
					(length 5.08)
					(name "IO_L7N_HDGC_AD5N_86"
						(effects
							(font
								(size 1.27 1.27)
							)
						)
					)
					(number "E10"
						(effects
							(font
								(size 1.27 1.27)
							)
						)
					)
				)
				(pin bidirectional line
					(at 0 -40.64 0)
					(length 5.08)
					(name "IO_L8P_HDGC_AD4P_86"
						(effects
							(font
								(size 1.27 1.27)
							)
						)
					)
					(number "D11"
						(effects
							(font
								(size 1.27 1.27)
							)
						)
					)
				)
				(pin bidirectional line
					(at 0 -43.18 0)
					(length 5.08)
					(name "IO_L8N_HDGC_AD4N_86"
						(effects
							(font
								(size 1.27 1.27)
							)
						)
					)
					(number "D10"
						(effects
							(font
								(size 1.27 1.27)
							)
						)
					)
				)
				(pin bidirectional line
					(at 0 -45.72 0)
					(length 5.08)
					(name "IO_L9P_AD3P_86"
						(effects
							(font
								(size 1.27 1.27)
							)
						)
					)
					(number "D9"
						(effects
							(font
								(size 1.27 1.27)
							)
						)
					)
				)
				(pin bidirectional line
					(at 0 -48.26 0)
					(length 5.08)
					(name "IO_L9N_AD3N_86"
						(effects
							(font
								(size 1.27 1.27)
							)
						)
					)
					(number "C9"
						(effects
							(font
								(size 1.27 1.27)
							)
						)
					)
				)
				(pin bidirectional line
					(at 0 -50.8 0)
					(length 5.08)
					(name "IO_L10P_AD2P_86"
						(effects
							(font
								(size 1.27 1.27)
							)
						)
					)
					(number "B9"
						(effects
							(font
								(size 1.27 1.27)
							)
						)
					)
				)
				(pin bidirectional line
					(at 0 -53.34 0)
					(length 5.08)
					(name "IO_L10N_AD2N_86"
						(effects
							(font
								(size 1.27 1.27)
							)
						)
					)
					(number "A9"
						(effects
							(font
								(size 1.27 1.27)
							)
						)
					)
				)
				(pin bidirectional line
					(at 0 -55.88 0)
					(length 5.08)
					(name "IO_L11P_AD1P_86"
						(effects
							(font
								(size 1.27 1.27)
							)
						)
					)
					(number "B10"
						(effects
							(font
								(size 1.27 1.27)
							)
						)
					)
				)
				(pin bidirectional line
					(at 0 -58.42 0)
					(length 5.08)
					(name "IO_L11N_AD1N_86"
						(effects
							(font
								(size 1.27 1.27)
							)
						)
					)
					(number "A10"
						(effects
							(font
								(size 1.27 1.27)
							)
						)
					)
				)
				(pin bidirectional line
					(at 0 -60.96 0)
					(length 5.08)
					(name "IO_L12P_AD0P_86"
						(effects
							(font
								(size 1.27 1.27)
							)
						)
					)
					(number "C11"
						(effects
							(font
								(size 1.27 1.27)
							)
						)
					)
				)
				(pin bidirectional line
					(at 0 -63.5 0)
					(length 5.08)
					(name "IO_L12N_AD0N_86"
						(effects
							(font
								(size 1.27 1.27)
							)
						)
					)
					(number "B11"
						(effects
							(font
								(size 1.27 1.27)
							)
						)
					)
				)
			)
			(symbol "XCAU25P-2FFVB676I_8_1"
				(rectangle
					(start 5.08 2.54)
					(end 33.02 -67.31)
					(stroke
						(width 0.254)
						(type default)
					)
					(fill
						(type background)
					)
				)
				(polyline
					(pts
						(xy 22.86 -3.81) (xy 30.48 -3.81) (xy 30.48 -64.77) (xy 22.86 -64.77)
					)
					(stroke
						(width 0.254)
						(type default)
					)
					(fill
						(type background)
					)
				)
				(text "BANK 87"
					(at 22.86 -2.54 0)
					(effects
						(font
							(size 1.27 1.27)
							(thickness 0.15)
						)
						(justify left bottom)
					)
				)
				(text ""
					(at 50.8 -31.75 0)
					(effects
						(font
							(size 1.27 1.27)
							(thickness 0.15)
						)
						(justify left bottom)
					)
				)
				(text ""
					(at 50.8 -31.75 0)
					(effects
						(font
							(size 1.27 1.27)
							(thickness 0.15)
						)
						(justify left bottom)
					)
				)
				(pin power_in line
					(at 0 0 0)
					(length 5.08)
					(name "VCCO_87"
						(effects
							(font
								(size 1.27 1.27)
							)
						)
					)
					(number "E14"
						(effects
							(font
								(size 1.27 1.27)
							)
						)
					)
				)
				(pin passive line
					(at 0 0 0)
					(length 5.08)
					(hide yes)
					(name "VCCO_87"
						(effects
							(font
								(size 1.27 1.27)
							)
						)
					)
					(number "H15"
						(effects
							(font
								(size 1.27 1.27)
							)
						)
					)
				)
				(pin bidirectional line
					(at 0 -5.08 0)
					(length 5.08)
					(name "IO_L1P_AD15P_87"
						(effects
							(font
								(size 1.27 1.27)
							)
						)
					)
					(number "J12"
						(effects
							(font
								(size 1.27 1.27)
							)
						)
					)
				)
				(pin bidirectional line
					(at 0 -7.62 0)
					(length 5.08)
					(name "IO_L1N_AD15N_87"
						(effects
							(font
								(size 1.27 1.27)
							)
						)
					)
					(number "H12"
						(effects
							(font
								(size 1.27 1.27)
							)
						)
					)
				)
				(pin bidirectional line
					(at 0 -10.16 0)
					(length 5.08)
					(name "IO_L2P_AD14P_87"
						(effects
							(font
								(size 1.27 1.27)
							)
						)
					)
					(number "J13"
						(effects
							(font
								(size 1.27 1.27)
							)
						)
					)
				)
				(pin bidirectional line
					(at 0 -12.7 0)
					(length 5.08)
					(name "IO_L2N_AD14N_87"
						(effects
							(font
								(size 1.27 1.27)
							)
						)
					)
					(number "H13"
						(effects
							(font
								(size 1.27 1.27)
							)
						)
					)
				)
				(pin bidirectional line
					(at 0 -15.24 0)
					(length 5.08)
					(name "IO_L3P_AD13P_87"
						(effects
							(font
								(size 1.27 1.27)
							)
						)
					)
					(number "H14"
						(effects
							(font
								(size 1.27 1.27)
							)
						)
					)
				)
				(pin bidirectional line
					(at 0 -17.78 0)
					(length 5.08)
					(name "IO_L3N_AD13N_87"
						(effects
							(font
								(size 1.27 1.27)
							)
						)
					)
					(number "G14"
						(effects
							(font
								(size 1.27 1.27)
							)
						)
					)
				)
				(pin bidirectional line
					(at 0 -20.32 0)
					(length 5.08)
					(name "IO_L4P_AD12P_87"
						(effects
							(font
								(size 1.27 1.27)
							)
						)
					)
					(number "J15"
						(effects
							(font
								(size 1.27 1.27)
							)
						)
					)
				)
				(pin bidirectional line
					(at 0 -22.86 0)
					(length 5.08)
					(name "IO_L4N_AD12N_87"
						(effects
							(font
								(size 1.27 1.27)
							)
						)
					)
					(number "J14"
						(effects
							(font
								(size 1.27 1.27)
							)
						)
					)
				)
				(pin bidirectional line
					(at 0 -25.4 0)
					(length 5.08)
					(name "IO_L5P_HDGC_87"
						(effects
							(font
								(size 1.27 1.27)
							)
						)
					)
					(number "G12"
						(effects
							(font
								(size 1.27 1.27)
							)
						)
					)
				)
				(pin bidirectional line
					(at 0 -27.94 0)
					(length 5.08)
					(name "IO_L5N_HDGC_87"
						(effects
							(font
								(size 1.27 1.27)
							)
						)
					)
					(number "F12"
						(effects
							(font
								(size 1.27 1.27)
							)
						)
					)
				)
				(pin bidirectional line
					(at 0 -30.48 0)
					(length 5.08)
					(name "IO_L6P_HDGC_87"
						(effects
							(font
								(size 1.27 1.27)
							)
						)
					)
					(number "F14"
						(effects
							(font
								(size 1.27 1.27)
							)
						)
					)
				)
				(pin bidirectional line
					(at 0 -33.02 0)
					(length 5.08)
					(name "IO_L6N_HDGC_87"
						(effects
							(font
								(size 1.27 1.27)
							)
						)
					)
					(number "F13"
						(effects
							(font
								(size 1.27 1.27)
							)
						)
					)
				)
				(pin bidirectional line
					(at 0 -35.56 0)
					(length 5.08)
					(name "IO_L7P_HDGC_87"
						(effects
							(font
								(size 1.27 1.27)
							)
						)
					)
					(number "E13"
						(effects
							(font
								(size 1.27 1.27)
							)
						)
					)
				)
				(pin bidirectional line
					(at 0 -38.1 0)
					(length 5.08)
					(name "IO_L7N_HDGC_87"
						(effects
							(font
								(size 1.27 1.27)
							)
						)
					)
					(number "E12"
						(effects
							(font
								(size 1.27 1.27)
							)
						)
					)
				)
				(pin bidirectional line
					(at 0 -40.64 0)
					(length 5.08)
					(name "IO_L8P_HDGC_87"
						(effects
							(font
								(size 1.27 1.27)
							)
						)
					)
					(number "D14"
						(effects
							(font
								(size 1.27 1.27)
							)
						)
					)
				)
				(pin bidirectional line
					(at 0 -43.18 0)
					(length 5.08)
					(name "IO_L8N_HDGC_87"
						(effects
							(font
								(size 1.27 1.27)
							)
						)
					)
					(number "D13"
						(effects
							(font
								(size 1.27 1.27)
							)
						)
					)
				)
				(pin bidirectional line
					(at 0 -45.72 0)
					(length 5.08)
					(name "IO_L9P_AD11P_87"
						(effects
							(font
								(size 1.27 1.27)
							)
						)
					)
					(number "C14"
						(effects
							(font
								(size 1.27 1.27)
							)
						)
					)
				)
				(pin bidirectional line
					(at 0 -48.26 0)
					(length 5.08)
					(name "IO_L9N_AD11N_87"
						(effects
							(font
								(size 1.27 1.27)
							)
						)
					)
					(number "C13"
						(effects
							(font
								(size 1.27 1.27)
							)
						)
					)
				)
				(pin bidirectional line
					(at 0 -50.8 0)
					(length 5.08)
					(name "IO_L10P_AD10P_87"
						(effects
							(font
								(size 1.27 1.27)
							)
						)
					)
					(number "C12"
						(effects
							(font
								(size 1.27 1.27)
							)
						)
					)
				)
				(pin bidirectional line
					(at 0 -53.34 0)
					(length 5.08)
					(name "IO_L10N_AD10N_87"
						(effects
							(font
								(size 1.27 1.27)
							)
						)
					)
					(number "B12"
						(effects
							(font
								(size 1.27 1.27)
							)
						)
					)
				)
				(pin bidirectional line
					(at 0 -55.88 0)
					(length 5.08)
					(name "IO_L11P_AD9P_87"
						(effects
							(font
								(size 1.27 1.27)
							)
						)
					)
					(number "A13"
						(effects
							(font
								(size 1.27 1.27)
							)
						)
					)
				)
				(pin bidirectional line
					(at 0 -58.42 0)
					(length 5.08)
					(name "IO_L11N_AD9N_87"
						(effects
							(font
								(size 1.27 1.27)
							)
						)
					)
					(number "A12"
						(effects
							(font
								(size 1.27 1.27)
							)
						)
					)
				)
				(pin bidirectional line
					(at 0 -60.96 0)
					(length 5.08)
					(name "IO_L12P_AD8P_87"
						(effects
							(font
								(size 1.27 1.27)
							)
						)
					)
					(number "B14"
						(effects
							(font
								(size 1.27 1.27)
							)
						)
					)
				)
				(pin bidirectional line
					(at 0 -63.5 0)
					(length 5.08)
					(name "IO_L12N_AD8N_87"
						(effects
							(font
								(size 1.27 1.27)
							)
						)
					)
					(number "A14"
						(effects
							(font
								(size 1.27 1.27)
							)
						)
					)
				)
			)
			(symbol "XCAU25P-2FFVB676I_9_1"
				(rectangle
					(start 5.08 6.35)
					(end 27.94 -58.42)
					(stroke
						(width 0.254)
						(type default)
					)
					(fill
						(type background)
					)
				)
				(polyline
					(pts
						(xy 16.51 2.54) (xy 25.4 2.54) (xy 25.4 -55.88) (xy 16.51 -55.88)
					)
					(stroke
						(width 0.254)
						(type default)
					)
					(fill
						(type background)
					)
				)
				(text "GTX 224"
					(at 6.35 2.54 0)
					(effects
						(font
							(size 1.27 1.27)
							(thickness 0.15)
						)
						(justify left bottom)
					)
				)
				(text ""
					(at 50.8 -31.75 0)
					(effects
						(font
							(size 1.27 1.27)
							(thickness 0.15)
						)
						(justify left bottom)
					)
				)
				(text ""
					(at 50.8 -31.75 0)
					(effects
						(font
							(size 1.27 1.27)
							(thickness 0.15)
						)
						(justify left bottom)
					)
				)
				(pin output line
					(at 0 0 0)
					(length 5.08)
					(name "MGTYTXP0_224"
						(effects
							(font
								(size 1.27 1.27)
							)
						)
					)
					(number "AF7"
						(effects
							(font
								(size 1.27 1.27)
							)
						)
					)
				)
				(pin output line
					(at 0 -2.54 0)
					(length 5.08)
					(name "MGTYTXN0_224"
						(effects
							(font
								(size 1.27 1.27)
							)
						)
					)
					(number "AF6"
						(effects
							(font
								(size 1.27 1.27)
							)
						)
					)
				)
				(pin output line
					(at 0 -5.08 0)
					(length 5.08)
					(name "MGTYTXP1_224"
						(effects
							(font
								(size 1.27 1.27)
							)
						)
					)
					(number "AE9"
						(effects
							(font
								(size 1.27 1.27)
							)
						)
					)
				)
				(pin output line
					(at 0 -7.62 0)
					(length 5.08)
					(name "MGTYTXN1_224"
						(effects
							(font
								(size 1.27 1.27)
							)
						)
					)
					(number "AE8"
						(effects
							(font
								(size 1.27 1.27)
							)
						)
					)
				)
				(pin output line
					(at 0 -10.16 0)
					(length 5.08)
					(name "MGTYTXP2_224"
						(effects
							(font
								(size 1.27 1.27)
							)
						)
					)
					(number "AD7"
						(effects
							(font
								(size 1.27 1.27)
							)
						)
					)
				)
				(pin output line
					(at 0 -12.7 0)
					(length 5.08)
					(name "MGTYTXN2_224"
						(effects
							(font
								(size 1.27 1.27)
							)
						)
					)
					(number "AD6"
						(effects
							(font
								(size 1.27 1.27)
							)
						)
					)
				)
				(pin output line
					(at 0 -15.24 0)
					(length 5.08)
					(name "MGTYTXP3_224"
						(effects
							(font
								(size 1.27 1.27)
							)
						)
					)
					(number "AC5"
						(effects
							(font
								(size 1.27 1.27)
							)
						)
					)
				)
				(pin output line
					(at 0 -17.78 0)
					(length 5.08)
					(name "MGTYTXN3_224"
						(effects
							(font
								(size 1.27 1.27)
							)
						)
					)
					(number "AC4"
						(effects
							(font
								(size 1.27 1.27)
							)
						)
					)
				)
				(pin input line
					(at 0 -22.86 0)
					(length 5.08)
					(name "MGTYRXP0_224"
						(effects
							(font
								(size 1.27 1.27)
							)
						)
					)
					(number "AF2"
						(effects
							(font
								(size 1.27 1.27)
							)
						)
					)
				)
				(pin input line
					(at 0 -25.4 0)
					(length 5.08)
					(name "MGTYRXN0_224"
						(effects
							(font
								(size 1.27 1.27)
							)
						)
					)
					(number "AF1"
						(effects
							(font
								(size 1.27 1.27)
							)
						)
					)
				)
				(pin input line
					(at 0 -27.94 0)
					(length 5.08)
					(name "MGTYRXP1_224"
						(effects
							(font
								(size 1.27 1.27)
							)
						)
					)
					(number "AE4"
						(effects
							(font
								(size 1.27 1.27)
							)
						)
					)
				)
				(pin input line
					(at 0 -30.48 0)
					(length 5.08)
					(name "MGTYRXN1_224"
						(effects
							(font
								(size 1.27 1.27)
							)
						)
					)
					(number "AE3"
						(effects
							(font
								(size 1.27 1.27)
							)
						)
					)
				)
				(pin input line
					(at 0 -33.02 0)
					(length 5.08)
					(name "MGTYRXP2_224"
						(effects
							(font
								(size 1.27 1.27)
							)
						)
					)
					(number "AD2"
						(effects
							(font
								(size 1.27 1.27)
							)
						)
					)
				)
				(pin input line
					(at 0 -35.56 0)
					(length 5.08)
					(name "MGTYRXN2_224"
						(effects
							(font
								(size 1.27 1.27)
							)
						)
					)
					(number "AD1"
						(effects
							(font
								(size 1.27 1.27)
							)
						)
					)
				)
				(pin input line
					(at 0 -38.1 0)
					(length 5.08)
					(name "MGTYRXP3_224"
						(effects
							(font
								(size 1.27 1.27)
							)
						)
					)
					(number "AB2"
						(effects
							(font
								(size 1.27 1.27)
							)
						)
					)
				)
				(pin input line
					(at 0 -40.64 0)
					(length 5.08)
					(name "MGTYRXN3_224"
						(effects
							(font
								(size 1.27 1.27)
							)
						)
					)
					(number "AB1"
						(effects
							(font
								(size 1.27 1.27)
							)
						)
					)
				)
				(pin input line
					(at 0 -45.72 0)
					(length 5.08)
					(name "MGTREFCLK0P_224"
						(effects
							(font
								(size 1.27 1.27)
							)
						)
					)
					(number "AB7"
						(effects
							(font
								(size 1.27 1.27)
							)
						)
					)
				)
				(pin input line
					(at 0 -48.26 0)
					(length 5.08)
					(name "MGTREFCLK0N_224"
						(effects
							(font
								(size 1.27 1.27)
							)
						)
					)
					(number "AB6"
						(effects
							(font
								(size 1.27 1.27)
							)
						)
					)
				)
				(pin input line
					(at 0 -50.8 0)
					(length 5.08)
					(name "MGTREFCLK1P_224"
						(effects
							(font
								(size 1.27 1.27)
							)
						)
					)
					(number "Y7"
						(effects
							(font
								(size 1.27 1.27)
							)
						)
					)
				)
				(pin input line
					(at 0 -53.34 0)
					(length 5.08)
					(name "MGTREFCLK1N_224"
						(effects
							(font
								(size 1.27 1.27)
							)
						)
					)
					(number "Y6"
						(effects
							(font
								(size 1.27 1.27)
							)
						)
					)
				)
			)
			(symbol "XCAU25P-2FFVB676I_10_1"
				(rectangle
					(start 5.08 6.35)
					(end 27.94 -58.42)
					(stroke
						(width 0.254)
						(type default)
					)
					(fill
						(type background)
					)
				)
				(polyline
					(pts
						(xy 16.51 2.54) (xy 25.4 2.54) (xy 25.4 -55.88) (xy 16.51 -55.88)
					)
					(stroke
						(width 0.254)
						(type default)
					)
					(fill
						(type background)
					)
				)
				(text "GTX 225"
					(at 6.35 2.54 0)
					(effects
						(font
							(size 1.27 1.27)
							(thickness 0.15)
						)
						(justify left bottom)
					)
				)
				(text ""
					(at 50.8 -31.75 0)
					(effects
						(font
							(size 1.27 1.27)
							(thickness 0.15)
						)
						(justify left bottom)
					)
				)
				(text ""
					(at 50.8 -31.75 0)
					(effects
						(font
							(size 1.27 1.27)
							(thickness 0.15)
						)
						(justify left bottom)
					)
				)
				(pin output line
					(at 0 0 0)
					(length 5.08)
					(name "MGTYTXP0_225"
						(effects
							(font
								(size 1.27 1.27)
							)
						)
					)
					(number "AA5"
						(effects
							(font
								(size 1.27 1.27)
							)
						)
					)
				)
				(pin output line
					(at 0 -2.54 0)
					(length 5.08)
					(name "MGTYTXN0_225"
						(effects
							(font
								(size 1.27 1.27)
							)
						)
					)
					(number "AA4"
						(effects
							(font
								(size 1.27 1.27)
							)
						)
					)
				)
				(pin output line
					(at 0 -5.08 0)
					(length 5.08)
					(name "MGTYTXP1_225"
						(effects
							(font
								(size 1.27 1.27)
							)
						)
					)
					(number "W5"
						(effects
							(font
								(size 1.27 1.27)
							)
						)
					)
				)
				(pin output line
					(at 0 -7.62 0)
					(length 5.08)
					(name "MGTYTXN1_225"
						(effects
							(font
								(size 1.27 1.27)
							)
						)
					)
					(number "W4"
						(effects
							(font
								(size 1.27 1.27)
							)
						)
					)
				)
				(pin output line
					(at 0 -10.16 0)
					(length 5.08)
					(name "MGTYTXP2_225"
						(effects
							(font
								(size 1.27 1.27)
							)
						)
					)
					(number "U5"
						(effects
							(font
								(size 1.27 1.27)
							)
						)
					)
				)
				(pin output line
					(at 0 -12.7 0)
					(length 5.08)
					(name "MGTYTXN2_225"
						(effects
							(font
								(size 1.27 1.27)
							)
						)
					)
					(number "U4"
						(effects
							(font
								(size 1.27 1.27)
							)
						)
					)
				)
				(pin output line
					(at 0 -15.24 0)
					(length 5.08)
					(name "MGTYTXP3_225"
						(effects
							(font
								(size 1.27 1.27)
							)
						)
					)
					(number "R5"
						(effects
							(font
								(size 1.27 1.27)
							)
						)
					)
				)
				(pin output line
					(at 0 -17.78 0)
					(length 5.08)
					(name "MGTYTXN3_225"
						(effects
							(font
								(size 1.27 1.27)
							)
						)
					)
					(number "R4"
						(effects
							(font
								(size 1.27 1.27)
							)
						)
					)
				)
				(pin input line
					(at 0 -22.86 0)
					(length 5.08)
					(name "MGTYRXP0_225"
						(effects
							(font
								(size 1.27 1.27)
							)
						)
					)
					(number "Y2"
						(effects
							(font
								(size 1.27 1.27)
							)
						)
					)
				)
				(pin input line
					(at 0 -25.4 0)
					(length 5.08)
					(name "MGTYRXN0_225"
						(effects
							(font
								(size 1.27 1.27)
							)
						)
					)
					(number "Y1"
						(effects
							(font
								(size 1.27 1.27)
							)
						)
					)
				)
				(pin input line
					(at 0 -27.94 0)
					(length 5.08)
					(name "MGTYRXP1_225"
						(effects
							(font
								(size 1.27 1.27)
							)
						)
					)
					(number "V2"
						(effects
							(font
								(size 1.27 1.27)
							)
						)
					)
				)
				(pin input line
					(at 0 -30.48 0)
					(length 5.08)
					(name "MGTYRXN1_225"
						(effects
							(font
								(size 1.27 1.27)
							)
						)
					)
					(number "V1"
						(effects
							(font
								(size 1.27 1.27)
							)
						)
					)
				)
				(pin input line
					(at 0 -33.02 0)
					(length 5.08)
					(name "MGTYRXP2_225"
						(effects
							(font
								(size 1.27 1.27)
							)
						)
					)
					(number "T2"
						(effects
							(font
								(size 1.27 1.27)
							)
						)
					)
				)
				(pin input line
					(at 0 -35.56 0)
					(length 5.08)
					(name "MGTYRXN2_225"
						(effects
							(font
								(size 1.27 1.27)
							)
						)
					)
					(number "T1"
						(effects
							(font
								(size 1.27 1.27)
							)
						)
					)
				)
				(pin input line
					(at 0 -38.1 0)
					(length 5.08)
					(name "MGTYRXP3_225"
						(effects
							(font
								(size 1.27 1.27)
							)
						)
					)
					(number "P2"
						(effects
							(font
								(size 1.27 1.27)
							)
						)
					)
				)
				(pin input line
					(at 0 -40.64 0)
					(length 5.08)
					(name "MGTYRXN3_225"
						(effects
							(font
								(size 1.27 1.27)
							)
						)
					)
					(number "P1"
						(effects
							(font
								(size 1.27 1.27)
							)
						)
					)
				)
				(pin input line
					(at 0 -45.72 0)
					(length 5.08)
					(name "MGTREFCLK0P_225"
						(effects
							(font
								(size 1.27 1.27)
							)
						)
					)
					(number "V7"
						(effects
							(font
								(size 1.27 1.27)
							)
						)
					)
				)
				(pin input line
					(at 0 -48.26 0)
					(length 5.08)
					(name "MGTREFCLK0N_225"
						(effects
							(font
								(size 1.27 1.27)
							)
						)
					)
					(number "V6"
						(effects
							(font
								(size 1.27 1.27)
							)
						)
					)
				)
				(pin input line
					(at 0 -50.8 0)
					(length 5.08)
					(name "MGTREFCLK1P_225"
						(effects
							(font
								(size 1.27 1.27)
							)
						)
					)
					(number "T7"
						(effects
							(font
								(size 1.27 1.27)
							)
						)
					)
				)
				(pin input line
					(at 0 -53.34 0)
					(length 5.08)
					(name "MGTREFCLK1N_225"
						(effects
							(font
								(size 1.27 1.27)
							)
						)
					)
					(number "T6"
						(effects
							(font
								(size 1.27 1.27)
							)
						)
					)
				)
			)
			(symbol "XCAU25P-2FFVB676I_11_1"
				(rectangle
					(start 5.08 6.35)
					(end 27.94 -58.42)
					(stroke
						(width 0.254)
						(type default)
					)
					(fill
						(type background)
					)
				)
				(polyline
					(pts
						(xy 16.51 2.54) (xy 25.4 2.54) (xy 25.4 -55.88) (xy 16.51 -55.88)
					)
					(stroke
						(width 0.254)
						(type default)
					)
					(fill
						(type background)
					)
				)
				(text "GTX 226"
					(at 6.35 2.54 0)
					(effects
						(font
							(size 1.27 1.27)
							(thickness 0.15)
						)
						(justify left bottom)
					)
				)
				(text ""
					(at 50.8 -31.75 0)
					(effects
						(font
							(size 1.27 1.27)
							(thickness 0.15)
						)
						(justify left bottom)
					)
				)
				(text ""
					(at 50.8 -31.75 0)
					(effects
						(font
							(size 1.27 1.27)
							(thickness 0.15)
						)
						(justify left bottom)
					)
				)
				(pin output line
					(at 0 0 0)
					(length 5.08)
					(name "MGTYTXP0_226"
						(effects
							(font
								(size 1.27 1.27)
							)
						)
					)
					(number "N5"
						(effects
							(font
								(size 1.27 1.27)
							)
						)
					)
				)
				(pin output line
					(at 0 -2.54 0)
					(length 5.08)
					(name "MGTYTXN0_226"
						(effects
							(font
								(size 1.27 1.27)
							)
						)
					)
					(number "N4"
						(effects
							(font
								(size 1.27 1.27)
							)
						)
					)
				)
				(pin output line
					(at 0 -5.08 0)
					(length 5.08)
					(name "MGTYTXP1_226"
						(effects
							(font
								(size 1.27 1.27)
							)
						)
					)
					(number "L5"
						(effects
							(font
								(size 1.27 1.27)
							)
						)
					)
				)
				(pin output line
					(at 0 -7.62 0)
					(length 5.08)
					(name "MGTYTXN1_226"
						(effects
							(font
								(size 1.27 1.27)
							)
						)
					)
					(number "L4"
						(effects
							(font
								(size 1.27 1.27)
							)
						)
					)
				)
				(pin output line
					(at 0 -10.16 0)
					(length 5.08)
					(name "MGTYTXP2_226"
						(effects
							(font
								(size 1.27 1.27)
							)
						)
					)
					(number "J5"
						(effects
							(font
								(size 1.27 1.27)
							)
						)
					)
				)
				(pin output line
					(at 0 -12.7 0)
					(length 5.08)
					(name "MGTYTXN2_226"
						(effects
							(font
								(size 1.27 1.27)
							)
						)
					)
					(number "J4"
						(effects
							(font
								(size 1.27 1.27)
							)
						)
					)
				)
				(pin output line
					(at 0 -15.24 0)
					(length 5.08)
					(name "MGTYTXP3_226"
						(effects
							(font
								(size 1.27 1.27)
							)
						)
					)
					(number "G5"
						(effects
							(font
								(size 1.27 1.27)
							)
						)
					)
				)
				(pin output line
					(at 0 -17.78 0)
					(length 5.08)
					(name "MGTYTXN3_226"
						(effects
							(font
								(size 1.27 1.27)
							)
						)
					)
					(number "G4"
						(effects
							(font
								(size 1.27 1.27)
							)
						)
					)
				)
				(pin input line
					(at 0 -22.86 0)
					(length 5.08)
					(name "MGTYRXP0_226"
						(effects
							(font
								(size 1.27 1.27)
							)
						)
					)
					(number "M2"
						(effects
							(font
								(size 1.27 1.27)
							)
						)
					)
				)
				(pin input line
					(at 0 -25.4 0)
					(length 5.08)
					(name "MGTYRXN0_226"
						(effects
							(font
								(size 1.27 1.27)
							)
						)
					)
					(number "M1"
						(effects
							(font
								(size 1.27 1.27)
							)
						)
					)
				)
				(pin input line
					(at 0 -27.94 0)
					(length 5.08)
					(name "MGTYRXP1_226"
						(effects
							(font
								(size 1.27 1.27)
							)
						)
					)
					(number "K2"
						(effects
							(font
								(size 1.27 1.27)
							)
						)
					)
				)
				(pin input line
					(at 0 -30.48 0)
					(length 5.08)
					(name "MGTYRXN1_226"
						(effects
							(font
								(size 1.27 1.27)
							)
						)
					)
					(number "K1"
						(effects
							(font
								(size 1.27 1.27)
							)
						)
					)
				)
				(pin input line
					(at 0 -33.02 0)
					(length 5.08)
					(name "MGTYRXP2_226"
						(effects
							(font
								(size 1.27 1.27)
							)
						)
					)
					(number "H2"
						(effects
							(font
								(size 1.27 1.27)
							)
						)
					)
				)
				(pin input line
					(at 0 -35.56 0)
					(length 5.08)
					(name "MGTYRXN2_226"
						(effects
							(font
								(size 1.27 1.27)
							)
						)
					)
					(number "H1"
						(effects
							(font
								(size 1.27 1.27)
							)
						)
					)
				)
				(pin input line
					(at 0 -38.1 0)
					(length 5.08)
					(name "MGTYRXP3_226"
						(effects
							(font
								(size 1.27 1.27)
							)
						)
					)
					(number "F2"
						(effects
							(font
								(size 1.27 1.27)
							)
						)
					)
				)
				(pin input line
					(at 0 -40.64 0)
					(length 5.08)
					(name "MGTYRXN3_226"
						(effects
							(font
								(size 1.27 1.27)
							)
						)
					)
					(number "F1"
						(effects
							(font
								(size 1.27 1.27)
							)
						)
					)
				)
				(pin input line
					(at 0 -45.72 0)
					(length 5.08)
					(name "MGTREFCLK0P_226"
						(effects
							(font
								(size 1.27 1.27)
							)
						)
					)
					(number "P7"
						(effects
							(font
								(size 1.27 1.27)
							)
						)
					)
				)
				(pin input line
					(at 0 -48.26 0)
					(length 5.08)
					(name "MGTREFCLK0N_226"
						(effects
							(font
								(size 1.27 1.27)
							)
						)
					)
					(number "P6"
						(effects
							(font
								(size 1.27 1.27)
							)
						)
					)
				)
				(pin input line
					(at 0 -50.8 0)
					(length 5.08)
					(name "MGTREFCLK1P_226"
						(effects
							(font
								(size 1.27 1.27)
							)
						)
					)
					(number "M7"
						(effects
							(font
								(size 1.27 1.27)
							)
						)
					)
				)
				(pin input line
					(at 0 -53.34 0)
					(length 5.08)
					(name "MGTREFCLK1N_226"
						(effects
							(font
								(size 1.27 1.27)
							)
						)
					)
					(number "M6"
						(effects
							(font
								(size 1.27 1.27)
							)
						)
					)
				)
			)
			(symbol "XCAU25P-2FFVB676I_12_1"
				(rectangle
					(start 5.08 2.54)
					(end 35.56 -27.94)
					(stroke
						(width 0.254)
						(type default)
					)
					(fill
						(type background)
					)
				)
				(text ""
					(at 21.59 -3.175 900)
					(effects
						(font
							(size 1.27 1.27)
							(thickness 0.15)
						)
						(justify right top)
					)
				)
				(text ""
					(at 21.59 -3.175 900)
					(effects
						(font
							(size 1.27 1.27)
							(thickness 0.15)
						)
						(justify right top)
					)
				)
				(pin input line
					(at 0 0 0)
					(length 5.08)
					(name "MGTAVTT_R"
						(effects
							(font
								(size 1.27 1.27)
							)
						)
					)
					(number "A7"
						(effects
							(font
								(size 1.27 1.27)
							)
						)
					)
				)
				(pin passive line
					(at 0 0 0)
					(length 5.08)
					(hide yes)
					(name "MGTAVTT_R"
						(effects
							(font
								(size 1.27 1.27)
							)
						)
					)
					(number "AB5"
						(effects
							(font
								(size 1.27 1.27)
							)
						)
					)
				)
				(pin passive line
					(at 0 0 0)
					(length 5.08)
					(hide yes)
					(name "MGTAVTT_R"
						(effects
							(font
								(size 1.27 1.27)
							)
						)
					)
					(number "AE7"
						(effects
							(font
								(size 1.27 1.27)
							)
						)
					)
				)
				(pin passive line
					(at 0 0 0)
					(length 5.08)
					(hide yes)
					(name "MGTAVTT_R"
						(effects
							(font
								(size 1.27 1.27)
							)
						)
					)
					(number "C7"
						(effects
							(font
								(size 1.27 1.27)
							)
						)
					)
				)
				(pin passive line
					(at 0 0 0)
					(length 5.08)
					(hide yes)
					(name "MGTAVTT_R"
						(effects
							(font
								(size 1.27 1.27)
							)
						)
					)
					(number "E7"
						(effects
							(font
								(size 1.27 1.27)
							)
						)
					)
				)
				(pin passive line
					(at 0 0 0)
					(length 5.08)
					(hide yes)
					(name "MGTAVTT_R"
						(effects
							(font
								(size 1.27 1.27)
							)
						)
					)
					(number "F5"
						(effects
							(font
								(size 1.27 1.27)
							)
						)
					)
				)
				(pin passive line
					(at 0 0 0)
					(length 5.08)
					(hide yes)
					(name "MGTAVTT_R"
						(effects
							(font
								(size 1.27 1.27)
							)
						)
					)
					(number "G7"
						(effects
							(font
								(size 1.27 1.27)
							)
						)
					)
				)
				(pin passive line
					(at 0 0 0)
					(length 5.08)
					(hide yes)
					(name "MGTAVTT_R"
						(effects
							(font
								(size 1.27 1.27)
							)
						)
					)
					(number "H5"
						(effects
							(font
								(size 1.27 1.27)
							)
						)
					)
				)
				(pin passive line
					(at 0 0 0)
					(length 5.08)
					(hide yes)
					(name "MGTAVTT_R"
						(effects
							(font
								(size 1.27 1.27)
							)
						)
					)
					(number "K5"
						(effects
							(font
								(size 1.27 1.27)
							)
						)
					)
				)
				(pin passive line
					(at 0 0 0)
					(length 5.08)
					(hide yes)
					(name "MGTAVTT_R"
						(effects
							(font
								(size 1.27 1.27)
							)
						)
					)
					(number "M5"
						(effects
							(font
								(size 1.27 1.27)
							)
						)
					)
				)
				(pin passive line
					(at 0 0 0)
					(length 5.08)
					(hide yes)
					(name "MGTAVTT_R"
						(effects
							(font
								(size 1.27 1.27)
							)
						)
					)
					(number "P5"
						(effects
							(font
								(size 1.27 1.27)
							)
						)
					)
				)
				(pin passive line
					(at 0 0 0)
					(length 5.08)
					(hide yes)
					(name "MGTAVTT_R"
						(effects
							(font
								(size 1.27 1.27)
							)
						)
					)
					(number "T5"
						(effects
							(font
								(size 1.27 1.27)
							)
						)
					)
				)
				(pin passive line
					(at 0 0 0)
					(length 5.08)
					(hide yes)
					(name "MGTAVTT_R"
						(effects
							(font
								(size 1.27 1.27)
							)
						)
					)
					(number "V5"
						(effects
							(font
								(size 1.27 1.27)
							)
						)
					)
				)
				(pin passive line
					(at 0 0 0)
					(length 5.08)
					(hide yes)
					(name "MGTAVTT_R"
						(effects
							(font
								(size 1.27 1.27)
							)
						)
					)
					(number "Y5"
						(effects
							(font
								(size 1.27 1.27)
							)
						)
					)
				)
				(pin power_in line
					(at 0 -2.54 0)
					(length 5.08)
					(name "MGTAVCC_R"
						(effects
							(font
								(size 1.27 1.27)
							)
						)
					)
					(number "AA7"
						(effects
							(font
								(size 1.27 1.27)
							)
						)
					)
				)
				(pin passive line
					(at 0 -2.54 0)
					(length 5.08)
					(hide yes)
					(name "MGTAVCC_R"
						(effects
							(font
								(size 1.27 1.27)
							)
						)
					)
					(number "AC7"
						(effects
							(font
								(size 1.27 1.27)
							)
						)
					)
				)
				(pin passive line
					(at 0 -2.54 0)
					(length 5.08)
					(hide yes)
					(name "MGTAVCC_R"
						(effects
							(font
								(size 1.27 1.27)
							)
						)
					)
					(number "J7"
						(effects
							(font
								(size 1.27 1.27)
							)
						)
					)
				)
				(pin passive line
					(at 0 -2.54 0)
					(length 5.08)
					(hide yes)
					(name "MGTAVCC_R"
						(effects
							(font
								(size 1.27 1.27)
							)
						)
					)
					(number "L7"
						(effects
							(font
								(size 1.27 1.27)
							)
						)
					)
				)
				(pin passive line
					(at 0 -2.54 0)
					(length 5.08)
					(hide yes)
					(name "MGTAVCC_R"
						(effects
							(font
								(size 1.27 1.27)
							)
						)
					)
					(number "N7"
						(effects
							(font
								(size 1.27 1.27)
							)
						)
					)
				)
				(pin passive line
					(at 0 -2.54 0)
					(length 5.08)
					(hide yes)
					(name "MGTAVCC_R"
						(effects
							(font
								(size 1.27 1.27)
							)
						)
					)
					(number "W7"
						(effects
							(font
								(size 1.27 1.27)
							)
						)
					)
				)
				(pin input line
					(at 0 -5.08 0)
					(length 5.08)
					(name "MGTRREF_R"
						(effects
							(font
								(size 1.27 1.27)
							)
						)
					)
					(number "AD9"
						(effects
							(font
								(size 1.27 1.27)
							)
						)
					)
				)
				(pin power_in line
					(at 0 -7.62 0)
					(length 5.08)
					(name "MGTVCCAUX_R"
						(effects
							(font
								(size 1.27 1.27)
							)
						)
					)
					(number "R7"
						(effects
							(font
								(size 1.27 1.27)
							)
						)
					)
				)
				(pin passive line
					(at 0 -7.62 0)
					(length 5.08)
					(hide yes)
					(name "MGTVCCAUX_R"
						(effects
							(font
								(size 1.27 1.27)
							)
						)
					)
					(number "U7"
						(effects
							(font
								(size 1.27 1.27)
							)
						)
					)
				)
				(pin input line
					(at 0 -10.16 0)
					(length 5.08)
					(name "MGTAVTTRCAL_R"
						(effects
							(font
								(size 1.27 1.27)
							)
						)
					)
					(number "AD8"
						(effects
							(font
								(size 1.27 1.27)
							)
						)
					)
				)
				(pin input line
					(at 0 -20.32 0)
					(length 5.08)
					(name "RSVDGND"
						(effects
							(font
								(size 1.27 1.27)
							)
						)
					)
					(number "W11"
						(effects
							(font
								(size 1.27 1.27)
							)
						)
					)
				)
				(pin input line
					(at 0 -22.86 0)
					(length 5.08)
					(name "GNDADC"
						(effects
							(font
								(size 1.27 1.27)
							)
						)
					)
					(number "N13"
						(effects
							(font
								(size 1.27 1.27)
							)
						)
					)
				)
				(pin power_in line
					(at 0 -25.4 0)
					(length 5.08)
					(name "GND"
						(effects
							(font
								(size 1.27 1.27)
							)
						)
					)
					(number "A1"
						(effects
							(font
								(size 1.27 1.27)
							)
						)
					)
				)
				(pin passive line
					(at 0 -25.4 0)
					(length 5.08)
					(hide yes)
					(name "GND"
						(effects
							(font
								(size 1.27 1.27)
							)
						)
					)
					(number "A11"
						(effects
							(font
								(size 1.27 1.27)
							)
						)
					)
				)
				(pin passive line
					(at 0 -25.4 0)
					(length 5.08)
					(hide yes)
					(name "GND"
						(effects
							(font
								(size 1.27 1.27)
							)
						)
					)
					(number "A16"
						(effects
							(font
								(size 1.27 1.27)
							)
						)
					)
				)
				(pin passive line
					(at 0 -25.4 0)
					(length 5.08)
					(hide yes)
					(name "GND"
						(effects
							(font
								(size 1.27 1.27)
							)
						)
					)
					(number "A2"
						(effects
							(font
								(size 1.27 1.27)
							)
						)
					)
				)
				(pin passive line
					(at 0 -25.4 0)
					(length 5.08)
					(hide yes)
					(name "GND"
						(effects
							(font
								(size 1.27 1.27)
							)
						)
					)
					(number "A21"
						(effects
							(font
								(size 1.27 1.27)
							)
						)
					)
				)
				(pin passive line
					(at 0 -25.4 0)
					(length 5.08)
					(hide yes)
					(name "GND"
						(effects
							(font
								(size 1.27 1.27)
							)
						)
					)
					(number "A26"
						(effects
							(font
								(size 1.27 1.27)
							)
						)
					)
				)
				(pin passive line
					(at 0 -25.4 0)
					(length 5.08)
					(hide yes)
					(name "GND"
						(effects
							(font
								(size 1.27 1.27)
							)
						)
					)
					(number "A5"
						(effects
							(font
								(size 1.27 1.27)
							)
						)
					)
				)
				(pin passive line
					(at 0 -25.4 0)
					(length 5.08)
					(hide yes)
					(name "GND"
						(effects
							(font
								(size 1.27 1.27)
							)
						)
					)
					(number "A6"
						(effects
							(font
								(size 1.27 1.27)
							)
						)
					)
				)
				(pin passive line
					(at 0 -25.4 0)
					(length 5.08)
					(hide yes)
					(name "GND"
						(effects
							(font
								(size 1.27 1.27)
							)
						)
					)
					(number "A8"
						(effects
							(font
								(size 1.27 1.27)
							)
						)
					)
				)
				(pin passive line
					(at 0 -25.4 0)
					(length 5.08)
					(hide yes)
					(name "GND"
						(effects
							(font
								(size 1.27 1.27)
							)
						)
					)
					(number "AA1"
						(effects
							(font
								(size 1.27 1.27)
							)
						)
					)
				)
				(pin passive line
					(at 0 -25.4 0)
					(length 5.08)
					(hide yes)
					(name "GND"
						(effects
							(font
								(size 1.27 1.27)
							)
						)
					)
					(number "AA16"
						(effects
							(font
								(size 1.27 1.27)
							)
						)
					)
				)
				(pin passive line
					(at 0 -25.4 0)
					(length 5.08)
					(hide yes)
					(name "GND"
						(effects
							(font
								(size 1.27 1.27)
							)
						)
					)
					(number "AA2"
						(effects
							(font
								(size 1.27 1.27)
							)
						)
					)
				)
				(pin passive line
					(at 0 -25.4 0)
					(length 5.08)
					(hide yes)
					(name "GND"
						(effects
							(font
								(size 1.27 1.27)
							)
						)
					)
					(number "AA26"
						(effects
							(font
								(size 1.27 1.27)
							)
						)
					)
				)
				(pin passive line
					(at 0 -25.4 0)
					(length 5.08)
					(hide yes)
					(name "GND"
						(effects
							(font
								(size 1.27 1.27)
							)
						)
					)
					(number "AA3"
						(effects
							(font
								(size 1.27 1.27)
							)
						)
					)
				)
				(pin passive line
					(at 0 -25.4 0)
					(length 5.08)
					(hide yes)
					(name "GND"
						(effects
							(font
								(size 1.27 1.27)
							)
						)
					)
					(number "AA6"
						(effects
							(font
								(size 1.27 1.27)
							)
						)
					)
				)
				(pin passive line
					(at 0 -25.4 0)
					(length 5.08)
					(hide yes)
					(name "GND"
						(effects
							(font
								(size 1.27 1.27)
							)
						)
					)
					(number "AA8"
						(effects
							(font
								(size 1.27 1.27)
							)
						)
					)
				)
				(pin passive line
					(at 0 -25.4 0)
					(length 5.08)
					(hide yes)
					(name "GND"
						(effects
							(font
								(size 1.27 1.27)
							)
						)
					)
					(number "AB13"
						(effects
							(font
								(size 1.27 1.27)
							)
						)
					)
				)
				(pin passive line
					(at 0 -25.4 0)
					(length 5.08)
					(hide yes)
					(name "GND"
						(effects
							(font
								(size 1.27 1.27)
							)
						)
					)
					(number "AB23"
						(effects
							(font
								(size 1.27 1.27)
							)
						)
					)
				)
				(pin passive line
					(at 0 -25.4 0)
					(length 5.08)
					(hide yes)
					(name "GND"
						(effects
							(font
								(size 1.27 1.27)
							)
						)
					)
					(number "AB3"
						(effects
							(font
								(size 1.27 1.27)
							)
						)
					)
				)
				(pin passive line
					(at 0 -25.4 0)
					(length 5.08)
					(hide yes)
					(name "GND"
						(effects
							(font
								(size 1.27 1.27)
							)
						)
					)
					(number "AB4"
						(effects
							(font
								(size 1.27 1.27)
							)
						)
					)
				)
				(pin passive line
					(at 0 -25.4 0)
					(length 5.08)
					(hide yes)
					(name "GND"
						(effects
							(font
								(size 1.27 1.27)
							)
						)
					)
					(number "AB8"
						(effects
							(font
								(size 1.27 1.27)
							)
						)
					)
				)
				(pin passive line
					(at 0 -25.4 0)
					(length 5.08)
					(hide yes)
					(name "GND"
						(effects
							(font
								(size 1.27 1.27)
							)
						)
					)
					(number "AC1"
						(effects
							(font
								(size 1.27 1.27)
							)
						)
					)
				)
				(pin passive line
					(at 0 -25.4 0)
					(length 5.08)
					(hide yes)
					(name "GND"
						(effects
							(font
								(size 1.27 1.27)
							)
						)
					)
					(number "AC10"
						(effects
							(font
								(size 1.27 1.27)
							)
						)
					)
				)
				(pin passive line
					(at 0 -25.4 0)
					(length 5.08)
					(hide yes)
					(name "GND"
						(effects
							(font
								(size 1.27 1.27)
							)
						)
					)
					(number "AC2"
						(effects
							(font
								(size 1.27 1.27)
							)
						)
					)
				)
				(pin passive line
					(at 0 -25.4 0)
					(length 5.08)
					(hide yes)
					(name "GND"
						(effects
							(font
								(size 1.27 1.27)
							)
						)
					)
					(number "AC20"
						(effects
							(font
								(size 1.27 1.27)
							)
						)
					)
				)
				(pin passive line
					(at 0 -25.4 0)
					(length 5.08)
					(hide yes)
					(name "GND"
						(effects
							(font
								(size 1.27 1.27)
							)
						)
					)
					(number "AC25"
						(effects
							(font
								(size 1.27 1.27)
							)
						)
					)
				)
				(pin passive line
					(at 0 -25.4 0)
					(length 5.08)
					(hide yes)
					(name "GND"
						(effects
							(font
								(size 1.27 1.27)
							)
						)
					)
					(number "AC3"
						(effects
							(font
								(size 1.27 1.27)
							)
						)
					)
				)
				(pin passive line
					(at 0 -25.4 0)
					(length 5.08)
					(hide yes)
					(name "GND"
						(effects
							(font
								(size 1.27 1.27)
							)
						)
					)
					(number "AC6"
						(effects
							(font
								(size 1.27 1.27)
							)
						)
					)
				)
				(pin passive line
					(at 0 -25.4 0)
					(length 5.08)
					(hide yes)
					(name "GND"
						(effects
							(font
								(size 1.27 1.27)
							)
						)
					)
					(number "AC8"
						(effects
							(font
								(size 1.27 1.27)
							)
						)
					)
				)
				(pin passive line
					(at 0 -25.4 0)
					(length 5.08)
					(hide yes)
					(name "GND"
						(effects
							(font
								(size 1.27 1.27)
							)
						)
					)
					(number "AC9"
						(effects
							(font
								(size 1.27 1.27)
							)
						)
					)
				)
				(pin passive line
					(at 0 -25.4 0)
					(length 5.08)
					(hide yes)
					(name "GND"
						(effects
							(font
								(size 1.27 1.27)
							)
						)
					)
					(number "AD10"
						(effects
							(font
								(size 1.27 1.27)
							)
						)
					)
				)
				(pin passive line
					(at 0 -25.4 0)
					(length 5.08)
					(hide yes)
					(name "GND"
						(effects
							(font
								(size 1.27 1.27)
							)
						)
					)
					(number "AD17"
						(effects
							(font
								(size 1.27 1.27)
							)
						)
					)
				)
				(pin passive line
					(at 0 -25.4 0)
					(length 5.08)
					(hide yes)
					(name "GND"
						(effects
							(font
								(size 1.27 1.27)
							)
						)
					)
					(number "AD3"
						(effects
							(font
								(size 1.27 1.27)
							)
						)
					)
				)
				(pin passive line
					(at 0 -25.4 0)
					(length 5.08)
					(hide yes)
					(name "GND"
						(effects
							(font
								(size 1.27 1.27)
							)
						)
					)
					(number "AD4"
						(effects
							(font
								(size 1.27 1.27)
							)
						)
					)
				)
				(pin passive line
					(at 0 -25.4 0)
					(length 5.08)
					(hide yes)
					(name "GND"
						(effects
							(font
								(size 1.27 1.27)
							)
						)
					)
					(number "AD5"
						(effects
							(font
								(size 1.27 1.27)
							)
						)
					)
				)
				(pin passive line
					(at 0 -25.4 0)
					(length 5.08)
					(hide yes)
					(name "GND"
						(effects
							(font
								(size 1.27 1.27)
							)
						)
					)
					(number "AE1"
						(effects
							(font
								(size 1.27 1.27)
							)
						)
					)
				)
				(pin passive line
					(at 0 -25.4 0)
					(length 5.08)
					(hide yes)
					(name "GND"
						(effects
							(font
								(size 1.27 1.27)
							)
						)
					)
					(number "AE10"
						(effects
							(font
								(size 1.27 1.27)
							)
						)
					)
				)
				(pin passive line
					(at 0 -25.4 0)
					(length 5.08)
					(hide yes)
					(name "GND"
						(effects
							(font
								(size 1.27 1.27)
							)
						)
					)
					(number "AE14"
						(effects
							(font
								(size 1.27 1.27)
							)
						)
					)
				)
				(pin passive line
					(at 0 -25.4 0)
					(length 5.08)
					(hide yes)
					(name "GND"
						(effects
							(font
								(size 1.27 1.27)
							)
						)
					)
					(number "AE19"
						(effects
							(font
								(size 1.27 1.27)
							)
						)
					)
				)
				(pin passive line
					(at 0 -25.4 0)
					(length 5.08)
					(hide yes)
					(name "GND"
						(effects
							(font
								(size 1.27 1.27)
							)
						)
					)
					(number "AE2"
						(effects
							(font
								(size 1.27 1.27)
							)
						)
					)
				)
				(pin passive line
					(at 0 -25.4 0)
					(length 5.08)
					(hide yes)
					(name "GND"
						(effects
							(font
								(size 1.27 1.27)
							)
						)
					)
					(number "AE24"
						(effects
							(font
								(size 1.27 1.27)
							)
						)
					)
				)
				(pin passive line
					(at 0 -25.4 0)
					(length 5.08)
					(hide yes)
					(name "GND"
						(effects
							(font
								(size 1.27 1.27)
							)
						)
					)
					(number "AE5"
						(effects
							(font
								(size 1.27 1.27)
							)
						)
					)
				)
				(pin passive line
					(at 0 -25.4 0)
					(length 5.08)
					(hide yes)
					(name "GND"
						(effects
							(font
								(size 1.27 1.27)
							)
						)
					)
					(number "AE6"
						(effects
							(font
								(size 1.27 1.27)
							)
						)
					)
				)
				(pin passive line
					(at 0 -25.4 0)
					(length 5.08)
					(hide yes)
					(name "GND"
						(effects
							(font
								(size 1.27 1.27)
							)
						)
					)
					(number "AF10"
						(effects
							(font
								(size 1.27 1.27)
							)
						)
					)
				)
				(pin passive line
					(at 0 -25.4 0)
					(length 5.08)
					(hide yes)
					(name "GND"
						(effects
							(font
								(size 1.27 1.27)
							)
						)
					)
					(number "AF11"
						(effects
							(font
								(size 1.27 1.27)
							)
						)
					)
				)
				(pin passive line
					(at 0 -25.4 0)
					(length 5.08)
					(hide yes)
					(name "GND"
						(effects
							(font
								(size 1.27 1.27)
							)
						)
					)
					(number "AF16"
						(effects
							(font
								(size 1.27 1.27)
							)
						)
					)
				)
				(pin passive line
					(at 0 -25.4 0)
					(length 5.08)
					(hide yes)
					(name "GND"
						(effects
							(font
								(size 1.27 1.27)
							)
						)
					)
					(number "AF21"
						(effects
							(font
								(size 1.27 1.27)
							)
						)
					)
				)
				(pin passive line
					(at 0 -25.4 0)
					(length 5.08)
					(hide yes)
					(name "GND"
						(effects
							(font
								(size 1.27 1.27)
							)
						)
					)
					(number "AF26"
						(effects
							(font
								(size 1.27 1.27)
							)
						)
					)
				)
				(pin passive line
					(at 0 -25.4 0)
					(length 5.08)
					(hide yes)
					(name "GND"
						(effects
							(font
								(size 1.27 1.27)
							)
						)
					)
					(number "AF3"
						(effects
							(font
								(size 1.27 1.27)
							)
						)
					)
				)
				(pin passive line
					(at 0 -25.4 0)
					(length 5.08)
					(hide yes)
					(name "GND"
						(effects
							(font
								(size 1.27 1.27)
							)
						)
					)
					(number "AF4"
						(effects
							(font
								(size 1.27 1.27)
							)
						)
					)
				)
				(pin passive line
					(at 0 -25.4 0)
					(length 5.08)
					(hide yes)
					(name "GND"
						(effects
							(font
								(size 1.27 1.27)
							)
						)
					)
					(number "AF5"
						(effects
							(font
								(size 1.27 1.27)
							)
						)
					)
				)
				(pin passive line
					(at 0 -25.4 0)
					(length 5.08)
					(hide yes)
					(name "GND"
						(effects
							(font
								(size 1.27 1.27)
							)
						)
					)
					(number "AF8"
						(effects
							(font
								(size 1.27 1.27)
							)
						)
					)
				)
				(pin passive line
					(at 0 -25.4 0)
					(length 5.08)
					(hide yes)
					(name "GND"
						(effects
							(font
								(size 1.27 1.27)
							)
						)
					)
					(number "AF9"
						(effects
							(font
								(size 1.27 1.27)
							)
						)
					)
				)
				(pin passive line
					(at 0 -25.4 0)
					(length 5.08)
					(hide yes)
					(name "GND"
						(effects
							(font
								(size 1.27 1.27)
							)
						)
					)
					(number "B13"
						(effects
							(font
								(size 1.27 1.27)
							)
						)
					)
				)
				(pin passive line
					(at 0 -25.4 0)
					(length 5.08)
					(hide yes)
					(name "GND"
						(effects
							(font
								(size 1.27 1.27)
							)
						)
					)
					(number "B18"
						(effects
							(font
								(size 1.27 1.27)
							)
						)
					)
				)
				(pin passive line
					(at 0 -25.4 0)
					(length 5.08)
					(hide yes)
					(name "GND"
						(effects
							(font
								(size 1.27 1.27)
							)
						)
					)
					(number "B23"
						(effects
							(font
								(size 1.27 1.27)
							)
						)
					)
				)
				(pin passive line
					(at 0 -25.4 0)
					(length 5.08)
					(hide yes)
					(name "GND"
						(effects
							(font
								(size 1.27 1.27)
							)
						)
					)
					(number "B3"
						(effects
							(font
								(size 1.27 1.27)
							)
						)
					)
				)
				(pin passive line
					(at 0 -25.4 0)
					(length 5.08)
					(hide yes)
					(name "GND"
						(effects
							(font
								(size 1.27 1.27)
							)
						)
					)
					(number "B4"
						(effects
							(font
								(size 1.27 1.27)
							)
						)
					)
				)
				(pin passive line
					(at 0 -25.4 0)
					(length 5.08)
					(hide yes)
					(name "GND"
						(effects
							(font
								(size 1.27 1.27)
							)
						)
					)
					(number "B5"
						(effects
							(font
								(size 1.27 1.27)
							)
						)
					)
				)
				(pin passive line
					(at 0 -25.4 0)
					(length 5.08)
					(hide yes)
					(name "GND"
						(effects
							(font
								(size 1.27 1.27)
							)
						)
					)
					(number "B8"
						(effects
							(font
								(size 1.27 1.27)
							)
						)
					)
				)
				(pin passive line
					(at 0 -25.4 0)
					(length 5.08)
					(hide yes)
					(name "GND"
						(effects
							(font
								(size 1.27 1.27)
							)
						)
					)
					(number "C1"
						(effects
							(font
								(size 1.27 1.27)
							)
						)
					)
				)
				(pin passive line
					(at 0 -25.4 0)
					(length 5.08)
					(hide yes)
					(name "GND"
						(effects
							(font
								(size 1.27 1.27)
							)
						)
					)
					(number "C10"
						(effects
							(font
								(size 1.27 1.27)
							)
						)
					)
				)
				(pin passive line
					(at 0 -25.4 0)
					(length 5.08)
					(hide yes)
					(name "GND"
						(effects
							(font
								(size 1.27 1.27)
							)
						)
					)
					(number "C15"
						(effects
							(font
								(size 1.27 1.27)
							)
						)
					)
				)
				(pin passive line
					(at 0 -25.4 0)
					(length 5.08)
					(hide yes)
					(name "GND"
						(effects
							(font
								(size 1.27 1.27)
							)
						)
					)
					(number "C2"
						(effects
							(font
								(size 1.27 1.27)
							)
						)
					)
				)
				(pin passive line
					(at 0 -25.4 0)
					(length 5.08)
					(hide yes)
					(name "GND"
						(effects
							(font
								(size 1.27 1.27)
							)
						)
					)
					(number "C25"
						(effects
							(font
								(size 1.27 1.27)
							)
						)
					)
				)
				(pin passive line
					(at 0 -25.4 0)
					(length 5.08)
					(hide yes)
					(name "GND"
						(effects
							(font
								(size 1.27 1.27)
							)
						)
					)
					(number "C5"
						(effects
							(font
								(size 1.27 1.27)
							)
						)
					)
				)
				(pin passive line
					(at 0 -25.4 0)
					(length 5.08)
					(hide yes)
					(name "GND"
						(effects
							(font
								(size 1.27 1.27)
							)
						)
					)
					(number "C6"
						(effects
							(font
								(size 1.27 1.27)
							)
						)
					)
				)
				(pin passive line
					(at 0 -25.4 0)
					(length 5.08)
					(hide yes)
					(name "GND"
						(effects
							(font
								(size 1.27 1.27)
							)
						)
					)
					(number "C8"
						(effects
							(font
								(size 1.27 1.27)
							)
						)
					)
				)
				(pin passive line
					(at 0 -25.4 0)
					(length 5.08)
					(hide yes)
					(name "GND"
						(effects
							(font
								(size 1.27 1.27)
							)
						)
					)
					(number "D12"
						(effects
							(font
								(size 1.27 1.27)
							)
						)
					)
				)
				(pin passive line
					(at 0 -25.4 0)
					(length 5.08)
					(hide yes)
					(name "GND"
						(effects
							(font
								(size 1.27 1.27)
							)
						)
					)
					(number "D22"
						(effects
							(font
								(size 1.27 1.27)
							)
						)
					)
				)
				(pin passive line
					(at 0 -25.4 0)
					(length 5.08)
					(hide yes)
					(name "GND"
						(effects
							(font
								(size 1.27 1.27)
							)
						)
					)
					(number "D3"
						(effects
							(font
								(size 1.27 1.27)
							)
						)
					)
				)
				(pin passive line
					(at 0 -25.4 0)
					(length 5.08)
					(hide yes)
					(name "GND"
						(effects
							(font
								(size 1.27 1.27)
							)
						)
					)
					(number "D4"
						(effects
							(font
								(size 1.27 1.27)
							)
						)
					)
				)
				(pin passive line
					(at 0 -25.4 0)
					(length 5.08)
					(hide yes)
					(name "GND"
						(effects
							(font
								(size 1.27 1.27)
							)
						)
					)
					(number "D5"
						(effects
							(font
								(size 1.27 1.27)
							)
						)
					)
				)
				(pin passive line
					(at 0 -25.4 0)
					(length 5.08)
					(hide yes)
					(name "GND"
						(effects
							(font
								(size 1.27 1.27)
							)
						)
					)
					(number "D8"
						(effects
							(font
								(size 1.27 1.27)
							)
						)
					)
				)
				(pin passive line
					(at 0 -25.4 0)
					(length 5.08)
					(hide yes)
					(name "GND"
						(effects
							(font
								(size 1.27 1.27)
							)
						)
					)
					(number "E1"
						(effects
							(font
								(size 1.27 1.27)
							)
						)
					)
				)
				(pin passive line
					(at 0 -25.4 0)
					(length 5.08)
					(hide yes)
					(name "GND"
						(effects
							(font
								(size 1.27 1.27)
							)
						)
					)
					(number "E19"
						(effects
							(font
								(size 1.27 1.27)
							)
						)
					)
				)
				(pin passive line
					(at 0 -25.4 0)
					(length 5.08)
					(hide yes)
					(name "GND"
						(effects
							(font
								(size 1.27 1.27)
							)
						)
					)
					(number "E2"
						(effects
							(font
								(size 1.27 1.27)
							)
						)
					)
				)
				(pin passive line
					(at 0 -25.4 0)
					(length 5.08)
					(hide yes)
					(name "GND"
						(effects
							(font
								(size 1.27 1.27)
							)
						)
					)
					(number "E3"
						(effects
							(font
								(size 1.27 1.27)
							)
						)
					)
				)
				(pin passive line
					(at 0 -25.4 0)
					(length 5.08)
					(hide yes)
					(name "GND"
						(effects
							(font
								(size 1.27 1.27)
							)
						)
					)
					(number "E6"
						(effects
							(font
								(size 1.27 1.27)
							)
						)
					)
				)
				(pin passive line
					(at 0 -25.4 0)
					(length 5.08)
					(hide yes)
					(name "GND"
						(effects
							(font
								(size 1.27 1.27)
							)
						)
					)
					(number "E8"
						(effects
							(font
								(size 1.27 1.27)
							)
						)
					)
				)
				(pin passive line
					(at 0 -25.4 0)
					(length 5.08)
					(hide yes)
					(name "GND"
						(effects
							(font
								(size 1.27 1.27)
							)
						)
					)
					(number "F11"
						(effects
							(font
								(size 1.27 1.27)
							)
						)
					)
				)
				(pin passive line
					(at 0 -25.4 0)
					(length 5.08)
					(hide yes)
					(name "GND"
						(effects
							(font
								(size 1.27 1.27)
							)
						)
					)
					(number "F16"
						(effects
							(font
								(size 1.27 1.27)
							)
						)
					)
				)
				(pin passive line
					(at 0 -25.4 0)
					(length 5.08)
					(hide yes)
					(name "GND"
						(effects
							(font
								(size 1.27 1.27)
							)
						)
					)
					(number "F21"
						(effects
							(font
								(size 1.27 1.27)
							)
						)
					)
				)
				(pin passive line
					(at 0 -25.4 0)
					(length 5.08)
					(hide yes)
					(name "GND"
						(effects
							(font
								(size 1.27 1.27)
							)
						)
					)
					(number "F26"
						(effects
							(font
								(size 1.27 1.27)
							)
						)
					)
				)
				(pin passive line
					(at 0 -25.4 0)
					(length 5.08)
					(hide yes)
					(name "GND"
						(effects
							(font
								(size 1.27 1.27)
							)
						)
					)
					(number "F3"
						(effects
							(font
								(size 1.27 1.27)
							)
						)
					)
				)
				(pin passive line
					(at 0 -25.4 0)
					(length 5.08)
					(hide yes)
					(name "GND"
						(effects
							(font
								(size 1.27 1.27)
							)
						)
					)
					(number "F4"
						(effects
							(font
								(size 1.27 1.27)
							)
						)
					)
				)
				(pin passive line
					(at 0 -25.4 0)
					(length 5.08)
					(hide yes)
					(name "GND"
						(effects
							(font
								(size 1.27 1.27)
							)
						)
					)
					(number "F8"
						(effects
							(font
								(size 1.27 1.27)
							)
						)
					)
				)
				(pin passive line
					(at 0 -25.4 0)
					(length 5.08)
					(hide yes)
					(name "GND"
						(effects
							(font
								(size 1.27 1.27)
							)
						)
					)
					(number "G1"
						(effects
							(font
								(size 1.27 1.27)
							)
						)
					)
				)
				(pin passive line
					(at 0 -25.4 0)
					(length 5.08)
					(hide yes)
					(name "GND"
						(effects
							(font
								(size 1.27 1.27)
							)
						)
					)
					(number "G13"
						(effects
							(font
								(size 1.27 1.27)
							)
						)
					)
				)
				(pin passive line
					(at 0 -25.4 0)
					(length 5.08)
					(hide yes)
					(name "GND"
						(effects
							(font
								(size 1.27 1.27)
							)
						)
					)
					(number "G2"
						(effects
							(font
								(size 1.27 1.27)
							)
						)
					)
				)
				(pin passive line
					(at 0 -25.4 0)
					(length 5.08)
					(hide yes)
					(name "GND"
						(effects
							(font
								(size 1.27 1.27)
							)
						)
					)
					(number "G23"
						(effects
							(font
								(size 1.27 1.27)
							)
						)
					)
				)
				(pin passive line
					(at 0 -25.4 0)
					(length 5.08)
					(hide yes)
					(name "GND"
						(effects
							(font
								(size 1.27 1.27)
							)
						)
					)
					(number "G3"
						(effects
							(font
								(size 1.27 1.27)
							)
						)
					)
				)
				(pin passive line
					(at 0 -25.4 0)
					(length 5.08)
					(hide yes)
					(name "GND"
						(effects
							(font
								(size 1.27 1.27)
							)
						)
					)
					(number "G6"
						(effects
							(font
								(size 1.27 1.27)
							)
						)
					)
				)
				(pin passive line
					(at 0 -25.4 0)
					(length 5.08)
					(hide yes)
					(name "GND"
						(effects
							(font
								(size 1.27 1.27)
							)
						)
					)
					(number "G8"
						(effects
							(font
								(size 1.27 1.27)
							)
						)
					)
				)
				(pin passive line
					(at 0 -25.4 0)
					(length 5.08)
					(hide yes)
					(name "GND"
						(effects
							(font
								(size 1.27 1.27)
							)
						)
					)
					(number "H20"
						(effects
							(font
								(size 1.27 1.27)
							)
						)
					)
				)
				(pin passive line
					(at 0 -25.4 0)
					(length 5.08)
					(hide yes)
					(name "GND"
						(effects
							(font
								(size 1.27 1.27)
							)
						)
					)
					(number "H3"
						(effects
							(font
								(size 1.27 1.27)
							)
						)
					)
				)
				(pin passive line
					(at 0 -25.4 0)
					(length 5.08)
					(hide yes)
					(name "GND"
						(effects
							(font
								(size 1.27 1.27)
							)
						)
					)
					(number "H4"
						(effects
							(font
								(size 1.27 1.27)
							)
						)
					)
				)
				(pin passive line
					(at 0 -25.4 0)
					(length 5.08)
					(hide yes)
					(name "GND"
						(effects
							(font
								(size 1.27 1.27)
							)
						)
					)
					(number "H8"
						(effects
							(font
								(size 1.27 1.27)
							)
						)
					)
				)
				(pin passive line
					(at 0 -25.4 0)
					(length 5.08)
					(hide yes)
					(name "GND"
						(effects
							(font
								(size 1.27 1.27)
							)
						)
					)
					(number "J1"
						(effects
							(font
								(size 1.27 1.27)
							)
						)
					)
				)
				(pin passive line
					(at 0 -25.4 0)
					(length 5.08)
					(hide yes)
					(name "GND"
						(effects
							(font
								(size 1.27 1.27)
							)
						)
					)
					(number "J17"
						(effects
							(font
								(size 1.27 1.27)
							)
						)
					)
				)
				(pin passive line
					(at 0 -25.4 0)
					(length 5.08)
					(hide yes)
					(name "GND"
						(effects
							(font
								(size 1.27 1.27)
							)
						)
					)
					(number "J2"
						(effects
							(font
								(size 1.27 1.27)
							)
						)
					)
				)
				(pin passive line
					(at 0 -25.4 0)
					(length 5.08)
					(hide yes)
					(name "GND"
						(effects
							(font
								(size 1.27 1.27)
							)
						)
					)
					(number "J3"
						(effects
							(font
								(size 1.27 1.27)
							)
						)
					)
				)
				(pin passive line
					(at 0 -25.4 0)
					(length 5.08)
					(hide yes)
					(name "GND"
						(effects
							(font
								(size 1.27 1.27)
							)
						)
					)
					(number "J6"
						(effects
							(font
								(size 1.27 1.27)
							)
						)
					)
				)
				(pin passive line
					(at 0 -25.4 0)
					(length 5.08)
					(hide yes)
					(name "GND"
						(effects
							(font
								(size 1.27 1.27)
							)
						)
					)
					(number "J8"
						(effects
							(font
								(size 1.27 1.27)
							)
						)
					)
				)
				(pin passive line
					(at 0 -25.4 0)
					(length 5.08)
					(hide yes)
					(name "GND"
						(effects
							(font
								(size 1.27 1.27)
							)
						)
					)
					(number "K12"
						(effects
							(font
								(size 1.27 1.27)
							)
						)
					)
				)
				(pin passive line
					(at 0 -25.4 0)
					(length 5.08)
					(hide yes)
					(name "GND"
						(effects
							(font
								(size 1.27 1.27)
							)
						)
					)
					(number "K14"
						(effects
							(font
								(size 1.27 1.27)
							)
						)
					)
				)
				(pin passive line
					(at 0 -25.4 0)
					(length 5.08)
					(hide yes)
					(name "GND"
						(effects
							(font
								(size 1.27 1.27)
							)
						)
					)
					(number "K16"
						(effects
							(font
								(size 1.27 1.27)
							)
						)
					)
				)
				(pin passive line
					(at 0 -25.4 0)
					(length 5.08)
					(hide yes)
					(name "GND"
						(effects
							(font
								(size 1.27 1.27)
							)
						)
					)
					(number "K19"
						(effects
							(font
								(size 1.27 1.27)
							)
						)
					)
				)
				(pin passive line
					(at 0 -25.4 0)
					(length 5.08)
					(hide yes)
					(name "GND"
						(effects
							(font
								(size 1.27 1.27)
							)
						)
					)
					(number "K24"
						(effects
							(font
								(size 1.27 1.27)
							)
						)
					)
				)
				(pin passive line
					(at 0 -25.4 0)
					(length 5.08)
					(hide yes)
					(name "GND"
						(effects
							(font
								(size 1.27 1.27)
							)
						)
					)
					(number "K3"
						(effects
							(font
								(size 1.27 1.27)
							)
						)
					)
				)
				(pin passive line
					(at 0 -25.4 0)
					(length 5.08)
					(hide yes)
					(name "GND"
						(effects
							(font
								(size 1.27 1.27)
							)
						)
					)
					(number "K4"
						(effects
							(font
								(size 1.27 1.27)
							)
						)
					)
				)
				(pin passive line
					(at 0 -25.4 0)
					(length 5.08)
					(hide yes)
					(name "GND"
						(effects
							(font
								(size 1.27 1.27)
							)
						)
					)
					(number "K8"
						(effects
							(font
								(size 1.27 1.27)
							)
						)
					)
				)
				(pin passive line
					(at 0 -25.4 0)
					(length 5.08)
					(hide yes)
					(name "GND"
						(effects
							(font
								(size 1.27 1.27)
							)
						)
					)
					(number "L1"
						(effects
							(font
								(size 1.27 1.27)
							)
						)
					)
				)
				(pin passive line
					(at 0 -25.4 0)
					(length 5.08)
					(hide yes)
					(name "GND"
						(effects
							(font
								(size 1.27 1.27)
							)
						)
					)
					(number "L11"
						(effects
							(font
								(size 1.27 1.27)
							)
						)
					)
				)
				(pin passive line
					(at 0 -25.4 0)
					(length 5.08)
					(hide yes)
					(name "GND"
						(effects
							(font
								(size 1.27 1.27)
							)
						)
					)
					(number "L13"
						(effects
							(font
								(size 1.27 1.27)
							)
						)
					)
				)
				(pin passive line
					(at 0 -25.4 0)
					(length 5.08)
					(hide yes)
					(name "GND"
						(effects
							(font
								(size 1.27 1.27)
							)
						)
					)
					(number "L15"
						(effects
							(font
								(size 1.27 1.27)
							)
						)
					)
				)
				(pin passive line
					(at 0 -25.4 0)
					(length 5.08)
					(hide yes)
					(name "GND"
						(effects
							(font
								(size 1.27 1.27)
							)
						)
					)
					(number "L17"
						(effects
							(font
								(size 1.27 1.27)
							)
						)
					)
				)
				(pin passive line
					(at 0 -25.4 0)
					(length 5.08)
					(hide yes)
					(name "GND"
						(effects
							(font
								(size 1.27 1.27)
							)
						)
					)
					(number "L2"
						(effects
							(font
								(size 1.27 1.27)
							)
						)
					)
				)
				(pin passive line
					(at 0 -25.4 0)
					(length 5.08)
					(hide yes)
					(name "GND"
						(effects
							(font
								(size 1.27 1.27)
							)
						)
					)
					(number "L21"
						(effects
							(font
								(size 1.27 1.27)
							)
						)
					)
				)
				(pin passive line
					(at 0 -25.4 0)
					(length 5.08)
					(hide yes)
					(name "GND"
						(effects
							(font
								(size 1.27 1.27)
							)
						)
					)
					(number "L26"
						(effects
							(font
								(size 1.27 1.27)
							)
						)
					)
				)
				(pin passive line
					(at 0 -25.4 0)
					(length 5.08)
					(hide yes)
					(name "GND"
						(effects
							(font
								(size 1.27 1.27)
							)
						)
					)
					(number "L3"
						(effects
							(font
								(size 1.27 1.27)
							)
						)
					)
				)
				(pin passive line
					(at 0 -25.4 0)
					(length 5.08)
					(hide yes)
					(name "GND"
						(effects
							(font
								(size 1.27 1.27)
							)
						)
					)
					(number "L6"
						(effects
							(font
								(size 1.27 1.27)
							)
						)
					)
				)
				(pin passive line
					(at 0 -25.4 0)
					(length 5.08)
					(hide yes)
					(name "GND"
						(effects
							(font
								(size 1.27 1.27)
							)
						)
					)
					(number "L8"
						(effects
							(font
								(size 1.27 1.27)
							)
						)
					)
				)
				(pin passive line
					(at 0 -25.4 0)
					(length 5.08)
					(hide yes)
					(name "GND"
						(effects
							(font
								(size 1.27 1.27)
							)
						)
					)
					(number "M10"
						(effects
							(font
								(size 1.27 1.27)
							)
						)
					)
				)
				(pin passive line
					(at 0 -25.4 0)
					(length 5.08)
					(hide yes)
					(name "GND"
						(effects
							(font
								(size 1.27 1.27)
							)
						)
					)
					(number "M12"
						(effects
							(font
								(size 1.27 1.27)
							)
						)
					)
				)
				(pin passive line
					(at 0 -25.4 0)
					(length 5.08)
					(hide yes)
					(name "GND"
						(effects
							(font
								(size 1.27 1.27)
							)
						)
					)
					(number "M14"
						(effects
							(font
								(size 1.27 1.27)
							)
						)
					)
				)
				(pin passive line
					(at 0 -25.4 0)
					(length 5.08)
					(hide yes)
					(name "GND"
						(effects
							(font
								(size 1.27 1.27)
							)
						)
					)
					(number "M16"
						(effects
							(font
								(size 1.27 1.27)
							)
						)
					)
				)
				(pin passive line
					(at 0 -25.4 0)
					(length 5.08)
					(hide yes)
					(name "GND"
						(effects
							(font
								(size 1.27 1.27)
							)
						)
					)
					(number "M23"
						(effects
							(font
								(size 1.27 1.27)
							)
						)
					)
				)
				(pin passive line
					(at 0 -25.4 0)
					(length 5.08)
					(hide yes)
					(name "GND"
						(effects
							(font
								(size 1.27 1.27)
							)
						)
					)
					(number "M3"
						(effects
							(font
								(size 1.27 1.27)
							)
						)
					)
				)
				(pin passive line
					(at 0 -25.4 0)
					(length 5.08)
					(hide yes)
					(name "GND"
						(effects
							(font
								(size 1.27 1.27)
							)
						)
					)
					(number "M4"
						(effects
							(font
								(size 1.27 1.27)
							)
						)
					)
				)
				(pin passive line
					(at 0 -25.4 0)
					(length 5.08)
					(hide yes)
					(name "GND"
						(effects
							(font
								(size 1.27 1.27)
							)
						)
					)
					(number "M8"
						(effects
							(font
								(size 1.27 1.27)
							)
						)
					)
				)
				(pin passive line
					(at 0 -25.4 0)
					(length 5.08)
					(hide yes)
					(name "GND"
						(effects
							(font
								(size 1.27 1.27)
							)
						)
					)
					(number "N1"
						(effects
							(font
								(size 1.27 1.27)
							)
						)
					)
				)
				(pin passive line
					(at 0 -25.4 0)
					(length 5.08)
					(hide yes)
					(name "GND"
						(effects
							(font
								(size 1.27 1.27)
							)
						)
					)
					(number "N11"
						(effects
							(font
								(size 1.27 1.27)
							)
						)
					)
				)
				(pin passive line
					(at 0 -25.4 0)
					(length 5.08)
					(hide yes)
					(name "GND"
						(effects
							(font
								(size 1.27 1.27)
							)
						)
					)
					(number "N15"
						(effects
							(font
								(size 1.27 1.27)
							)
						)
					)
				)
				(pin passive line
					(at 0 -25.4 0)
					(length 5.08)
					(hide yes)
					(name "GND"
						(effects
							(font
								(size 1.27 1.27)
							)
						)
					)
					(number "N17"
						(effects
							(font
								(size 1.27 1.27)
							)
						)
					)
				)
				(pin passive line
					(at 0 -25.4 0)
					(length 5.08)
					(hide yes)
					(name "GND"
						(effects
							(font
								(size 1.27 1.27)
							)
						)
					)
					(number "N2"
						(effects
							(font
								(size 1.27 1.27)
							)
						)
					)
				)
				(pin passive line
					(at 0 -25.4 0)
					(length 5.08)
					(hide yes)
					(name "GND"
						(effects
							(font
								(size 1.27 1.27)
							)
						)
					)
					(number "N20"
						(effects
							(font
								(size 1.27 1.27)
							)
						)
					)
				)
				(pin passive line
					(at 0 -25.4 0)
					(length 5.08)
					(hide yes)
					(name "GND"
						(effects
							(font
								(size 1.27 1.27)
							)
						)
					)
					(number "N25"
						(effects
							(font
								(size 1.27 1.27)
							)
						)
					)
				)
				(pin passive line
					(at 0 -25.4 0)
					(length 5.08)
					(hide yes)
					(name "GND"
						(effects
							(font
								(size 1.27 1.27)
							)
						)
					)
					(number "N3"
						(effects
							(font
								(size 1.27 1.27)
							)
						)
					)
				)
				(pin passive line
					(at 0 -25.4 0)
					(length 5.08)
					(hide yes)
					(name "GND"
						(effects
							(font
								(size 1.27 1.27)
							)
						)
					)
					(number "N6"
						(effects
							(font
								(size 1.27 1.27)
							)
						)
					)
				)
				(pin passive line
					(at 0 -25.4 0)
					(length 5.08)
					(hide yes)
					(name "GND"
						(effects
							(font
								(size 1.27 1.27)
							)
						)
					)
					(number "N8"
						(effects
							(font
								(size 1.27 1.27)
							)
						)
					)
				)
				(pin passive line
					(at 0 -25.4 0)
					(length 5.08)
					(hide yes)
					(name "GND"
						(effects
							(font
								(size 1.27 1.27)
							)
						)
					)
					(number "P10"
						(effects
							(font
								(size 1.27 1.27)
							)
						)
					)
				)
				(pin passive line
					(at 0 -25.4 0)
					(length 5.08)
					(hide yes)
					(name "GND"
						(effects
							(font
								(size 1.27 1.27)
							)
						)
					)
					(number "P12"
						(effects
							(font
								(size 1.27 1.27)
							)
						)
					)
				)
				(pin passive line
					(at 0 -25.4 0)
					(length 5.08)
					(hide yes)
					(name "GND"
						(effects
							(font
								(size 1.27 1.27)
							)
						)
					)
					(number "P16"
						(effects
							(font
								(size 1.27 1.27)
							)
						)
					)
				)
				(pin passive line
					(at 0 -25.4 0)
					(length 5.08)
					(hide yes)
					(name "GND"
						(effects
							(font
								(size 1.27 1.27)
							)
						)
					)
					(number "P3"
						(effects
							(font
								(size 1.27 1.27)
							)
						)
					)
				)
				(pin passive line
					(at 0 -25.4 0)
					(length 5.08)
					(hide yes)
					(name "GND"
						(effects
							(font
								(size 1.27 1.27)
							)
						)
					)
					(number "P4"
						(effects
							(font
								(size 1.27 1.27)
							)
						)
					)
				)
				(pin passive line
					(at 0 -25.4 0)
					(length 5.08)
					(hide yes)
					(name "GND"
						(effects
							(font
								(size 1.27 1.27)
							)
						)
					)
					(number "P8"
						(effects
							(font
								(size 1.27 1.27)
							)
						)
					)
				)
				(pin passive line
					(at 0 -25.4 0)
					(length 5.08)
					(hide yes)
					(name "GND"
						(effects
							(font
								(size 1.27 1.27)
							)
						)
					)
					(number "R1"
						(effects
							(font
								(size 1.27 1.27)
							)
						)
					)
				)
				(pin passive line
					(at 0 -25.4 0)
					(length 5.08)
					(hide yes)
					(name "GND"
						(effects
							(font
								(size 1.27 1.27)
							)
						)
					)
					(number "R11"
						(effects
							(font
								(size 1.27 1.27)
							)
						)
					)
				)
				(pin passive line
					(at 0 -25.4 0)
					(length 5.08)
					(hide yes)
					(name "GND"
						(effects
							(font
								(size 1.27 1.27)
							)
						)
					)
					(number "R15"
						(effects
							(font
								(size 1.27 1.27)
							)
						)
					)
				)
				(pin passive line
					(at 0 -25.4 0)
					(length 5.08)
					(hide yes)
					(name "GND"
						(effects
							(font
								(size 1.27 1.27)
							)
						)
					)
					(number "R17"
						(effects
							(font
								(size 1.27 1.27)
							)
						)
					)
				)
				(pin passive line
					(at 0 -25.4 0)
					(length 5.08)
					(hide yes)
					(name "GND"
						(effects
							(font
								(size 1.27 1.27)
							)
						)
					)
					(number "R19"
						(effects
							(font
								(size 1.27 1.27)
							)
						)
					)
				)
				(pin passive line
					(at 0 -25.4 0)
					(length 5.08)
					(hide yes)
					(name "GND"
						(effects
							(font
								(size 1.27 1.27)
							)
						)
					)
					(number "R2"
						(effects
							(font
								(size 1.27 1.27)
							)
						)
					)
				)
				(pin passive line
					(at 0 -25.4 0)
					(length 5.08)
					(hide yes)
					(name "GND"
						(effects
							(font
								(size 1.27 1.27)
							)
						)
					)
					(number "R24"
						(effects
							(font
								(size 1.27 1.27)
							)
						)
					)
				)
				(pin passive line
					(at 0 -25.4 0)
					(length 5.08)
					(hide yes)
					(name "GND"
						(effects
							(font
								(size 1.27 1.27)
							)
						)
					)
					(number "R3"
						(effects
							(font
								(size 1.27 1.27)
							)
						)
					)
				)
				(pin passive line
					(at 0 -25.4 0)
					(length 5.08)
					(hide yes)
					(name "GND"
						(effects
							(font
								(size 1.27 1.27)
							)
						)
					)
					(number "R6"
						(effects
							(font
								(size 1.27 1.27)
							)
						)
					)
				)
				(pin passive line
					(at 0 -25.4 0)
					(length 5.08)
					(hide yes)
					(name "GND"
						(effects
							(font
								(size 1.27 1.27)
							)
						)
					)
					(number "R8"
						(effects
							(font
								(size 1.27 1.27)
							)
						)
					)
				)
				(pin passive line
					(at 0 -25.4 0)
					(length 5.08)
					(hide yes)
					(name "GND"
						(effects
							(font
								(size 1.27 1.27)
							)
						)
					)
					(number "T10"
						(effects
							(font
								(size 1.27 1.27)
							)
						)
					)
				)
				(pin passive line
					(at 0 -25.4 0)
					(length 5.08)
					(hide yes)
					(name "GND"
						(effects
							(font
								(size 1.27 1.27)
							)
						)
					)
					(number "T12"
						(effects
							(font
								(size 1.27 1.27)
							)
						)
					)
				)
				(pin passive line
					(at 0 -25.4 0)
					(length 5.08)
					(hide yes)
					(name "GND"
						(effects
							(font
								(size 1.27 1.27)
							)
						)
					)
					(number "T16"
						(effects
							(font
								(size 1.27 1.27)
							)
						)
					)
				)
				(pin passive line
					(at 0 -25.4 0)
					(length 5.08)
					(hide yes)
					(name "GND"
						(effects
							(font
								(size 1.27 1.27)
							)
						)
					)
					(number "T21"
						(effects
							(font
								(size 1.27 1.27)
							)
						)
					)
				)
				(pin passive line
					(at 0 -25.4 0)
					(length 5.08)
					(hide yes)
					(name "GND"
						(effects
							(font
								(size 1.27 1.27)
							)
						)
					)
					(number "T26"
						(effects
							(font
								(size 1.27 1.27)
							)
						)
					)
				)
				(pin passive line
					(at 0 -25.4 0)
					(length 5.08)
					(hide yes)
					(name "GND"
						(effects
							(font
								(size 1.27 1.27)
							)
						)
					)
					(number "T3"
						(effects
							(font
								(size 1.27 1.27)
							)
						)
					)
				)
				(pin passive line
					(at 0 -25.4 0)
					(length 5.08)
					(hide yes)
					(name "GND"
						(effects
							(font
								(size 1.27 1.27)
							)
						)
					)
					(number "T4"
						(effects
							(font
								(size 1.27 1.27)
							)
						)
					)
				)
				(pin passive line
					(at 0 -25.4 0)
					(length 5.08)
					(hide yes)
					(name "GND"
						(effects
							(font
								(size 1.27 1.27)
							)
						)
					)
					(number "T8"
						(effects
							(font
								(size 1.27 1.27)
							)
						)
					)
				)
				(pin passive line
					(at 0 -25.4 0)
					(length 5.08)
					(hide yes)
					(name "GND"
						(effects
							(font
								(size 1.27 1.27)
							)
						)
					)
					(number "U1"
						(effects
							(font
								(size 1.27 1.27)
							)
						)
					)
				)
				(pin passive line
					(at 0 -25.4 0)
					(length 5.08)
					(hide yes)
					(name "GND"
						(effects
							(font
								(size 1.27 1.27)
							)
						)
					)
					(number "U11"
						(effects
							(font
								(size 1.27 1.27)
							)
						)
					)
				)
				(pin passive line
					(at 0 -25.4 0)
					(length 5.08)
					(hide yes)
					(name "GND"
						(effects
							(font
								(size 1.27 1.27)
							)
						)
					)
					(number "U13"
						(effects
							(font
								(size 1.27 1.27)
							)
						)
					)
				)
				(pin passive line
					(at 0 -25.4 0)
					(length 5.08)
					(hide yes)
					(name "GND"
						(effects
							(font
								(size 1.27 1.27)
							)
						)
					)
					(number "U15"
						(effects
							(font
								(size 1.27 1.27)
							)
						)
					)
				)
				(pin passive line
					(at 0 -25.4 0)
					(length 5.08)
					(hide yes)
					(name "GND"
						(effects
							(font
								(size 1.27 1.27)
							)
						)
					)
					(number "U17"
						(effects
							(font
								(size 1.27 1.27)
							)
						)
					)
				)
				(pin passive line
					(at 0 -25.4 0)
					(length 5.08)
					(hide yes)
					(name "GND"
						(effects
							(font
								(size 1.27 1.27)
							)
						)
					)
					(number "U18"
						(effects
							(font
								(size 1.27 1.27)
							)
						)
					)
				)
				(pin passive line
					(at 0 -25.4 0)
					(length 5.08)
					(hide yes)
					(name "GND"
						(effects
							(font
								(size 1.27 1.27)
							)
						)
					)
					(number "U2"
						(effects
							(font
								(size 1.27 1.27)
							)
						)
					)
				)
				(pin passive line
					(at 0 -25.4 0)
					(length 5.08)
					(hide yes)
					(name "GND"
						(effects
							(font
								(size 1.27 1.27)
							)
						)
					)
					(number "U3"
						(effects
							(font
								(size 1.27 1.27)
							)
						)
					)
				)
				(pin passive line
					(at 0 -25.4 0)
					(length 5.08)
					(hide yes)
					(name "GND"
						(effects
							(font
								(size 1.27 1.27)
							)
						)
					)
					(number "U6"
						(effects
							(font
								(size 1.27 1.27)
							)
						)
					)
				)
				(pin passive line
					(at 0 -25.4 0)
					(length 5.08)
					(hide yes)
					(name "GND"
						(effects
							(font
								(size 1.27 1.27)
							)
						)
					)
					(number "U8"
						(effects
							(font
								(size 1.27 1.27)
							)
						)
					)
				)
				(pin passive line
					(at 0 -25.4 0)
					(length 5.08)
					(hide yes)
					(name "GND"
						(effects
							(font
								(size 1.27 1.27)
							)
						)
					)
					(number "V10"
						(effects
							(font
								(size 1.27 1.27)
							)
						)
					)
				)
				(pin passive line
					(at 0 -25.4 0)
					(length 5.08)
					(hide yes)
					(name "GND"
						(effects
							(font
								(size 1.27 1.27)
							)
						)
					)
					(number "V12"
						(effects
							(font
								(size 1.27 1.27)
							)
						)
					)
				)
				(pin passive line
					(at 0 -25.4 0)
					(length 5.08)
					(hide yes)
					(name "GND"
						(effects
							(font
								(size 1.27 1.27)
							)
						)
					)
					(number "V14"
						(effects
							(font
								(size 1.27 1.27)
							)
						)
					)
				)
				(pin passive line
					(at 0 -25.4 0)
					(length 5.08)
					(hide yes)
					(name "GND"
						(effects
							(font
								(size 1.27 1.27)
							)
						)
					)
					(number "V16"
						(effects
							(font
								(size 1.27 1.27)
							)
						)
					)
				)
				(pin passive line
					(at 0 -25.4 0)
					(length 5.08)
					(hide yes)
					(name "GND"
						(effects
							(font
								(size 1.27 1.27)
							)
						)
					)
					(number "V20"
						(effects
							(font
								(size 1.27 1.27)
							)
						)
					)
				)
				(pin passive line
					(at 0 -25.4 0)
					(length 5.08)
					(hide yes)
					(name "GND"
						(effects
							(font
								(size 1.27 1.27)
							)
						)
					)
					(number "V25"
						(effects
							(font
								(size 1.27 1.27)
							)
						)
					)
				)
				(pin passive line
					(at 0 -25.4 0)
					(length 5.08)
					(hide yes)
					(name "GND"
						(effects
							(font
								(size 1.27 1.27)
							)
						)
					)
					(number "V3"
						(effects
							(font
								(size 1.27 1.27)
							)
						)
					)
				)
				(pin passive line
					(at 0 -25.4 0)
					(length 5.08)
					(hide yes)
					(name "GND"
						(effects
							(font
								(size 1.27 1.27)
							)
						)
					)
					(number "V4"
						(effects
							(font
								(size 1.27 1.27)
							)
						)
					)
				)
				(pin passive line
					(at 0 -25.4 0)
					(length 5.08)
					(hide yes)
					(name "GND"
						(effects
							(font
								(size 1.27 1.27)
							)
						)
					)
					(number "V8"
						(effects
							(font
								(size 1.27 1.27)
							)
						)
					)
				)
				(pin passive line
					(at 0 -25.4 0)
					(length 5.08)
					(hide yes)
					(name "GND"
						(effects
							(font
								(size 1.27 1.27)
							)
						)
					)
					(number "W1"
						(effects
							(font
								(size 1.27 1.27)
							)
						)
					)
				)
				(pin passive line
					(at 0 -25.4 0)
					(length 5.08)
					(hide yes)
					(name "GND"
						(effects
							(font
								(size 1.27 1.27)
							)
						)
					)
					(number "W17"
						(effects
							(font
								(size 1.27 1.27)
							)
						)
					)
				)
				(pin passive line
					(at 0 -25.4 0)
					(length 5.08)
					(hide yes)
					(name "GND"
						(effects
							(font
								(size 1.27 1.27)
							)
						)
					)
					(number "W2"
						(effects
							(font
								(size 1.27 1.27)
							)
						)
					)
				)
				(pin passive line
					(at 0 -25.4 0)
					(length 5.08)
					(hide yes)
					(name "GND"
						(effects
							(font
								(size 1.27 1.27)
							)
						)
					)
					(number "W22"
						(effects
							(font
								(size 1.27 1.27)
							)
						)
					)
				)
				(pin passive line
					(at 0 -25.4 0)
					(length 5.08)
					(hide yes)
					(name "GND"
						(effects
							(font
								(size 1.27 1.27)
							)
						)
					)
					(number "W3"
						(effects
							(font
								(size 1.27 1.27)
							)
						)
					)
				)
				(pin passive line
					(at 0 -25.4 0)
					(length 5.08)
					(hide yes)
					(name "GND"
						(effects
							(font
								(size 1.27 1.27)
							)
						)
					)
					(number "W6"
						(effects
							(font
								(size 1.27 1.27)
							)
						)
					)
				)
				(pin passive line
					(at 0 -25.4 0)
					(length 5.08)
					(hide yes)
					(name "GND"
						(effects
							(font
								(size 1.27 1.27)
							)
						)
					)
					(number "W8"
						(effects
							(font
								(size 1.27 1.27)
							)
						)
					)
				)
				(pin passive line
					(at 0 -25.4 0)
					(length 5.08)
					(hide yes)
					(name "GND"
						(effects
							(font
								(size 1.27 1.27)
							)
						)
					)
					(number "Y19"
						(effects
							(font
								(size 1.27 1.27)
							)
						)
					)
				)
				(pin passive line
					(at 0 -25.4 0)
					(length 5.08)
					(hide yes)
					(name "GND"
						(effects
							(font
								(size 1.27 1.27)
							)
						)
					)
					(number "Y3"
						(effects
							(font
								(size 1.27 1.27)
							)
						)
					)
				)
				(pin passive line
					(at 0 -25.4 0)
					(length 5.08)
					(hide yes)
					(name "GND"
						(effects
							(font
								(size 1.27 1.27)
							)
						)
					)
					(number "Y4"
						(effects
							(font
								(size 1.27 1.27)
							)
						)
					)
				)
				(pin passive line
					(at 0 -25.4 0)
					(length 5.08)
					(hide yes)
					(name "GND"
						(effects
							(font
								(size 1.27 1.27)
							)
						)
					)
					(number "Y8"
						(effects
							(font
								(size 1.27 1.27)
							)
						)
					)
				)
				(pin no_connect line
					(at 7.62 2.54 270)
					(length 5.08)
					(hide yes)
					(name "NC"
						(effects
							(font
								(size 1.27 1.27)
							)
						)
					)
					(number "B2"
						(effects
							(font
								(size 1.27 1.27)
							)
						)
					)
				)
				(pin no_connect line
					(at 10.16 2.54 270)
					(length 5.08)
					(hide yes)
					(name "NC"
						(effects
							(font
								(size 1.27 1.27)
							)
						)
					)
					(number "C4"
						(effects
							(font
								(size 1.27 1.27)
							)
						)
					)
				)
				(pin no_connect line
					(at 10.16 -27.94 90)
					(length 5.08)
					(hide yes)
					(name "NC"
						(effects
							(font
								(size 1.27 1.27)
							)
						)
					)
					(number "A4"
						(effects
							(font
								(size 1.27 1.27)
							)
						)
					)
				)
				(pin no_connect line
					(at 12.7 2.54 270)
					(length 5.08)
					(hide yes)
					(name "NC"
						(effects
							(font
								(size 1.27 1.27)
							)
						)
					)
					(number "D2"
						(effects
							(font
								(size 1.27 1.27)
							)
						)
					)
				)
				(pin no_connect line
					(at 12.7 -27.94 90)
					(length 5.08)
					(hide yes)
					(name "NC"
						(effects
							(font
								(size 1.27 1.27)
							)
						)
					)
					(number "F6"
						(effects
							(font
								(size 1.27 1.27)
							)
						)
					)
				)
				(pin no_connect line
					(at 15.24 2.54 270)
					(length 5.08)
					(hide yes)
					(name "NC"
						(effects
							(font
								(size 1.27 1.27)
							)
						)
					)
					(number "A3"
						(effects
							(font
								(size 1.27 1.27)
							)
						)
					)
				)
				(pin no_connect line
					(at 15.24 -27.94 90)
					(length 5.08)
					(hide yes)
					(name "NC"
						(effects
							(font
								(size 1.27 1.27)
							)
						)
					)
					(number "E4"
						(effects
							(font
								(size 1.27 1.27)
							)
						)
					)
				)
				(pin no_connect line
					(at 17.78 2.54 270)
					(length 5.08)
					(hide yes)
					(name "NC"
						(effects
							(font
								(size 1.27 1.27)
							)
						)
					)
					(number "B1"
						(effects
							(font
								(size 1.27 1.27)
							)
						)
					)
				)
				(pin no_connect line
					(at 17.78 -27.94 90)
					(length 5.08)
					(hide yes)
					(name "NC"
						(effects
							(font
								(size 1.27 1.27)
							)
						)
					)
					(number "D6"
						(effects
							(font
								(size 1.27 1.27)
							)
						)
					)
				)
				(pin no_connect line
					(at 20.32 2.54 270)
					(length 5.08)
					(hide yes)
					(name "NC"
						(effects
							(font
								(size 1.27 1.27)
							)
						)
					)
					(number "C3"
						(effects
							(font
								(size 1.27 1.27)
							)
						)
					)
				)
				(pin no_connect line
					(at 20.32 -27.94 90)
					(length 5.08)
					(hide yes)
					(name "NC"
						(effects
							(font
								(size 1.27 1.27)
							)
						)
					)
					(number "B6"
						(effects
							(font
								(size 1.27 1.27)
							)
						)
					)
				)
				(pin no_connect line
					(at 22.86 2.54 270)
					(length 5.08)
					(hide yes)
					(name "NC"
						(effects
							(font
								(size 1.27 1.27)
							)
						)
					)
					(number "D1"
						(effects
							(font
								(size 1.27 1.27)
							)
						)
					)
				)
				(pin no_connect line
					(at 22.86 -27.94 90)
					(length 5.08)
					(hide yes)
					(name "NC"
						(effects
							(font
								(size 1.27 1.27)
							)
						)
					)
					(number "F7"
						(effects
							(font
								(size 1.27 1.27)
							)
						)
					)
				)
				(pin no_connect line
					(at 25.4 2.54 270)
					(length 5.08)
					(hide yes)
					(name "NC"
						(effects
							(font
								(size 1.27 1.27)
							)
						)
					)
					(number "H7"
						(effects
							(font
								(size 1.27 1.27)
							)
						)
					)
				)
				(pin no_connect line
					(at 25.4 -27.94 90)
					(length 5.08)
					(hide yes)
					(name "NC"
						(effects
							(font
								(size 1.27 1.27)
							)
						)
					)
					(number "E5"
						(effects
							(font
								(size 1.27 1.27)
							)
						)
					)
				)
				(pin no_connect line
					(at 27.94 2.54 270)
					(length 5.08)
					(hide yes)
					(name "NC"
						(effects
							(font
								(size 1.27 1.27)
							)
						)
					)
					(number "H6"
						(effects
							(font
								(size 1.27 1.27)
							)
						)
					)
				)
				(pin no_connect line
					(at 27.94 -27.94 90)
					(length 5.08)
					(hide yes)
					(name "NC"
						(effects
							(font
								(size 1.27 1.27)
							)
						)
					)
					(number "D7"
						(effects
							(font
								(size 1.27 1.27)
							)
						)
					)
				)
				(pin no_connect line
					(at 30.48 2.54 270)
					(length 5.08)
					(hide yes)
					(name "NC"
						(effects
							(font
								(size 1.27 1.27)
							)
						)
					)
					(number "K7"
						(effects
							(font
								(size 1.27 1.27)
							)
						)
					)
				)
				(pin no_connect line
					(at 30.48 -27.94 90)
					(length 5.08)
					(hide yes)
					(name "NC"
						(effects
							(font
								(size 1.27 1.27)
							)
						)
					)
					(number "B7"
						(effects
							(font
								(size 1.27 1.27)
							)
						)
					)
				)
				(pin no_connect line
					(at 33.02 2.54 270)
					(length 5.08)
					(hide yes)
					(name "NC"
						(effects
							(font
								(size 1.27 1.27)
							)
						)
					)
					(number "K6"
						(effects
							(font
								(size 1.27 1.27)
							)
						)
					)
				)
				(pin power_in line
					(at 40.64 0 180)
					(length 5.08)
					(name "VCCINT"
						(effects
							(font
								(size 1.27 1.27)
							)
						)
					)
					(number "K11"
						(effects
							(font
								(size 1.27 1.27)
							)
						)
					)
				)
				(pin passive line
					(at 40.64 0 180)
					(length 5.08)
					(hide yes)
					(name "VCCINT"
						(effects
							(font
								(size 1.27 1.27)
							)
						)
					)
					(number "K13"
						(effects
							(font
								(size 1.27 1.27)
							)
						)
					)
				)
				(pin passive line
					(at 40.64 0 180)
					(length 5.08)
					(hide yes)
					(name "VCCINT"
						(effects
							(font
								(size 1.27 1.27)
							)
						)
					)
					(number "K15"
						(effects
							(font
								(size 1.27 1.27)
							)
						)
					)
				)
				(pin passive line
					(at 40.64 0 180)
					(length 5.08)
					(hide yes)
					(name "VCCINT"
						(effects
							(font
								(size 1.27 1.27)
							)
						)
					)
					(number "K17"
						(effects
							(font
								(size 1.27 1.27)
							)
						)
					)
				)
				(pin passive line
					(at 40.64 0 180)
					(length 5.08)
					(hide yes)
					(name "VCCINT"
						(effects
							(font
								(size 1.27 1.27)
							)
						)
					)
					(number "L10"
						(effects
							(font
								(size 1.27 1.27)
							)
						)
					)
				)
				(pin passive line
					(at 40.64 0 180)
					(length 5.08)
					(hide yes)
					(name "VCCINT"
						(effects
							(font
								(size 1.27 1.27)
							)
						)
					)
					(number "L12"
						(effects
							(font
								(size 1.27 1.27)
							)
						)
					)
				)
				(pin passive line
					(at 40.64 0 180)
					(length 5.08)
					(hide yes)
					(name "VCCINT"
						(effects
							(font
								(size 1.27 1.27)
							)
						)
					)
					(number "L14"
						(effects
							(font
								(size 1.27 1.27)
							)
						)
					)
				)
				(pin passive line
					(at 40.64 0 180)
					(length 5.08)
					(hide yes)
					(name "VCCINT"
						(effects
							(font
								(size 1.27 1.27)
							)
						)
					)
					(number "L16"
						(effects
							(font
								(size 1.27 1.27)
							)
						)
					)
				)
				(pin passive line
					(at 40.64 0 180)
					(length 5.08)
					(hide yes)
					(name "VCCINT"
						(effects
							(font
								(size 1.27 1.27)
							)
						)
					)
					(number "M11"
						(effects
							(font
								(size 1.27 1.27)
							)
						)
					)
				)
				(pin passive line
					(at 40.64 0 180)
					(length 5.08)
					(hide yes)
					(name "VCCINT"
						(effects
							(font
								(size 1.27 1.27)
							)
						)
					)
					(number "M13"
						(effects
							(font
								(size 1.27 1.27)
							)
						)
					)
				)
				(pin passive line
					(at 40.64 0 180)
					(length 5.08)
					(hide yes)
					(name "VCCINT"
						(effects
							(font
								(size 1.27 1.27)
							)
						)
					)
					(number "M15"
						(effects
							(font
								(size 1.27 1.27)
							)
						)
					)
				)
				(pin passive line
					(at 40.64 0 180)
					(length 5.08)
					(hide yes)
					(name "VCCINT"
						(effects
							(font
								(size 1.27 1.27)
							)
						)
					)
					(number "M17"
						(effects
							(font
								(size 1.27 1.27)
							)
						)
					)
				)
				(pin passive line
					(at 40.64 0 180)
					(length 5.08)
					(hide yes)
					(name "VCCINT"
						(effects
							(font
								(size 1.27 1.27)
							)
						)
					)
					(number "N10"
						(effects
							(font
								(size 1.27 1.27)
							)
						)
					)
				)
				(pin passive line
					(at 40.64 0 180)
					(length 5.08)
					(hide yes)
					(name "VCCINT"
						(effects
							(font
								(size 1.27 1.27)
							)
						)
					)
					(number "N12"
						(effects
							(font
								(size 1.27 1.27)
							)
						)
					)
				)
				(pin passive line
					(at 40.64 0 180)
					(length 5.08)
					(hide yes)
					(name "VCCINT"
						(effects
							(font
								(size 1.27 1.27)
							)
						)
					)
					(number "N16"
						(effects
							(font
								(size 1.27 1.27)
							)
						)
					)
				)
				(pin passive line
					(at 40.64 0 180)
					(length 5.08)
					(hide yes)
					(name "VCCINT"
						(effects
							(font
								(size 1.27 1.27)
							)
						)
					)
					(number "P11"
						(effects
							(font
								(size 1.27 1.27)
							)
						)
					)
				)
				(pin passive line
					(at 40.64 0 180)
					(length 5.08)
					(hide yes)
					(name "VCCINT"
						(effects
							(font
								(size 1.27 1.27)
							)
						)
					)
					(number "P15"
						(effects
							(font
								(size 1.27 1.27)
							)
						)
					)
				)
				(pin passive line
					(at 40.64 0 180)
					(length 5.08)
					(hide yes)
					(name "VCCINT"
						(effects
							(font
								(size 1.27 1.27)
							)
						)
					)
					(number "P17"
						(effects
							(font
								(size 1.27 1.27)
							)
						)
					)
				)
				(pin passive line
					(at 40.64 0 180)
					(length 5.08)
					(hide yes)
					(name "VCCINT"
						(effects
							(font
								(size 1.27 1.27)
							)
						)
					)
					(number "R10"
						(effects
							(font
								(size 1.27 1.27)
							)
						)
					)
				)
				(pin passive line
					(at 40.64 0 180)
					(length 5.08)
					(hide yes)
					(name "VCCINT"
						(effects
							(font
								(size 1.27 1.27)
							)
						)
					)
					(number "R12"
						(effects
							(font
								(size 1.27 1.27)
							)
						)
					)
				)
				(pin passive line
					(at 40.64 0 180)
					(length 5.08)
					(hide yes)
					(name "VCCINT"
						(effects
							(font
								(size 1.27 1.27)
							)
						)
					)
					(number "R16"
						(effects
							(font
								(size 1.27 1.27)
							)
						)
					)
				)
				(pin passive line
					(at 40.64 0 180)
					(length 5.08)
					(hide yes)
					(name "VCCINT"
						(effects
							(font
								(size 1.27 1.27)
							)
						)
					)
					(number "T11"
						(effects
							(font
								(size 1.27 1.27)
							)
						)
					)
				)
				(pin passive line
					(at 40.64 0 180)
					(length 5.08)
					(hide yes)
					(name "VCCINT"
						(effects
							(font
								(size 1.27 1.27)
							)
						)
					)
					(number "T15"
						(effects
							(font
								(size 1.27 1.27)
							)
						)
					)
				)
				(pin passive line
					(at 40.64 0 180)
					(length 5.08)
					(hide yes)
					(name "VCCINT"
						(effects
							(font
								(size 1.27 1.27)
							)
						)
					)
					(number "T17"
						(effects
							(font
								(size 1.27 1.27)
							)
						)
					)
				)
				(pin passive line
					(at 40.64 0 180)
					(length 5.08)
					(hide yes)
					(name "VCCINT"
						(effects
							(font
								(size 1.27 1.27)
							)
						)
					)
					(number "U10"
						(effects
							(font
								(size 1.27 1.27)
							)
						)
					)
				)
				(pin passive line
					(at 40.64 0 180)
					(length 5.08)
					(hide yes)
					(name "VCCINT"
						(effects
							(font
								(size 1.27 1.27)
							)
						)
					)
					(number "U12"
						(effects
							(font
								(size 1.27 1.27)
							)
						)
					)
				)
				(pin passive line
					(at 40.64 0 180)
					(length 5.08)
					(hide yes)
					(name "VCCINT"
						(effects
							(font
								(size 1.27 1.27)
							)
						)
					)
					(number "U14"
						(effects
							(font
								(size 1.27 1.27)
							)
						)
					)
				)
				(pin passive line
					(at 40.64 0 180)
					(length 5.08)
					(hide yes)
					(name "VCCINT"
						(effects
							(font
								(size 1.27 1.27)
							)
						)
					)
					(number "U16"
						(effects
							(font
								(size 1.27 1.27)
							)
						)
					)
				)
				(pin passive line
					(at 40.64 0 180)
					(length 5.08)
					(hide yes)
					(name "VCCINT"
						(effects
							(font
								(size 1.27 1.27)
							)
						)
					)
					(number "V11"
						(effects
							(font
								(size 1.27 1.27)
							)
						)
					)
				)
				(pin passive line
					(at 40.64 0 180)
					(length 5.08)
					(hide yes)
					(name "VCCINT"
						(effects
							(font
								(size 1.27 1.27)
							)
						)
					)
					(number "V13"
						(effects
							(font
								(size 1.27 1.27)
							)
						)
					)
				)
				(pin passive line
					(at 40.64 0 180)
					(length 5.08)
					(hide yes)
					(name "VCCINT"
						(effects
							(font
								(size 1.27 1.27)
							)
						)
					)
					(number "V15"
						(effects
							(font
								(size 1.27 1.27)
							)
						)
					)
				)
				(pin passive line
					(at 40.64 0 180)
					(length 5.08)
					(hide yes)
					(name "VCCINT"
						(effects
							(font
								(size 1.27 1.27)
							)
						)
					)
					(number "V17"
						(effects
							(font
								(size 1.27 1.27)
							)
						)
					)
				)
				(pin power_in line
					(at 40.64 -2.54 180)
					(length 5.08)
					(name "VCCINT_IO"
						(effects
							(font
								(size 1.27 1.27)
							)
						)
					)
					(number "L9"
						(effects
							(font
								(size 1.27 1.27)
							)
						)
					)
				)
				(pin passive line
					(at 40.64 -2.54 180)
					(length 5.08)
					(hide yes)
					(name "VCCINT_IO"
						(effects
							(font
								(size 1.27 1.27)
							)
						)
					)
					(number "M9"
						(effects
							(font
								(size 1.27 1.27)
							)
						)
					)
				)
				(pin passive line
					(at 40.64 -2.54 180)
					(length 5.08)
					(hide yes)
					(name "VCCINT_IO"
						(effects
							(font
								(size 1.27 1.27)
							)
						)
					)
					(number "N9"
						(effects
							(font
								(size 1.27 1.27)
							)
						)
					)
				)
				(pin passive line
					(at 40.64 -2.54 180)
					(length 5.08)
					(hide yes)
					(name "VCCINT_IO"
						(effects
							(font
								(size 1.27 1.27)
							)
						)
					)
					(number "P9"
						(effects
							(font
								(size 1.27 1.27)
							)
						)
					)
				)
				(pin power_in line
					(at 40.64 -7.62 180)
					(length 5.08)
					(name "VCCAUX"
						(effects
							(font
								(size 1.27 1.27)
							)
						)
					)
					(number "M18"
						(effects
							(font
								(size 1.27 1.27)
							)
						)
					)
				)
				(pin passive line
					(at 40.64 -7.62 180)
					(length 5.08)
					(hide yes)
					(name "VCCAUX"
						(effects
							(font
								(size 1.27 1.27)
							)
						)
					)
					(number "N18"
						(effects
							(font
								(size 1.27 1.27)
							)
						)
					)
				)
				(pin power_in line
					(at 40.64 -10.16 180)
					(length 5.08)
					(name "VCCAUX_IO"
						(effects
							(font
								(size 1.27 1.27)
							)
						)
					)
					(number "P18"
						(effects
							(font
								(size 1.27 1.27)
							)
						)
					)
				)
				(pin passive line
					(at 40.64 -10.16 180)
					(length 5.08)
					(hide yes)
					(name "VCCAUX_IO"
						(effects
							(font
								(size 1.27 1.27)
							)
						)
					)
					(number "R18"
						(effects
							(font
								(size 1.27 1.27)
							)
						)
					)
				)
				(pin passive line
					(at 40.64 -10.16 180)
					(length 5.08)
					(hide yes)
					(name "VCCAUX_IO"
						(effects
							(font
								(size 1.27 1.27)
							)
						)
					)
					(number "T18"
						(effects
							(font
								(size 1.27 1.27)
							)
						)
					)
				)
				(pin power_in line
					(at 40.64 -15.24 180)
					(length 5.08)
					(name "VCCBRAM"
						(effects
							(font
								(size 1.27 1.27)
							)
						)
					)
					(number "R9"
						(effects
							(font
								(size 1.27 1.27)
							)
						)
					)
				)
				(pin passive line
					(at 40.64 -15.24 180)
					(length 5.08)
					(hide yes)
					(name "VCCBRAM"
						(effects
							(font
								(size 1.27 1.27)
							)
						)
					)
					(number "T9"
						(effects
							(font
								(size 1.27 1.27)
							)
						)
					)
				)
				(pin passive line
					(at 40.64 -15.24 180)
					(length 5.08)
					(hide yes)
					(name "VCCBRAM"
						(effects
							(font
								(size 1.27 1.27)
							)
						)
					)
					(number "U9"
						(effects
							(font
								(size 1.27 1.27)
							)
						)
					)
				)
				(pin passive line
					(at 40.64 -15.24 180)
					(length 5.08)
					(hide yes)
					(name "VCCBRAM"
						(effects
							(font
								(size 1.27 1.27)
							)
						)
					)
					(number "V9"
						(effects
							(font
								(size 1.27 1.27)
							)
						)
					)
				)
				(pin power_in line
					(at 40.64 -20.32 180)
					(length 5.08)
					(name "VCCADC"
						(effects
							(font
								(size 1.27 1.27)
							)
						)
					)
					(number "N14"
						(effects
							(font
								(size 1.27 1.27)
							)
						)
					)
				)
				(pin power_in line
					(at 40.64 -25.4 180)
					(length 5.08)
					(name "VBATT"
						(effects
							(font
								(size 1.27 1.27)
							)
						)
					)
					(number "Y9"
						(effects
							(font
								(size 1.27 1.27)
							)
						)
					)
				)
			)
		)
	(symbol "antmicroFerriteBeadsandChips:FB_120Z_1.3A_Murata-BLM15PD_0402"
			(pin_numbers
				(hide yes)
			)
			(pin_names
				(hide yes)
			)
			(exclude_from_sim no)
			(in_bom yes)
			(on_board yes)
			(property "Reference" "FB"
				(at 13.97 0 0)
				(effects
					(font
						(size 1.27 1.27)
						(thickness 0.15)
					)
					(justify left bottom)
				)
			)
			(property "Value" "FB_120Z_1.3A_Murata-BLM15PD_0402"
				(at 13.97 -2.54 0)
				(effects
					(font
						(size 1.27 1.27)
						(thickness 0.15)
					)
					(justify left bottom)
					(hide yes)
				)
			)
			(property "Footprint" "antmicro-footprints:FB_0402_1005Metric"
				(at 13.97 -7.62 0)
				(effects
					(font
						(size 1.27 1.27)
						(thickness 0.15)
					)
					(justify left bottom)
					(hide yes)
				)
			)
			(property "Datasheet" "https://www.murata.com/en-us/products/productdata/8796740059166/ENFA0018.pdf"
				(at 13.97 -10.16 0)
				(effects
					(font
						(size 1.27 1.27)
						(thickness 0.15)
					)
					(justify left bottom)
					(hide yes)
				)
			)
			(property "Description" "Ferrite Bead, 0402 [1005 Metric], 120 ohm, 1.3 A, BLM15PD, 0.09 ohm, ± 25%, DC power line"
				(at 0 0 0)
				(effects
					(font
						(size 1.27 1.27)
					)
					(hide yes)
				)
			)
			(property "Val" "120Z/1.3A"
				(at 13.97 -5.08 0)
				(effects
					(font
						(size 1.27 1.27)
					)
					(justify left bottom)
				)
			)
			(property "MPN" "BLM15PD121SN1D"
				(at 13.97 -12.7 0)
				(effects
					(font
						(size 1.27 1.27)
						(thickness 0.15)
					)
					(justify left bottom)
					(hide yes)
				)
			)
			(property "Manufacturer" "Murata"
				(at 13.97 -15.24 0)
				(effects
					(font
						(size 1.27 1.27)
						(thickness 0.15)
					)
					(justify left bottom)
					(hide yes)
				)
			)
			(property "Current" ""
				(at 20.32 -22.86 0)
				(effects
					(font
						(size 1.27 1.27)
						(thickness 0.15)
					)
					(justify left bottom)
					(hide yes)
				)
			)
			(property "Author" "Antmicro"
				(at 13.97 -17.78 0)
				(effects
					(font
						(size 1.27 1.27)
						(thickness 0.15)
					)
					(justify left bottom)
					(hide yes)
				)
			)
			(property "License" "Apache-2.0"
				(at 13.97 -20.32 0)
				(effects
					(font
						(size 1.27 1.27)
						(thickness 0.15)
					)
					(justify left bottom)
					(hide yes)
				)
			)
			(property "ki_keywords" "0402, SMT, FERRITE BEAD, PASSIVE"
				(at 0 0 0)
				(effects
					(font
						(size 1.27 1.27)
					)
					(hide yes)
				)
			)
			(symbol "FB_120Z_1.3A_Murata-BLM15PD_0402_0_1"
				(polyline
					(pts
						(xy 1.651 0) (xy 1.2446 0)
					)
					(stroke
						(width 0)
						(type default)
					)
					(fill
						(type none)
					)
				)
				(polyline
					(pts
						(xy 2.2606 -1.8288) (xy 1.0414 -1.1176) (xy 2.7432 1.8288) (xy 3.9624 1.1176) (xy 2.2606 -1.8288)
					)
					(stroke
						(width 0)
						(type default)
					)
					(fill
						(type none)
					)
				)
				(polyline
					(pts
						(xy 3.81 0) (xy 3.3274 0)
					)
					(stroke
						(width 0)
						(type default)
					)
					(fill
						(type none)
					)
				)
			)
			(symbol "FB_120Z_1.3A_Murata-BLM15PD_0402_1_1"
				(pin passive line
					(at 0 0 0)
					(length 1.27)
					(name "~"
						(effects
							(font
								(size 1.27 1.27)
							)
						)
					)
					(number "1"
						(effects
							(font
								(size 1.27 1.27)
							)
						)
					)
				)
				(pin passive line
					(at 5.08 0 180)
					(length 1.27)
					(name "~"
						(effects
							(font
								(size 1.27 1.27)
							)
						)
					)
					(number "2"
						(effects
							(font
								(size 1.27 1.27)
							)
						)
					)
				)
			)
		)
	(symbol "antmicroFerriteBeadsandChips:FB_120Z_2A_Murata-BLM18PG_0603"
			(pin_numbers
				(hide yes)
			)
			(pin_names
				(hide yes)
			)
			(exclude_from_sim no)
			(in_bom yes)
			(on_board yes)
			(property "Reference" "FB"
				(at 15.24 0 0)
				(effects
					(font
						(size 1.27 1.27)
						(thickness 0.15)
					)
					(justify left bottom)
				)
			)
			(property "Value" "FB_120Z_2A_Murata-BLM18PG_0603"
				(at 15.24 -2.54 0)
				(effects
					(font
						(size 1.27 1.27)
						(thickness 0.15)
					)
					(justify left bottom)
					(hide yes)
				)
			)
			(property "Footprint" "antmicro-footprints:FB_0603_1608Metric"
				(at 15.24 -7.62 0)
				(effects
					(font
						(size 1.27 1.27)
						(thickness 0.15)
					)
					(justify left bottom)
					(hide yes)
				)
			)
			(property "Datasheet" "https://www.murata.com/en-us/products/productdata/8796738650142/ENFA0003.pdf"
				(at 15.24 -10.16 0)
				(effects
					(font
						(size 1.27 1.27)
						(thickness 0.15)
					)
					(justify left bottom)
					(hide yes)
				)
			)
			(property "Description" "Ferrite Bead, 0603 [1608 Metric], 120 ohm, 2 A, BLM18P, 0.05 ohm, ± 25%, DC power line"
				(at 0 0 0)
				(effects
					(font
						(size 1.27 1.27)
					)
					(hide yes)
				)
			)
			(property "Val" "120Z/2A"
				(at 15.24 -5.08 0)
				(effects
					(font
						(size 1.27 1.27)
					)
					(justify left bottom)
				)
			)
			(property "MPN" "BLM18PG121SN1D"
				(at 15.24 -12.7 0)
				(effects
					(font
						(size 1.27 1.27)
						(thickness 0.15)
					)
					(justify left bottom)
					(hide yes)
				)
			)
			(property "Manufacturer" "Murata"
				(at 15.24 -15.24 0)
				(effects
					(font
						(size 1.27 1.27)
						(thickness 0.15)
					)
					(justify left bottom)
					(hide yes)
				)
			)
			(property "Current" ""
				(at 20.32 -22.86 0)
				(effects
					(font
						(size 1.27 1.27)
						(thickness 0.15)
					)
					(justify left bottom)
					(hide yes)
				)
			)
			(property "Author" "Antmicro"
				(at 15.24 -17.78 0)
				(effects
					(font
						(size 1.27 1.27)
						(thickness 0.15)
					)
					(justify left bottom)
					(hide yes)
				)
			)
			(property "License" "Apache-2.0"
				(at 15.24 -20.32 0)
				(effects
					(font
						(size 1.27 1.27)
						(thickness 0.15)
					)
					(justify left bottom)
					(hide yes)
				)
			)
			(property "ki_keywords" "0603, SMT, FERRITE BEAD, PASSIVE"
				(at 0 0 0)
				(effects
					(font
						(size 1.27 1.27)
					)
					(hide yes)
				)
			)
			(symbol "FB_120Z_2A_Murata-BLM18PG_0603_0_1"
				(polyline
					(pts
						(xy 1.651 0) (xy 1.2446 0)
					)
					(stroke
						(width 0)
						(type default)
					)
					(fill
						(type none)
					)
				)
				(polyline
					(pts
						(xy 2.2606 -1.8288) (xy 1.0414 -1.1176) (xy 2.7432 1.8288) (xy 3.9624 1.1176) (xy 2.2606 -1.8288)
					)
					(stroke
						(width 0)
						(type default)
					)
					(fill
						(type none)
					)
				)
				(polyline
					(pts
						(xy 3.81 0) (xy 3.3274 0)
					)
					(stroke
						(width 0)
						(type default)
					)
					(fill
						(type none)
					)
				)
			)
			(symbol "FB_120Z_2A_Murata-BLM18PG_0603_1_1"
				(pin passive line
					(at 0 0 0)
					(length 1.27)
					(name "~"
						(effects
							(font
								(size 1.27 1.27)
							)
						)
					)
					(number "1"
						(effects
							(font
								(size 1.27 1.27)
							)
						)
					)
				)
				(pin passive line
					(at 5.08 0 180)
					(length 1.27)
					(name "~"
						(effects
							(font
								(size 1.27 1.27)
							)
						)
					)
					(number "2"
						(effects
							(font
								(size 1.27 1.27)
							)
						)
					)
				)
			)
		)
	(symbol "antmicroFerriteBeadsandChips:FB_600Z_0.5A_Murata-BLM18AG_0603"
			(pin_numbers
				(hide yes)
			)
			(pin_names
				(hide yes)
			)
			(exclude_from_sim no)
			(in_bom yes)
			(on_board yes)
			(property "Reference" "FB"
				(at 15.24 0 0)
				(effects
					(font
						(size 1.27 1.27)
						(thickness 0.15)
					)
					(justify left bottom)
				)
			)
			(property "Value" "FB_600Z_0.5A_Murata-BLM18AG_0603"
				(at 15.24 -2.54 0)
				(effects
					(font
						(size 1.27 1.27)
						(thickness 0.15)
					)
					(justify left bottom)
					(hide yes)
				)
			)
			(property "Footprint" "antmicro-footprints:FB_0603_1608Metric"
				(at 15.24 -7.62 0)
				(effects
					(font
						(size 1.27 1.27)
						(thickness 0.15)
					)
					(justify left bottom)
					(hide yes)
				)
			)
			(property "Datasheet" "https://www.murata.com/en-us/products/productdata/8796738650142/ENFA0003.pdf"
				(at 15.24 -10.16 0)
				(effects
					(font
						(size 1.27 1.27)
						(thickness 0.15)
					)
					(justify left bottom)
					(hide yes)
				)
			)
			(property "Description" "Ferrite Bead, 0603 [1608 Metric], 600 ohm, 500 mA, BLM18A, 0.38 ohm, ± 25%, General use"
				(at 0 0 0)
				(effects
					(font
						(size 1.27 1.27)
					)
					(hide yes)
				)
			)
			(property "Val" "600Z/0.5A"
				(at 15.24 -5.08 0)
				(effects
					(font
						(size 1.27 1.27)
					)
					(justify left bottom)
				)
			)
			(property "MPN" "BLM18AG601SN1D"
				(at 15.24 -12.7 0)
				(effects
					(font
						(size 1.27 1.27)
						(thickness 0.15)
					)
					(justify left bottom)
					(hide yes)
				)
			)
			(property "Manufacturer" "Murata"
				(at 15.24 -15.24 0)
				(effects
					(font
						(size 1.27 1.27)
						(thickness 0.15)
					)
					(justify left bottom)
					(hide yes)
				)
			)
			(property "Current" ""
				(at 20.32 -22.86 0)
				(effects
					(font
						(size 1.27 1.27)
						(thickness 0.15)
					)
					(justify left bottom)
					(hide yes)
				)
			)
			(property "Author" "Antmicro"
				(at 15.24 -17.78 0)
				(effects
					(font
						(size 1.27 1.27)
						(thickness 0.15)
					)
					(justify left bottom)
					(hide yes)
				)
			)
			(property "License" "Apache-2.0"
				(at 15.24 -20.32 0)
				(effects
					(font
						(size 1.27 1.27)
						(thickness 0.15)
					)
					(justify left bottom)
					(hide yes)
				)
			)
			(property "ki_keywords" "0603, SMT, FERRITE BEAD, PASSIVE"
				(at 0 0 0)
				(effects
					(font
						(size 1.27 1.27)
					)
					(hide yes)
				)
			)
			(symbol "FB_600Z_0.5A_Murata-BLM18AG_0603_0_1"
				(polyline
					(pts
						(xy 1.651 0) (xy 1.2446 0)
					)
					(stroke
						(width 0)
						(type default)
					)
					(fill
						(type none)
					)
				)
				(polyline
					(pts
						(xy 2.2606 -1.8288) (xy 1.0414 -1.1176) (xy 2.7432 1.8288) (xy 3.9624 1.1176) (xy 2.2606 -1.8288)
					)
					(stroke
						(width 0)
						(type default)
					)
					(fill
						(type none)
					)
				)
				(polyline
					(pts
						(xy 3.81 0) (xy 3.3274 0)
					)
					(stroke
						(width 0)
						(type default)
					)
					(fill
						(type none)
					)
				)
			)
			(symbol "FB_600Z_0.5A_Murata-BLM18AG_0603_1_1"
				(pin passive line
					(at 0 0 0)
					(length 1.27)
					(name "~"
						(effects
							(font
								(size 1.27 1.27)
							)
						)
					)
					(number "1"
						(effects
							(font
								(size 1.27 1.27)
							)
						)
					)
				)
				(pin passive line
					(at 5.08 0 180)
					(length 1.27)
					(name "~"
						(effects
							(font
								(size 1.27 1.27)
							)
						)
					)
					(number "2"
						(effects
							(font
								(size 1.27 1.27)
							)
						)
					)
				)
			)
		)
	(symbol "antmicroFixedInductors:L_150n_30A_WE-HCM-7050"
			(pin_numbers
				(hide yes)
			)
			(pin_names
				(hide yes)
			)
			(exclude_from_sim no)
			(in_bom yes)
			(on_board yes)
			(property "Reference" "L"
				(at 13.97 0 0)
				(effects
					(font
						(size 1.27 1.27)
						(thickness 0.15)
					)
					(justify left bottom)
				)
			)
			(property "Value" "L_150n_30A_WE-HCM-7050"
				(at 13.97 -2.54 0)
				(effects
					(font
						(size 1.27 1.27)
						(thickness 0.15)
					)
					(justify left bottom)
					(hide yes)
				)
			)
			(property "Footprint" "antmicro-footprints:L_WE-HCM-7050"
				(at 13.97 -7.62 0)
				(effects
					(font
						(size 1.27 1.27)
						(thickness 0.15)
					)
					(justify left bottom)
					(hide yes)
				)
			)
			(property "Datasheet" "https://www.we-online.com/components/products/datasheet/744302015.pdf"
				(at 13.97 -10.16 0)
				(effects
					(font
						(size 1.27 1.27)
						(thickness 0.15)
					)
					(justify left bottom)
					(hide yes)
				)
			)
			(property "Description" "Power Inductor (SMD), 150 nH, 30 A, Shielded, 32 A, WE-HCM Series"
				(at 0 0 0)
				(effects
					(font
						(size 1.27 1.27)
					)
					(hide yes)
				)
			)
			(property "Val" "150n/30A"
				(at 13.97 -5.08 0)
				(effects
					(font
						(size 1.27 1.27)
						(thickness 0.15)
					)
					(justify left bottom)
				)
			)
			(property "Manufacturer" "Würth Elektronik"
				(at 13.97 -12.7 0)
				(effects
					(font
						(size 1.27 1.27)
						(thickness 0.15)
					)
					(justify left bottom)
					(hide yes)
				)
			)
			(property "MPN" "744302015"
				(at 13.97 -15.24 0)
				(effects
					(font
						(size 1.27 1.27)
						(thickness 0.15)
					)
					(justify left bottom)
					(hide yes)
				)
			)
			(property "ISat" "35 A"
				(at 13.97 -16.51 0)
				(effects
					(font
						(size 1.27 1.27)
					)
					(justify left)
					(hide yes)
				)
			)
			(property "IMax" "30 A"
				(at 13.97 -20.32 0)
				(effects
					(font
						(size 1.27 1.27)
						(thickness 0.15)
					)
					(justify left bottom)
					(hide yes)
				)
			)
			(property "Size" "7.15x7"
				(at 13.97 -22.86 0)
				(effects
					(font
						(size 1.27 1.27)
						(thickness 0.15)
					)
					(justify left bottom)
					(hide yes)
				)
			)
			(property "Author" "Antmicro"
				(at 13.97 -25.4 0)
				(effects
					(font
						(size 1.27 1.27)
						(thickness 0.15)
					)
					(justify left bottom)
					(hide yes)
				)
			)
			(property "License" "Apache-2.0"
				(at 13.97 -27.94 0)
				(effects
					(font
						(size 1.27 1.27)
						(thickness 0.15)
					)
					(justify left bottom)
					(hide yes)
				)
			)
			(property "ki_keywords" "SMT, INDUCTOR, PASSIVE"
				(at 0 0 0)
				(effects
					(font
						(size 1.27 1.27)
					)
					(hide yes)
				)
			)
			(symbol "L_150n_30A_WE-HCM-7050_0_1"
				(arc
					(start 0.508 0)
					(mid 1.016 0.5058)
					(end 1.524 0)
					(stroke
						(width 0)
						(type default)
					)
					(fill
						(type none)
					)
				)
				(arc
					(start 1.524 0)
					(mid 2.032 0.5058)
					(end 2.54 0)
					(stroke
						(width 0)
						(type default)
					)
					(fill
						(type none)
					)
				)
				(arc
					(start 2.54 0)
					(mid 3.048 0.5058)
					(end 3.556 0)
					(stroke
						(width 0)
						(type default)
					)
					(fill
						(type none)
					)
				)
				(arc
					(start 3.556 0)
					(mid 4.064 0.5058)
					(end 4.572 0)
					(stroke
						(width 0)
						(type default)
					)
					(fill
						(type none)
					)
				)
			)
			(symbol "L_150n_30A_WE-HCM-7050_1_1"
				(pin passive line
					(at 0 0 0)
					(length 0.508)
					(name "~"
						(effects
							(font
								(size 1.27 1.27)
							)
						)
					)
					(number "1"
						(effects
							(font
								(size 1.27 1.27)
							)
						)
					)
				)
				(pin passive line
					(at 5.08 0 180)
					(length 0.508)
					(name "~"
						(effects
							(font
								(size 1.27 1.27)
							)
						)
					)
					(number "2"
						(effects
							(font
								(size 1.27 1.27)
							)
						)
					)
				)
			)
		)
	(symbol "antmicroFixedInductors:L_20n_0.35A_0402"
			(pin_numbers
				(hide yes)
			)
			(pin_names
				(hide yes)
			)
			(exclude_from_sim no)
			(in_bom yes)
			(on_board yes)
			(property "Reference" "L"
				(at 13.97 0 0)
				(effects
					(font
						(size 1.27 1.27)
						(thickness 0.15)
					)
					(justify left bottom)
				)
			)
			(property "Value" "L_20n_0.35A_0402"
				(at 13.97 -2.54 0)
				(effects
					(font
						(size 1.27 1.27)
						(thickness 0.15)
					)
					(justify left bottom)
					(hide yes)
				)
			)
			(property "Footprint" "antmicro-footprints:L_0402_1005Metric"
				(at 13.97 -7.62 0)
				(effects
					(font
						(size 1.27 1.27)
						(thickness 0.15)
					)
					(justify left bottom)
					(hide yes)
				)
			)
			(property "Datasheet" "https://product.tdk.com/system/files/dam/doc/product/inductor/inductor/smd/catalog/inductor_automotive_high-frequency_mlg1005s_en.pdf?ref_disty=mouser"
				(at 13.97 -10.16 0)
				(effects
					(font
						(size 1.27 1.27)
						(thickness 0.15)
					)
					(justify left bottom)
					(hide yes)
				)
			)
			(property "Description" "Multilayer Inductor, AEC-Q200, 20 nH, 0.6 ohm, 1.9 GHz, 350 mA, 0402 [1005 Metric], MLG Series"
				(at 0 0 0)
				(effects
					(font
						(size 1.27 1.27)
					)
					(hide yes)
				)
			)
			(property "Val" "20n/0.35A"
				(at 13.97 -5.08 0)
				(effects
					(font
						(size 1.27 1.27)
						(thickness 0.15)
					)
					(justify left bottom)
				)
			)
			(property "Manufacturer" "TDK"
				(at 13.97 -12.7 0)
				(effects
					(font
						(size 1.27 1.27)
						(thickness 0.15)
					)
					(justify left bottom)
					(hide yes)
				)
			)
			(property "MPN" "MLG1005S20NJTD25"
				(at 13.97 -15.24 0)
				(effects
					(font
						(size 1.27 1.27)
						(thickness 0.15)
					)
					(justify left bottom)
					(hide yes)
				)
			)
			(property "ISat" ""
				(at 13.97 -13.97 0)
				(effects
					(font
						(size 1.27 1.27)
					)
					(justify left)
					(hide yes)
				)
			)
			(property "IMax" "0.35 A"
				(at 13.97 -17.78 0)
				(effects
					(font
						(size 1.27 1.27)
						(thickness 0.15)
					)
					(justify left bottom)
					(hide yes)
				)
			)
			(property "Size" "1.0x0.5"
				(at 13.97 -20.32 0)
				(effects
					(font
						(size 1.27 1.27)
						(thickness 0.15)
					)
					(justify left bottom)
					(hide yes)
				)
			)
			(property "Author" "Antmicro"
				(at 13.97 -22.86 0)
				(effects
					(font
						(size 1.27 1.27)
						(thickness 0.15)
					)
					(justify left bottom)
					(hide yes)
				)
			)
			(property "License" "Apache-2.0"
				(at 13.97 -25.4 0)
				(effects
					(font
						(size 1.27 1.27)
						(thickness 0.15)
					)
					(justify left bottom)
					(hide yes)
				)
			)
			(property "ki_keywords" "SMT, INDUCTOR, PASSIVE"
				(at 0 0 0)
				(effects
					(font
						(size 1.27 1.27)
					)
					(hide yes)
				)
			)
			(symbol "L_20n_0.35A_0402_0_1"
				(arc
					(start 0.508 0)
					(mid 1.016 0.5058)
					(end 1.524 0)
					(stroke
						(width 0)
						(type default)
					)
					(fill
						(type none)
					)
				)
				(arc
					(start 1.524 0)
					(mid 2.032 0.5058)
					(end 2.54 0)
					(stroke
						(width 0)
						(type default)
					)
					(fill
						(type none)
					)
				)
				(arc
					(start 2.54 0)
					(mid 3.048 0.5058)
					(end 3.556 0)
					(stroke
						(width 0)
						(type default)
					)
					(fill
						(type none)
					)
				)
				(arc
					(start 3.556 0)
					(mid 4.064 0.5058)
					(end 4.572 0)
					(stroke
						(width 0)
						(type default)
					)
					(fill
						(type none)
					)
				)
			)
			(symbol "L_20n_0.35A_0402_1_1"
				(pin passive line
					(at 0 0 0)
					(length 0.508)
					(name "~"
						(effects
							(font
								(size 1.27 1.27)
							)
						)
					)
					(number "1"
						(effects
							(font
								(size 1.27 1.27)
							)
						)
					)
				)
				(pin passive line
					(at 5.08 0 180)
					(length 0.508)
					(name "~"
						(effects
							(font
								(size 1.27 1.27)
							)
						)
					)
					(number "2"
						(effects
							(font
								(size 1.27 1.27)
							)
						)
					)
				)
			)
		)
	(symbol "antmicroFuses:F_1.25A_0603"
			(pin_numbers
				(hide yes)
			)
			(pin_names
				(hide yes)
			)
			(exclude_from_sim no)
			(in_bom yes)
			(on_board yes)
			(property "Reference" "F"
				(at 24.13 -2.54 0)
				(effects
					(font
						(size 1.27 1.27)
						(thickness 0.15)
					)
					(justify left bottom)
				)
			)
			(property "Value" "F_1.25A_0603"
				(at 24.13 -5.08 0)
				(effects
					(font
						(size 1.27 1.27)
						(thickness 0.15)
					)
					(justify left bottom)
					(hide yes)
				)
			)
			(property "Footprint" "antmicro-footprints:F_0603_1608Metric"
				(at 24.13 -7.62 0)
				(effects
					(font
						(size 1.27 1.27)
						(thickness 0.15)
					)
					(justify left bottom)
					(hide yes)
				)
			)
			(property "Datasheet" "https://www.littelfuse.com/~/media/electronics/datasheets/fuses/littelfuse_fuse_467_datasheet.pdf.pdf"
				(at 24.13 -10.16 0)
				(effects
					(font
						(size 1.27 1.27)
						(thickness 0.15)
					)
					(justify left bottom)
					(hide yes)
				)
			)
			(property "Description" "Fuse, Surface Mount, 1.25 A, Very Fast Acting, 32 V, 32 V, 0603 (1608 Metric), 467"
				(at 0 0 0)
				(effects
					(font
						(size 1.27 1.27)
					)
					(hide yes)
				)
			)
			(property "MPN" "04671.25NR"
				(at 24.13 -12.7 0)
				(effects
					(font
						(size 1.27 1.27)
						(thickness 0.15)
					)
					(justify left bottom)
				)
			)
			(property "Manufacturer" "Littelfuse"
				(at 24.13 -15.24 0)
				(effects
					(font
						(size 1.27 1.27)
						(thickness 0.15)
					)
					(justify left bottom)
					(hide yes)
				)
			)
			(property "Author" "Antmicro"
				(at 24.13 -17.78 0)
				(effects
					(font
						(size 1.27 1.27)
						(thickness 0.15)
					)
					(justify left bottom)
					(hide yes)
				)
			)
			(property "License" "Apache-2.0"
				(at 24.13 -20.32 0)
				(effects
					(font
						(size 1.27 1.27)
						(thickness 0.15)
					)
					(justify left bottom)
					(hide yes)
				)
			)
			(property "ki_keywords" "0603, SMT, FUSE, PASSIVE"
				(at 0 0 0)
				(effects
					(font
						(size 1.27 1.27)
					)
					(hide yes)
				)
			)
			(symbol "F_1.25A_0603_0_1"
				(rectangle
					(start 1.27 0.508)
					(end 3.81 -0.508)
					(stroke
						(width 0)
						(type default)
					)
					(fill
						(type none)
					)
				)
				(polyline
					(pts
						(xy 1.27 0) (xy 3.81 0)
					)
					(stroke
						(width 0)
						(type default)
					)
					(fill
						(type none)
					)
				)
			)
			(symbol "F_1.25A_0603_1_1"
				(pin passive line
					(at 0 0 0)
					(length 1.27)
					(name "~"
						(effects
							(font
								(size 1.27 1.27)
							)
						)
					)
					(number "1"
						(effects
							(font
								(size 1.27 1.27)
							)
						)
					)
				)
				(pin passive line
					(at 5.08 0 180)
					(length 1.27)
					(name "~"
						(effects
							(font
								(size 1.27 1.27)
							)
						)
					)
					(number "2"
						(effects
							(font
								(size 1.27 1.27)
							)
						)
					)
				)
			)
		)
	(symbol "antmicroFuses:F_4A_1206"
			(pin_numbers
				(hide yes)
			)
			(pin_names
				(offset 0.9906)
				(hide yes)
			)
			(exclude_from_sim no)
			(in_bom yes)
			(on_board yes)
			(property "Reference" "F"
				(at 20.32 -5.08 0)
				(effects
					(font
						(size 1.27 1.27)
						(thickness 0.15)
					)
					(justify left bottom)
				)
			)
			(property "Value" "F_4A_1206"
				(at 20.32 -7.62 0)
				(effects
					(font
						(size 1.27 1.27)
						(thickness 0.15)
					)
					(justify left bottom)
					(hide yes)
				)
			)
			(property "Footprint" "antmicro-footprints:F_1206_3216Metric"
				(at 20.32 -10.16 0)
				(effects
					(font
						(size 1.27 1.27)
						(thickness 0.15)
					)
					(justify left bottom)
					(hide yes)
				)
			)
			(property "Datasheet" "https://www.littelfuse.com/media?resourcetype=datasheets&itemid=dbe9bcd7-6072-4adf-bf5b-d33e52a6b90f&filename=littelfuse-fuse-466-datasheet"
				(at 20.32 -12.7 0)
				(effects
					(font
						(size 1.27 1.27)
						(thickness 0.15)
					)
					(justify left bottom)
					(hide yes)
				)
			)
			(property "Description" "Fuse, Surface Mount, 4 A, Very Fast Acting, 32 V, 32 V, 1206 (3216 Metric), 466"
				(at 0 0 0)
				(effects
					(font
						(size 1.27 1.27)
					)
					(hide yes)
				)
			)
			(property "Manufacturer" "Littelfuse"
				(at 20.32 -15.24 0)
				(effects
					(font
						(size 1.27 1.27)
						(thickness 0.15)
					)
					(justify left bottom)
					(hide yes)
				)
			)
			(property "MPN" "0466004.NR "
				(at 20.32 -17.78 0)
				(effects
					(font
						(size 1.27 1.27)
						(thickness 0.15)
					)
					(justify left bottom)
				)
			)
			(property "Author" "Antmicro"
				(at 20.32 -20.32 0)
				(effects
					(font
						(size 1.27 1.27)
						(thickness 0.15)
					)
					(justify left bottom)
					(hide yes)
				)
			)
			(property "License" "Apache-2.0"
				(at 20.32 -22.86 0)
				(effects
					(font
						(size 1.27 1.27)
						(thickness 0.15)
					)
					(justify left bottom)
					(hide yes)
				)
			)
			(property "ki_keywords" "FUSE, PASSIVE"
				(at 0 0 0)
				(effects
					(font
						(size 1.27 1.27)
					)
					(hide yes)
				)
			)
			(symbol "F_4A_1206_0_1"
				(rectangle
					(start 1.27 0.508)
					(end 3.81 -0.508)
					(stroke
						(width 0)
						(type default)
					)
					(fill
						(type none)
					)
				)
				(polyline
					(pts
						(xy 1.27 0) (xy 3.81 0)
					)
					(stroke
						(width 0)
						(type default)
					)
					(fill
						(type none)
					)
				)
			)
			(symbol "F_4A_1206_1_1"
				(pin passive line
					(at 0 0 0)
					(length 1.27)
					(name "~"
						(effects
							(font
								(size 1.27 1.27)
							)
						)
					)
					(number "1"
						(effects
							(font
								(size 1.27 1.27)
							)
						)
					)
				)
				(pin passive line
					(at 5.08 0 180)
					(length 1.27)
					(name "~"
						(effects
							(font
								(size 1.27 1.27)
							)
						)
					)
					(number "2"
						(effects
							(font
								(size 1.27 1.27)
							)
						)
					)
				)
			)
		)
	(symbol "antmicroGenericPinHeaders:PinHeader_2x7_P2mm_SMD_Shrouded_no-locator"
			(exclude_from_sim no)
			(in_bom yes)
			(on_board yes)
			(property "Reference" "J"
				(at 25.4 -2.54 0)
				(effects
					(font
						(size 1.27 1.27)
						(thickness 0.15)
					)
					(justify left bottom)
				)
			)
			(property "Value" "PinHeader_2x7_P2mm_SMD_Shrouded_no-locator"
				(at 25.4 -5.08 0)
				(effects
					(font
						(size 1.27 1.27)
						(thickness 0.15)
					)
					(justify left bottom)
					(hide yes)
				)
			)
			(property "Footprint" "antmicro-footprints:PinHeader_2x7_P2mm_SMD_Shrouded_no-locator"
				(at 25.4 -7.62 0)
				(effects
					(font
						(size 1.27 1.27)
						(thickness 0.15)
					)
					(justify left bottom)
					(hide yes)
				)
			)
			(property "Datasheet" "https://www.molex.com/pdm_docs/ps/PS-87831-027-001.pdf"
				(at 25.4 -10.16 0)
				(effects
					(font
						(size 1.27 1.27)
						(thickness 0.15)
					)
					(justify left bottom)
					(hide yes)
				)
			)
			(property "Description" "Pin Header, Signal, Wire-to-Board, 2 mm, 2 Rows, 14 Contacts, Surface Mount Straight"
				(at 0 0 0)
				(effects
					(font
						(size 1.27 1.27)
					)
					(hide yes)
				)
			)
			(property "MPN" "878321412"
				(at 25.4 -12.7 0)
				(effects
					(font
						(size 1.27 1.27)
						(thickness 0.15)
					)
					(justify left bottom)
				)
			)
			(property "Manufacturer" "Molex"
				(at 25.4 -15.24 0)
				(effects
					(font
						(size 1.27 1.27)
						(thickness 0.15)
					)
					(justify left bottom)
					(hide yes)
				)
			)
			(property "Author" "Antmicro"
				(at 25.4 -17.78 0)
				(effects
					(font
						(size 1.27 1.27)
						(thickness 0.15)
					)
					(justify left bottom)
					(hide yes)
				)
			)
			(property "License" "Apache-2.0"
				(at 25.4 -20.32 0)
				(effects
					(font
						(size 1.27 1.27)
						(thickness 0.15)
					)
					(justify left bottom)
					(hide yes)
				)
			)
			(property "ki_keywords" "PINSTRIP, HEADER "
				(at 0 0 0)
				(effects
					(font
						(size 1.27 1.27)
					)
					(hide yes)
				)
			)
			(symbol "PinHeader_2x7_P2mm_SMD_Shrouded_no-locator_1_1"
				(rectangle
					(start 2.54 1.27)
					(end 7.62 -16.51)
					(stroke
						(width 0.254)
						(type default)
					)
					(fill
						(type background)
					)
				)
				(rectangle
					(start 3.556 0.254)
					(end 4.064 -0.254)
					(stroke
						(width 0.254)
						(type default)
					)
					(fill
						(type background)
					)
				)
				(rectangle
					(start 3.556 -2.286)
					(end 4.064 -2.794)
					(stroke
						(width 0.254)
						(type default)
					)
					(fill
						(type background)
					)
				)
				(rectangle
					(start 3.556 -4.826)
					(end 4.064 -5.334)
					(stroke
						(width 0.254)
						(type default)
					)
					(fill
						(type background)
					)
				)
				(rectangle
					(start 3.556 -7.366)
					(end 4.064 -7.874)
					(stroke
						(width 0.254)
						(type default)
					)
					(fill
						(type background)
					)
				)
				(rectangle
					(start 3.556 -9.906)
					(end 4.064 -10.414)
					(stroke
						(width 0.254)
						(type default)
					)
					(fill
						(type background)
					)
				)
				(rectangle
					(start 3.556 -12.446)
					(end 4.064 -12.954)
					(stroke
						(width 0.254)
						(type default)
					)
					(fill
						(type background)
					)
				)
				(rectangle
					(start 3.556 -14.986)
					(end 4.064 -15.494)
					(stroke
						(width 0.254)
						(type default)
					)
					(fill
						(type background)
					)
				)
				(rectangle
					(start 6.096 0.254)
					(end 6.604 -0.254)
					(stroke
						(width 0.254)
						(type default)
					)
					(fill
						(type background)
					)
				)
				(rectangle
					(start 6.096 -2.286)
					(end 6.604 -2.794)
					(stroke
						(width 0.254)
						(type default)
					)
					(fill
						(type background)
					)
				)
				(rectangle
					(start 6.096 -4.826)
					(end 6.604 -5.334)
					(stroke
						(width 0.254)
						(type default)
					)
					(fill
						(type background)
					)
				)
				(rectangle
					(start 6.096 -7.366)
					(end 6.604 -7.874)
					(stroke
						(width 0.254)
						(type default)
					)
					(fill
						(type background)
					)
				)
				(rectangle
					(start 6.096 -9.906)
					(end 6.604 -10.414)
					(stroke
						(width 0.254)
						(type default)
					)
					(fill
						(type background)
					)
				)
				(rectangle
					(start 6.096 -12.446)
					(end 6.604 -12.954)
					(stroke
						(width 0.254)
						(type default)
					)
					(fill
						(type background)
					)
				)
				(rectangle
					(start 6.096 -14.986)
					(end 6.604 -15.494)
					(stroke
						(width 0.254)
						(type default)
					)
					(fill
						(type background)
					)
				)
				(pin passive line
					(at 0 0 0)
					(length 2.54)
					(name "~"
						(effects
							(font
								(size 1.27 1.27)
							)
						)
					)
					(number "1"
						(effects
							(font
								(size 1.27 1.27)
							)
						)
					)
				)
				(pin passive line
					(at 0 -2.54 0)
					(length 2.54)
					(name "~"
						(effects
							(font
								(size 1.27 1.27)
							)
						)
					)
					(number "3"
						(effects
							(font
								(size 1.27 1.27)
							)
						)
					)
				)
				(pin passive line
					(at 0 -5.08 0)
					(length 2.54)
					(name "~"
						(effects
							(font
								(size 1.27 1.27)
							)
						)
					)
					(number "5"
						(effects
							(font
								(size 1.27 1.27)
							)
						)
					)
				)
				(pin passive line
					(at 0 -7.62 0)
					(length 2.54)
					(name "~"
						(effects
							(font
								(size 1.27 1.27)
							)
						)
					)
					(number "7"
						(effects
							(font
								(size 1.27 1.27)
							)
						)
					)
				)
				(pin passive line
					(at 0 -10.16 0)
					(length 2.54)
					(name "~"
						(effects
							(font
								(size 1.27 1.27)
							)
						)
					)
					(number "9"
						(effects
							(font
								(size 1.27 1.27)
							)
						)
					)
				)
				(pin passive line
					(at 0 -12.7 0)
					(length 2.54)
					(name "~"
						(effects
							(font
								(size 1.27 1.27)
							)
						)
					)
					(number "11"
						(effects
							(font
								(size 1.27 1.27)
							)
						)
					)
				)
				(pin passive line
					(at 0 -15.24 0)
					(length 2.54)
					(name "~"
						(effects
							(font
								(size 1.27 1.27)
							)
						)
					)
					(number "13"
						(effects
							(font
								(size 1.27 1.27)
							)
						)
					)
				)
				(pin passive line
					(at 10.16 0 180)
					(length 2.54)
					(name "~"
						(effects
							(font
								(size 1.27 1.27)
							)
						)
					)
					(number "2"
						(effects
							(font
								(size 1.27 1.27)
							)
						)
					)
				)
				(pin passive line
					(at 10.16 -2.54 180)
					(length 2.54)
					(name "~"
						(effects
							(font
								(size 1.27 1.27)
							)
						)
					)
					(number "4"
						(effects
							(font
								(size 1.27 1.27)
							)
						)
					)
				)
				(pin passive line
					(at 10.16 -5.08 180)
					(length 2.54)
					(name "~"
						(effects
							(font
								(size 1.27 1.27)
							)
						)
					)
					(number "6"
						(effects
							(font
								(size 1.27 1.27)
							)
						)
					)
				)
				(pin passive line
					(at 10.16 -7.62 180)
					(length 2.54)
					(name "~"
						(effects
							(font
								(size 1.27 1.27)
							)
						)
					)
					(number "8"
						(effects
							(font
								(size 1.27 1.27)
							)
						)
					)
				)
				(pin passive line
					(at 10.16 -10.16 180)
					(length 2.54)
					(name "~"
						(effects
							(font
								(size 1.27 1.27)
							)
						)
					)
					(number "10"
						(effects
							(font
								(size 1.27 1.27)
							)
						)
					)
				)
				(pin passive line
					(at 10.16 -12.7 180)
					(length 2.54)
					(name "~"
						(effects
							(font
								(size 1.27 1.27)
							)
						)
					)
					(number "12"
						(effects
							(font
								(size 1.27 1.27)
							)
						)
					)
				)
				(pin passive line
					(at 10.16 -15.24 180)
					(length 2.54)
					(name "~"
						(effects
							(font
								(size 1.27 1.27)
							)
						)
					)
					(number "14"
						(effects
							(font
								(size 1.27 1.27)
							)
						)
					)
				)
			)
		)
	(symbol "antmicroInterfaceAnalogSwitchesMultiplexersDemultiplexers:TS5A3359_VSSOP"
			(exclude_from_sim no)
			(in_bom yes)
			(on_board yes)
			(property "Reference" "U"
				(at 41.91 -2.54 0)
				(effects
					(font
						(size 1.27 1.27)
						(thickness 0.15)
					)
					(justify left bottom)
				)
			)
			(property "Value" "TS5A3359_VSSOP"
				(at 41.91 -5.08 0)
				(effects
					(font
						(size 1.27 1.27)
						(thickness 0.15)
					)
					(justify left bottom)
				)
			)
			(property "Footprint" "antmicro-footprints:VSSOP-8_2.3x2mm_P0.5mm"
				(at 41.91 -7.62 0)
				(effects
					(font
						(size 1.27 1.27)
						(thickness 0.15)
					)
					(justify left bottom)
					(hide yes)
				)
			)
			(property "Datasheet" "https://www.ti.com/general/docs/suppproductinfo.tsp?distId=26&gotoUrl=http%3A%2F%2Fwww.ti.com%2Flit%2Fgpn%2Fts5a3359"
				(at 41.91 -10.16 0)
				(effects
					(font
						(size 1.27 1.27)
						(thickness 0.15)
					)
					(justify left bottom)
					(hide yes)
				)
			)
			(property "Description" "Interface analog switch/multiplexer/demultiplexer"
				(at 0 0 0)
				(effects
					(font
						(size 1.27 1.27)
					)
					(hide yes)
				)
			)
			(property "MPN" "TS5A3359DCUR"
				(at 41.91 -12.7 0)
				(effects
					(font
						(size 1.27 1.27)
						(thickness 0.15)
					)
					(justify left bottom)
					(hide yes)
				)
			)
			(property "Manufacturer" "Texas Instruments"
				(at 41.91 -15.24 0)
				(effects
					(font
						(size 1.27 1.27)
						(thickness 0.15)
					)
					(justify left bottom)
					(hide yes)
				)
			)
			(property "Author" "Antmicro"
				(at 41.91 -17.78 0)
				(effects
					(font
						(size 1.27 1.27)
						(thickness 0.15)
					)
					(justify left bottom)
					(hide yes)
				)
			)
			(property "License" "Apache-2.0"
				(at 41.91 -20.32 0)
				(effects
					(font
						(size 1.27 1.27)
						(thickness 0.15)
					)
					(justify left bottom)
					(hide yes)
				)
			)
			(property "ki_keywords" "IC"
				(at 0 0 0)
				(effects
					(font
						(size 1.27 1.27)
					)
					(hide yes)
				)
			)
			(symbol "TS5A3359_VSSOP_1_1"
				(rectangle
					(start 2.54 2.54)
					(end 24.13 -15.24)
					(stroke
						(width 0.254)
						(type default)
					)
					(fill
						(type background)
					)
				)
				(polyline
					(pts
						(xy 7.62 0) (xy 10.16 0)
					)
					(stroke
						(width 0.254)
						(type default)
					)
					(fill
						(type background)
					)
				)
				(polyline
					(pts
						(xy 7.62 -2.54) (xy 10.16 -2.54)
					)
					(stroke
						(width 0.254)
						(type default)
					)
					(fill
						(type background)
					)
				)
				(polyline
					(pts
						(xy 7.62 -5.08) (xy 10.16 -5.08)
					)
					(stroke
						(width 0.254)
						(type default)
					)
					(fill
						(type background)
					)
				)
				(polyline
					(pts
						(xy 7.62 -10.16) (xy 13.208 -10.16)
					)
					(stroke
						(width 0.254)
						(type default)
					)
					(fill
						(type background)
					)
				)
				(polyline
					(pts
						(xy 7.62 -12.7) (xy 13.208 -12.7)
					)
					(stroke
						(width 0.254)
						(type default)
					)
					(fill
						(type background)
					)
				)
				(arc
					(start 10.4902 -0.2794)
					(mid 10.3147 0.0129)
					(end 10.4902 0.3048)
					(stroke
						(width 0.254)
						(type default)
					)
					(fill
						(type background)
					)
				)
				(arc
					(start 10.4902 -2.8194)
					(mid 10.3147 -2.5271)
					(end 10.4902 -2.2352)
					(stroke
						(width 0.254)
						(type default)
					)
					(fill
						(type background)
					)
				)
				(arc
					(start 10.4902 -5.3594)
					(mid 10.3147 -5.0671)
					(end 10.4902 -4.7752)
					(stroke
						(width 0.254)
						(type default)
					)
					(fill
						(type background)
					)
				)
				(arc
					(start 10.4902 0.3048)
					(mid 10.829 0.2941)
					(end 10.9982 0)
					(stroke
						(width 0.254)
						(type default)
					)
					(fill
						(type background)
					)
				)
				(arc
					(start 10.4902 -2.2352)
					(mid 10.829 -2.2459)
					(end 10.9982 -2.54)
					(stroke
						(width 0.254)
						(type default)
					)
					(fill
						(type background)
					)
				)
				(arc
					(start 10.4902 -4.7752)
					(mid 10.829 -4.7859)
					(end 10.9982 -5.08)
					(stroke
						(width 0.254)
						(type default)
					)
					(fill
						(type background)
					)
				)
				(arc
					(start 10.9982 0)
					(mid 10.8272 -0.2881)
					(end 10.4902 -0.2794)
					(stroke
						(width 0.254)
						(type default)
					)
					(fill
						(type background)
					)
				)
				(arc
					(start 10.9982 -2.54)
					(mid 10.8272 -2.8281)
					(end 10.4902 -2.8194)
					(stroke
						(width 0.254)
						(type default)
					)
					(fill
						(type background)
					)
				)
				(arc
					(start 10.9982 -5.08)
					(mid 10.8272 -5.3681)
					(end 10.4902 -5.3594)
					(stroke
						(width 0.254)
						(type default)
					)
					(fill
						(type background)
					)
				)
				(polyline
					(pts
						(xy 13.716 -1.778) (xy 13.716 -12.7)
					)
					(stroke
						(width 0.254)
						(type default)
					)
					(fill
						(type background)
					)
				)
				(polyline
					(pts
						(xy 15.494 -2.54) (xy 11.684 -0.762)
					)
					(stroke
						(width 0.254)
						(type default)
					)
					(fill
						(type background)
					)
				)
				(arc
					(start 15.8242 -2.8194)
					(mid 15.6513 -2.5287)
					(end 15.8242 -2.2352)
					(stroke
						(width 0.254)
						(type default)
					)
					(fill
						(type background)
					)
				)
				(arc
					(start 15.8242 -2.2352)
					(mid 16.161 -2.249)
					(end 16.3322 -2.54)
					(stroke
						(width 0.254)
						(type default)
					)
					(fill
						(type background)
					)
				)
				(arc
					(start 16.3322 -2.54)
					(mid 16.1606 -2.8308)
					(end 15.8242 -2.8194)
					(stroke
						(width 0.254)
						(type default)
					)
					(fill
						(type background)
					)
				)
				(polyline
					(pts
						(xy 19.05 -2.54) (xy 16.51 -2.54)
					)
					(stroke
						(width 0.254)
						(type default)
					)
					(fill
						(type background)
					)
				)
				(pin passive line
					(at 0 0 0)
					(length 2.54)
					(name "NO1"
						(effects
							(font
								(size 1.27 1.27)
							)
						)
					)
					(number "1"
						(effects
							(font
								(size 1.27 1.27)
							)
						)
					)
				)
				(pin passive line
					(at 0 -2.54 0)
					(length 2.54)
					(name "NO2"
						(effects
							(font
								(size 1.27 1.27)
							)
						)
					)
					(number "2"
						(effects
							(font
								(size 1.27 1.27)
							)
						)
					)
				)
				(pin passive line
					(at 0 -5.08 0)
					(length 2.54)
					(name "NO3"
						(effects
							(font
								(size 1.27 1.27)
							)
						)
					)
					(number "3"
						(effects
							(font
								(size 1.27 1.27)
							)
						)
					)
				)
				(pin passive line
					(at 0 -10.16 0)
					(length 2.54)
					(name "IN1"
						(effects
							(font
								(size 1.27 1.27)
							)
						)
					)
					(number "6"
						(effects
							(font
								(size 1.27 1.27)
							)
						)
					)
				)
				(pin passive line
					(at 0 -12.7 0)
					(length 2.54)
					(name "IN2"
						(effects
							(font
								(size 1.27 1.27)
							)
						)
					)
					(number "5"
						(effects
							(font
								(size 1.27 1.27)
							)
						)
					)
				)
				(pin passive line
					(at 26.67 0 180)
					(length 2.54)
					(name "VCC"
						(effects
							(font
								(size 1.27 1.27)
							)
						)
					)
					(number "8"
						(effects
							(font
								(size 1.27 1.27)
							)
						)
					)
				)
				(pin passive line
					(at 26.67 -2.54 180)
					(length 2.54)
					(name "COM"
						(effects
							(font
								(size 1.27 1.27)
							)
						)
					)
					(number "7"
						(effects
							(font
								(size 1.27 1.27)
							)
						)
					)
				)
				(pin passive line
					(at 26.67 -12.7 180)
					(length 2.54)
					(name "GND"
						(effects
							(font
								(size 1.27 1.27)
							)
						)
					)
					(number "4"
						(effects
							(font
								(size 1.27 1.27)
							)
						)
					)
				)
			)
		)
	(symbol "antmicroInterfaceControllers:FT4232H_VQFN"
			(exclude_from_sim no)
			(in_bom yes)
			(on_board yes)
			(property "Reference" "U"
				(at 55.88 -2.54 0)
				(effects
					(font
						(size 1.27 1.27)
						(thickness 0.15)
					)
					(justify left bottom)
				)
			)
			(property "Value" "FT4232H_VQFN"
				(at 55.88 -15.24 0)
				(effects
					(font
						(size 1.27 1.27)
						(thickness 0.15)
					)
					(justify left bottom)
					(hide yes)
				)
			)
			(property "Footprint" "antmicro-footprints:QFN-56-1EP_8x8mm_P0.5mm"
				(at 55.88 -7.62 0)
				(effects
					(font
						(size 1.27 1.27)
						(thickness 0.15)
					)
					(justify left bottom)
					(hide yes)
				)
			)
			(property "Datasheet" "https://www.ftdichip.com/Support/Documents/DataSheets/ICs/DS_FT4232H.pdf"
				(at 55.88 -10.16 0)
				(effects
					(font
						(size 1.27 1.27)
						(thickness 0.15)
					)
					(justify left bottom)
					(hide yes)
				)
			)
			(property "Description" "Interface Bridges, USB to UART, MPSSE, 1.62 V, 1.98 V, VQFN, 56 Pins, -40 °C"
				(at 0 0 0)
				(effects
					(font
						(size 1.27 1.27)
					)
					(hide yes)
				)
			)
			(property "Manufacturer" "FTDI Chip"
				(at 55.88 -12.7 0)
				(effects
					(font
						(size 1.27 1.27)
						(thickness 0.15)
					)
					(justify left bottom)
					(hide yes)
				)
			)
			(property "MPN" "FT4232H-56Q-REEL"
				(at 55.88 -5.08 0)
				(effects
					(font
						(size 1.27 1.27)
						(thickness 0.15)
					)
					(justify left bottom)
				)
			)
			(property "Author" "Antmicro"
				(at 55.88 -17.78 0)
				(effects
					(font
						(size 1.27 1.27)
						(thickness 0.15)
					)
					(justify left bottom)
					(hide yes)
				)
			)
			(property "License" "Apache-2.0"
				(at 55.88 -20.32 0)
				(effects
					(font
						(size 1.27 1.27)
						(thickness 0.15)
					)
					(justify left bottom)
					(hide yes)
				)
			)
			(property "ki_keywords" "SMT, INTERFACE, IC, CONTROLLER, USB, UART, I2C, SPI, JTAG"
				(at 0 0 0)
				(effects
					(font
						(size 1.27 1.27)
					)
					(hide yes)
				)
			)
			(symbol "FT4232H_VQFN_1_1"
				(rectangle
					(start 2.54 2.54)
					(end 38.1 -93.98)
					(stroke
						(width 0.254)
						(type default)
					)
					(fill
						(type background)
					)
				)
				(pin power_in line
					(at 0 0 0)
					(length 2.54)
					(name "V_{REGIN}"
						(effects
							(font
								(size 1.27 1.27)
							)
						)
					)
					(number "44"
						(effects
							(font
								(size 1.27 1.27)
							)
						)
					)
				)
				(pin power_in line
					(at 0 -2.54 0)
					(length 2.54)
					(name "V_{CCIO}"
						(effects
							(font
								(size 1.27 1.27)
							)
						)
					)
					(number "16"
						(effects
							(font
								(size 1.27 1.27)
							)
						)
					)
				)
				(pin passive line
					(at 0 -2.54 0)
					(length 2.54)
					(hide yes)
					(name "V_{CCIO}"
						(effects
							(font
								(size 1.27 1.27)
							)
						)
					)
					(number "36"
						(effects
							(font
								(size 1.27 1.27)
							)
						)
					)
				)
				(pin passive line
					(at 0 -2.54 0)
					(length 2.54)
					(hide yes)
					(name "V_{CCIO}"
						(effects
							(font
								(size 1.27 1.27)
							)
						)
					)
					(number "50"
						(effects
							(font
								(size 1.27 1.27)
							)
						)
					)
				)
				(pin power_out line
					(at 0 -6.35 0)
					(length 2.54)
					(name "V_{REGOUT}"
						(effects
							(font
								(size 1.27 1.27)
							)
						)
					)
					(number "43"
						(effects
							(font
								(size 1.27 1.27)
							)
						)
					)
				)
				(pin power_in line
					(at 0 -10.16 0)
					(length 2.54)
					(name "V_{PHY}"
						(effects
							(font
								(size 1.27 1.27)
							)
						)
					)
					(number "5"
						(effects
							(font
								(size 1.27 1.27)
							)
						)
					)
				)
				(pin power_in line
					(at 0 -12.7 0)
					(length 2.54)
					(name "V_{PLL}"
						(effects
							(font
								(size 1.27 1.27)
							)
						)
					)
					(number "9"
						(effects
							(font
								(size 1.27 1.27)
							)
						)
					)
				)
				(pin power_in line
					(at 0 -15.24 0)
					(length 2.54)
					(name "V_{CORE}"
						(effects
							(font
								(size 1.27 1.27)
							)
						)
					)
					(number "2"
						(effects
							(font
								(size 1.27 1.27)
							)
						)
					)
				)
				(pin passive line
					(at 0 -15.24 0)
					(length 2.54)
					(hide yes)
					(name "V_{CORE}"
						(effects
							(font
								(size 1.27 1.27)
							)
						)
					)
					(number "31"
						(effects
							(font
								(size 1.27 1.27)
							)
						)
					)
				)
				(pin bidirectional line
					(at 0 -22.86 0)
					(length 2.54)
					(name "D+"
						(effects
							(font
								(size 1.27 1.27)
							)
						)
					)
					(number "8"
						(effects
							(font
								(size 1.27 1.27)
							)
						)
					)
				)
				(pin bidirectional line
					(at 0 -25.4 0)
					(length 2.54)
					(name "D-"
						(effects
							(font
								(size 1.27 1.27)
							)
						)
					)
					(number "7"
						(effects
							(font
								(size 1.27 1.27)
							)
						)
					)
				)
				(pin input line
					(at 0 -36.83 0)
					(length 2.54)
					(name "~{RESET}"
						(effects
							(font
								(size 1.27 1.27)
							)
						)
					)
					(number "11"
						(effects
							(font
								(size 1.27 1.27)
							)
						)
					)
				)
				(pin bidirectional line
					(at 0 -44.45 0)
					(length 2.54)
					(name "EECS"
						(effects
							(font
								(size 1.27 1.27)
							)
						)
					)
					(number "1"
						(effects
							(font
								(size 1.27 1.27)
							)
						)
					)
				)
				(pin output line
					(at 0 -46.99 0)
					(length 2.54)
					(name "EECLK"
						(effects
							(font
								(size 1.27 1.27)
							)
						)
					)
					(number "56"
						(effects
							(font
								(size 1.27 1.27)
							)
						)
					)
				)
				(pin bidirectional line
					(at 0 -49.53 0)
					(length 2.54)
					(name "EEDATA"
						(effects
							(font
								(size 1.27 1.27)
							)
						)
					)
					(number "55"
						(effects
							(font
								(size 1.27 1.27)
							)
						)
					)
				)
				(pin input line
					(at 0 -54.61 0)
					(length 2.54)
					(name "OSCI"
						(effects
							(font
								(size 1.27 1.27)
							)
						)
					)
					(number "3"
						(effects
							(font
								(size 1.27 1.27)
							)
						)
					)
				)
				(pin output line
					(at 0 -59.69 0)
					(length 2.54)
					(name "OSCO"
						(effects
							(font
								(size 1.27 1.27)
							)
						)
					)
					(number "4"
						(effects
							(font
								(size 1.27 1.27)
							)
						)
					)
				)
				(pin input line
					(at 0 -77.47 0)
					(length 2.54)
					(name "REF"
						(effects
							(font
								(size 1.27 1.27)
							)
						)
					)
					(number "6"
						(effects
							(font
								(size 1.27 1.27)
							)
						)
					)
				)
				(pin input line
					(at 0 -88.9 0)
					(length 2.54)
					(name "TEST"
						(effects
							(font
								(size 1.27 1.27)
							)
						)
					)
					(number "10"
						(effects
							(font
								(size 1.27 1.27)
							)
						)
					)
				)
				(pin power_in line
					(at 0 -91.44 0)
					(length 2.54)
					(name "GND"
						(effects
							(font
								(size 1.27 1.27)
							)
						)
					)
					(number "21"
						(effects
							(font
								(size 1.27 1.27)
							)
						)
					)
				)
				(pin passive line
					(at 0 -91.44 0)
					(length 2.54)
					(hide yes)
					(name "GND"
						(effects
							(font
								(size 1.27 1.27)
							)
						)
					)
					(number "41"
						(effects
							(font
								(size 1.27 1.27)
							)
						)
					)
				)
				(pin passive line
					(at 0 -91.44 0)
					(length 2.54)
					(hide yes)
					(name "GND"
						(effects
							(font
								(size 1.27 1.27)
							)
						)
					)
					(number "45"
						(effects
							(font
								(size 1.27 1.27)
							)
						)
					)
				)
				(pin passive line
					(at 0 -91.44 0)
					(length 2.54)
					(hide yes)
					(name "GND"
						(effects
							(font
								(size 1.27 1.27)
							)
						)
					)
					(number "57"
						(effects
							(font
								(size 1.27 1.27)
							)
						)
					)
				)
				(pin bidirectional line
					(at 40.64 0 180)
					(length 2.54)
					(name "ADBUS0"
						(effects
							(font
								(size 1.27 1.27)
							)
						)
					)
					(number "12"
						(effects
							(font
								(size 1.27 1.27)
							)
						)
					)
				)
				(pin bidirectional line
					(at 40.64 -2.54 180)
					(length 2.54)
					(name "ADBUS1"
						(effects
							(font
								(size 1.27 1.27)
							)
						)
					)
					(number "13"
						(effects
							(font
								(size 1.27 1.27)
							)
						)
					)
				)
				(pin bidirectional line
					(at 40.64 -5.08 180)
					(length 2.54)
					(name "ADBUS2"
						(effects
							(font
								(size 1.27 1.27)
							)
						)
					)
					(number "14"
						(effects
							(font
								(size 1.27 1.27)
							)
						)
					)
				)
				(pin bidirectional line
					(at 40.64 -7.62 180)
					(length 2.54)
					(name "ADBUS3"
						(effects
							(font
								(size 1.27 1.27)
							)
						)
					)
					(number "15"
						(effects
							(font
								(size 1.27 1.27)
							)
						)
					)
				)
				(pin bidirectional line
					(at 40.64 -10.16 180)
					(length 2.54)
					(name "ADBUS4"
						(effects
							(font
								(size 1.27 1.27)
							)
						)
					)
					(number "17"
						(effects
							(font
								(size 1.27 1.27)
							)
						)
					)
				)
				(pin bidirectional line
					(at 40.64 -12.7 180)
					(length 2.54)
					(name "ADBUS5"
						(effects
							(font
								(size 1.27 1.27)
							)
						)
					)
					(number "18"
						(effects
							(font
								(size 1.27 1.27)
							)
						)
					)
				)
				(pin bidirectional line
					(at 40.64 -15.24 180)
					(length 2.54)
					(name "ADBUS6"
						(effects
							(font
								(size 1.27 1.27)
							)
						)
					)
					(number "19"
						(effects
							(font
								(size 1.27 1.27)
							)
						)
					)
				)
				(pin bidirectional line
					(at 40.64 -17.78 180)
					(length 2.54)
					(name "ADBUS7"
						(effects
							(font
								(size 1.27 1.27)
							)
						)
					)
					(number "20"
						(effects
							(font
								(size 1.27 1.27)
							)
						)
					)
				)
				(pin bidirectional line
					(at 40.64 -21.59 180)
					(length 2.54)
					(name "BDBUS0"
						(effects
							(font
								(size 1.27 1.27)
							)
						)
					)
					(number "22"
						(effects
							(font
								(size 1.27 1.27)
							)
						)
					)
				)
				(pin bidirectional line
					(at 40.64 -24.13 180)
					(length 2.54)
					(name "BDBUS1"
						(effects
							(font
								(size 1.27 1.27)
							)
						)
					)
					(number "23"
						(effects
							(font
								(size 1.27 1.27)
							)
						)
					)
				)
				(pin bidirectional line
					(at 40.64 -26.67 180)
					(length 2.54)
					(name "BDBUS2"
						(effects
							(font
								(size 1.27 1.27)
							)
						)
					)
					(number "24"
						(effects
							(font
								(size 1.27 1.27)
							)
						)
					)
				)
				(pin bidirectional line
					(at 40.64 -29.21 180)
					(length 2.54)
					(name "BDBUS3"
						(effects
							(font
								(size 1.27 1.27)
							)
						)
					)
					(number "25"
						(effects
							(font
								(size 1.27 1.27)
							)
						)
					)
				)
				(pin bidirectional line
					(at 40.64 -31.75 180)
					(length 2.54)
					(name "BDBUS4"
						(effects
							(font
								(size 1.27 1.27)
							)
						)
					)
					(number "26"
						(effects
							(font
								(size 1.27 1.27)
							)
						)
					)
				)
				(pin bidirectional line
					(at 40.64 -34.29 180)
					(length 2.54)
					(name "BDBUS5"
						(effects
							(font
								(size 1.27 1.27)
							)
						)
					)
					(number "27"
						(effects
							(font
								(size 1.27 1.27)
							)
						)
					)
				)
				(pin bidirectional line
					(at 40.64 -36.83 180)
					(length 2.54)
					(name "BDBUS6"
						(effects
							(font
								(size 1.27 1.27)
							)
						)
					)
					(number "28"
						(effects
							(font
								(size 1.27 1.27)
							)
						)
					)
				)
				(pin bidirectional line
					(at 40.64 -39.37 180)
					(length 2.54)
					(name "BDBUS7"
						(effects
							(font
								(size 1.27 1.27)
							)
						)
					)
					(number "29"
						(effects
							(font
								(size 1.27 1.27)
							)
						)
					)
				)
				(pin bidirectional line
					(at 40.64 -43.18 180)
					(length 2.54)
					(name "CDBUS0"
						(effects
							(font
								(size 1.27 1.27)
							)
						)
					)
					(number "32"
						(effects
							(font
								(size 1.27 1.27)
							)
						)
					)
				)
				(pin bidirectional line
					(at 40.64 -45.72 180)
					(length 2.54)
					(name "CDBUS1"
						(effects
							(font
								(size 1.27 1.27)
							)
						)
					)
					(number "33"
						(effects
							(font
								(size 1.27 1.27)
							)
						)
					)
				)
				(pin bidirectional line
					(at 40.64 -48.26 180)
					(length 2.54)
					(name "CDBUS2"
						(effects
							(font
								(size 1.27 1.27)
							)
						)
					)
					(number "34"
						(effects
							(font
								(size 1.27 1.27)
							)
						)
					)
				)
				(pin bidirectional line
					(at 40.64 -50.8 180)
					(length 2.54)
					(name "CDBUS3"
						(effects
							(font
								(size 1.27 1.27)
							)
						)
					)
					(number "35"
						(effects
							(font
								(size 1.27 1.27)
							)
						)
					)
				)
				(pin bidirectional line
					(at 40.64 -53.34 180)
					(length 2.54)
					(name "CDBUS4"
						(effects
							(font
								(size 1.27 1.27)
							)
						)
					)
					(number "37"
						(effects
							(font
								(size 1.27 1.27)
							)
						)
					)
				)
				(pin bidirectional line
					(at 40.64 -55.88 180)
					(length 2.54)
					(name "CDBUS5"
						(effects
							(font
								(size 1.27 1.27)
							)
						)
					)
					(number "38"
						(effects
							(font
								(size 1.27 1.27)
							)
						)
					)
				)
				(pin bidirectional line
					(at 40.64 -58.42 180)
					(length 2.54)
					(name "CDBUS6"
						(effects
							(font
								(size 1.27 1.27)
							)
						)
					)
					(number "39"
						(effects
							(font
								(size 1.27 1.27)
							)
						)
					)
				)
				(pin bidirectional line
					(at 40.64 -60.96 180)
					(length 2.54)
					(name "CDBUS7"
						(effects
							(font
								(size 1.27 1.27)
							)
						)
					)
					(number "40"
						(effects
							(font
								(size 1.27 1.27)
							)
						)
					)
				)
				(pin bidirectional line
					(at 40.64 -64.77 180)
					(length 2.54)
					(name "DDBUS0"
						(effects
							(font
								(size 1.27 1.27)
							)
						)
					)
					(number "42"
						(effects
							(font
								(size 1.27 1.27)
							)
						)
					)
				)
				(pin bidirectional line
					(at 40.64 -67.31 180)
					(length 2.54)
					(name "DDBUS1"
						(effects
							(font
								(size 1.27 1.27)
							)
						)
					)
					(number "46"
						(effects
							(font
								(size 1.27 1.27)
							)
						)
					)
				)
				(pin bidirectional line
					(at 40.64 -69.85 180)
					(length 2.54)
					(name "DDBUS2"
						(effects
							(font
								(size 1.27 1.27)
							)
						)
					)
					(number "47"
						(effects
							(font
								(size 1.27 1.27)
							)
						)
					)
				)
				(pin bidirectional line
					(at 40.64 -72.39 180)
					(length 2.54)
					(name "DDBUS3"
						(effects
							(font
								(size 1.27 1.27)
							)
						)
					)
					(number "48"
						(effects
							(font
								(size 1.27 1.27)
							)
						)
					)
				)
				(pin bidirectional line
					(at 40.64 -74.93 180)
					(length 2.54)
					(name "DDBUS4"
						(effects
							(font
								(size 1.27 1.27)
							)
						)
					)
					(number "49"
						(effects
							(font
								(size 1.27 1.27)
							)
						)
					)
				)
				(pin bidirectional line
					(at 40.64 -77.47 180)
					(length 2.54)
					(name "DDBUS5"
						(effects
							(font
								(size 1.27 1.27)
							)
						)
					)
					(number "51"
						(effects
							(font
								(size 1.27 1.27)
							)
						)
					)
				)
				(pin bidirectional line
					(at 40.64 -80.01 180)
					(length 2.54)
					(name "DDBUS6"
						(effects
							(font
								(size 1.27 1.27)
							)
						)
					)
					(number "52"
						(effects
							(font
								(size 1.27 1.27)
							)
						)
					)
				)
				(pin bidirectional line
					(at 40.64 -82.55 180)
					(length 2.54)
					(name "DDBUS7"
						(effects
							(font
								(size 1.27 1.27)
							)
						)
					)
					(number "53"
						(effects
							(font
								(size 1.27 1.27)
							)
						)
					)
				)
				(pin output line
					(at 40.64 -87.63 180)
					(length 2.54)
					(name "~{PWR_{EN}}"
						(effects
							(font
								(size 1.27 1.27)
							)
						)
					)
					(number "54"
						(effects
							(font
								(size 1.27 1.27)
							)
						)
					)
				)
				(pin output line
					(at 40.64 -90.17 180)
					(length 2.54)
					(name "~{SUSPEND}"
						(effects
							(font
								(size 1.27 1.27)
							)
						)
					)
					(number "30"
						(effects
							(font
								(size 1.27 1.27)
							)
						)
					)
				)
			)
		)
	(symbol "antmicroInterfaceControllers:KSZ9031RNXCA"
			(exclude_from_sim no)
			(in_bom yes)
			(on_board yes)
			(property "Reference" "U"
				(at 76.2 -5.08 0)
				(effects
					(font
						(size 1.27 1.27)
						(thickness 0.15)
					)
					(justify left bottom)
				)
			)
			(property "Value" "KSZ9031RNXCA"
				(at 76.2 -7.62 0)
				(effects
					(font
						(size 1.27 1.27)
						(thickness 0.15)
					)
					(justify left bottom)
					(hide yes)
				)
			)
			(property "Footprint" "antmicro-footprints:QFN-48-1EP_7x7x0.9mm_P0.5mm_EP3.5x3.5mm"
				(at 76.2 -10.16 0)
				(effects
					(font
						(size 1.27 1.27)
						(thickness 0.15)
					)
					(justify left bottom)
					(hide yes)
				)
			)
			(property "Datasheet" "http://ww1.microchip.com/downloads/en/DeviceDoc/00002117F.pdf"
				(at 76.2 -12.7 0)
				(effects
					(font
						(size 1.27 1.27)
						(thickness 0.15)
					)
					(justify left bottom)
					(hide yes)
				)
			)
			(property "Description" "Ethernet Controller, 1000 Mbps, IEEE 802.3, 1.14 V, 3.465 V, QFN, 48 Pins"
				(at 0 0 0)
				(effects
					(font
						(size 1.27 1.27)
					)
					(hide yes)
				)
			)
			(property "Manufacturer" "Microchip Technology"
				(at 76.2 -15.24 0)
				(effects
					(font
						(size 1.27 1.27)
						(thickness 0.15)
					)
					(justify left bottom)
					(hide yes)
				)
			)
			(property "MPN" "KSZ9031RNXCA"
				(at 76.2 -17.78 0)
				(effects
					(font
						(size 1.27 1.27)
						(thickness 0.15)
					)
					(justify left bottom)
				)
			)
			(property "Author" "Antmicro"
				(at 76.2 -20.32 0)
				(effects
					(font
						(size 1.27 1.27)
						(thickness 0.15)
					)
					(justify left bottom)
					(hide yes)
				)
			)
			(property "License" "Apache-2.0"
				(at 76.2 -22.86 0)
				(effects
					(font
						(size 1.27 1.27)
						(thickness 0.15)
					)
					(justify left bottom)
					(hide yes)
				)
			)
			(property "ki_keywords" "SMT, TRANSCEIVER, IC, ETHERNET, PHY"
				(at 0 0 0)
				(effects
					(font
						(size 1.27 1.27)
					)
					(hide yes)
				)
			)
			(symbol "KSZ9031RNXCA_1_1"
				(rectangle
					(start 2.54 2.54)
					(end 41.91 -62.23)
					(stroke
						(width 0.254)
						(type default)
					)
					(fill
						(type background)
					)
				)
				(text "10/100/1000"
					(at 21.59 -1.27 0)
					(effects
						(font
							(size 1.27 1.27)
							(thickness 0.15)
						)
						(justify bottom)
					)
				)
				(text "Ethernet PHY"
					(at 21.59 -3.81 0)
					(effects
						(font
							(size 1.27 1.27)
							(thickness 0.15)
						)
						(justify bottom)
					)
				)
				(pin power_in line
					(at 0 0 0)
					(length 2.54)
					(name "DVDDH"
						(effects
							(font
								(size 1.27 1.27)
							)
						)
					)
					(number "16"
						(effects
							(font
								(size 1.27 1.27)
							)
						)
					)
				)
				(pin passive line
					(at 0 0 0)
					(length 2.54)
					(hide yes)
					(name "DVDDH"
						(effects
							(font
								(size 1.27 1.27)
							)
						)
					)
					(number "34"
						(effects
							(font
								(size 1.27 1.27)
							)
						)
					)
				)
				(pin passive line
					(at 0 0 0)
					(length 2.54)
					(hide yes)
					(name "DVDDH"
						(effects
							(font
								(size 1.27 1.27)
							)
						)
					)
					(number "40"
						(effects
							(font
								(size 1.27 1.27)
							)
						)
					)
				)
				(pin power_in line
					(at 0 -3.81 0)
					(length 2.54)
					(name "AVDDH"
						(effects
							(font
								(size 1.27 1.27)
							)
						)
					)
					(number "1"
						(effects
							(font
								(size 1.27 1.27)
							)
						)
					)
				)
				(pin passive line
					(at 0 -3.81 0)
					(length 2.54)
					(hide yes)
					(name "AVDDH"
						(effects
							(font
								(size 1.27 1.27)
							)
						)
					)
					(number "12"
						(effects
							(font
								(size 1.27 1.27)
							)
						)
					)
				)
				(pin input line
					(at 0 -7.62 0)
					(length 2.54)
					(name "~{RESET}"
						(effects
							(font
								(size 1.27 1.27)
							)
						)
					)
					(number "42"
						(effects
							(font
								(size 1.27 1.27)
							)
						)
					)
				)
				(pin input line
					(at 0 -10.16 0)
					(length 2.54)
					(name "~{INT/PME}"
						(effects
							(font
								(size 1.27 1.27)
							)
						)
					)
					(number "38"
						(effects
							(font
								(size 1.27 1.27)
							)
						)
					)
				)
				(pin input line
					(at 0 -13.97 0)
					(length 2.54)
					(name "MDC"
						(effects
							(font
								(size 1.27 1.27)
							)
						)
					)
					(number "36"
						(effects
							(font
								(size 1.27 1.27)
							)
						)
					)
				)
				(pin input line
					(at 0 -16.51 0)
					(length 2.54)
					(name "MDIO"
						(effects
							(font
								(size 1.27 1.27)
							)
						)
					)
					(number "37"
						(effects
							(font
								(size 1.27 1.27)
							)
						)
					)
				)
				(pin input line
					(at 0 -20.32 0)
					(length 2.54)
					(name "TX_EN"
						(effects
							(font
								(size 1.27 1.27)
							)
						)
					)
					(number "25"
						(effects
							(font
								(size 1.27 1.27)
							)
						)
					)
				)
				(pin input line
					(at 0 -22.86 0)
					(length 2.54)
					(name "TXD0"
						(effects
							(font
								(size 1.27 1.27)
							)
						)
					)
					(number "19"
						(effects
							(font
								(size 1.27 1.27)
							)
						)
					)
				)
				(pin input line
					(at 0 -25.4 0)
					(length 2.54)
					(name "TXD1"
						(effects
							(font
								(size 1.27 1.27)
							)
						)
					)
					(number "20"
						(effects
							(font
								(size 1.27 1.27)
							)
						)
					)
				)
				(pin input line
					(at 0 -27.94 0)
					(length 2.54)
					(name "TXD2"
						(effects
							(font
								(size 1.27 1.27)
							)
						)
					)
					(number "21"
						(effects
							(font
								(size 1.27 1.27)
							)
						)
					)
				)
				(pin input line
					(at 0 -30.48 0)
					(length 2.54)
					(name "TXD3"
						(effects
							(font
								(size 1.27 1.27)
							)
						)
					)
					(number "22"
						(effects
							(font
								(size 1.27 1.27)
							)
						)
					)
				)
				(pin input clock
					(at 0 -33.02 0)
					(length 2.54)
					(name "GTX_CLK"
						(effects
							(font
								(size 1.27 1.27)
							)
						)
					)
					(number "24"
						(effects
							(font
								(size 1.27 1.27)
							)
						)
					)
				)
				(pin input line
					(at 0 -36.83 0)
					(length 2.54)
					(name "RX_DV/CLK125_EN"
						(effects
							(font
								(size 1.27 1.27)
							)
						)
					)
					(number "33"
						(effects
							(font
								(size 1.27 1.27)
							)
						)
					)
				)
				(pin input line
					(at 0 -39.37 0)
					(length 2.54)
					(name "RXD0/MODE0"
						(effects
							(font
								(size 1.27 1.27)
							)
						)
					)
					(number "32"
						(effects
							(font
								(size 1.27 1.27)
							)
						)
					)
				)
				(pin input line
					(at 0 -41.91 0)
					(length 2.54)
					(name "RXD1/MODE1"
						(effects
							(font
								(size 1.27 1.27)
							)
						)
					)
					(number "31"
						(effects
							(font
								(size 1.27 1.27)
							)
						)
					)
				)
				(pin input line
					(at 0 -44.45 0)
					(length 2.54)
					(name "RXD2/MODE2"
						(effects
							(font
								(size 1.27 1.27)
							)
						)
					)
					(number "28"
						(effects
							(font
								(size 1.27 1.27)
							)
						)
					)
				)
				(pin input line
					(at 0 -46.99 0)
					(length 2.54)
					(name "RXD3/MODE3"
						(effects
							(font
								(size 1.27 1.27)
							)
						)
					)
					(number "27"
						(effects
							(font
								(size 1.27 1.27)
							)
						)
					)
				)
				(pin input clock
					(at 0 -49.53 0)
					(length 2.54)
					(name "RX_CLK/PHYAD2"
						(effects
							(font
								(size 1.27 1.27)
							)
						)
					)
					(number "35"
						(effects
							(font
								(size 1.27 1.27)
							)
						)
					)
				)
				(pin input clock
					(at 0 -53.34 0)
					(length 2.54)
					(name "CLK125_NDO/LED_MODE"
						(effects
							(font
								(size 1.27 1.27)
							)
						)
					)
					(number "41"
						(effects
							(font
								(size 1.27 1.27)
							)
						)
					)
				)
				(pin input line
					(at 0 -57.15 0)
					(length 2.54)
					(name "XI"
						(effects
							(font
								(size 1.27 1.27)
							)
						)
					)
					(number "46"
						(effects
							(font
								(size 1.27 1.27)
							)
						)
					)
				)
				(pin input line
					(at 0 -59.69 0)
					(length 2.54)
					(name "XO"
						(effects
							(font
								(size 1.27 1.27)
							)
						)
					)
					(number "45"
						(effects
							(font
								(size 1.27 1.27)
							)
						)
					)
				)
				(pin no_connect line
					(at 41.91 -52.07 180)
					(length 2.54)
					(hide yes)
					(name "NC"
						(effects
							(font
								(size 1.27 1.27)
							)
						)
					)
					(number "47"
						(effects
							(font
								(size 1.27 1.27)
							)
						)
					)
				)
				(pin no_connect line
					(at 41.91 -53.34 180)
					(length 2.54)
					(hide yes)
					(name "NC"
						(effects
							(font
								(size 1.27 1.27)
							)
						)
					)
					(number "13"
						(effects
							(font
								(size 1.27 1.27)
							)
						)
					)
				)
				(pin power_in line
					(at 44.45 0 180)
					(length 2.54)
					(name "DVDDL"
						(effects
							(font
								(size 1.27 1.27)
							)
						)
					)
					(number "14"
						(effects
							(font
								(size 1.27 1.27)
							)
						)
					)
				)
				(pin passive line
					(at 44.45 0 180)
					(length 2.54)
					(hide yes)
					(name "DVDDL"
						(effects
							(font
								(size 1.27 1.27)
							)
						)
					)
					(number "18"
						(effects
							(font
								(size 1.27 1.27)
							)
						)
					)
				)
				(pin passive line
					(at 44.45 0 180)
					(length 2.54)
					(hide yes)
					(name "DVDDL"
						(effects
							(font
								(size 1.27 1.27)
							)
						)
					)
					(number "23"
						(effects
							(font
								(size 1.27 1.27)
							)
						)
					)
				)
				(pin passive line
					(at 44.45 0 180)
					(length 2.54)
					(hide yes)
					(name "DVDDL"
						(effects
							(font
								(size 1.27 1.27)
							)
						)
					)
					(number "26"
						(effects
							(font
								(size 1.27 1.27)
							)
						)
					)
				)
				(pin passive line
					(at 44.45 0 180)
					(length 2.54)
					(hide yes)
					(name "DVDDL"
						(effects
							(font
								(size 1.27 1.27)
							)
						)
					)
					(number "30"
						(effects
							(font
								(size 1.27 1.27)
							)
						)
					)
				)
				(pin passive line
					(at 44.45 0 180)
					(length 2.54)
					(hide yes)
					(name "DVDDL"
						(effects
							(font
								(size 1.27 1.27)
							)
						)
					)
					(number "39"
						(effects
							(font
								(size 1.27 1.27)
							)
						)
					)
				)
				(pin power_in line
					(at 44.45 -3.81 180)
					(length 2.54)
					(name "AVDDL"
						(effects
							(font
								(size 1.27 1.27)
							)
						)
					)
					(number "4"
						(effects
							(font
								(size 1.27 1.27)
							)
						)
					)
				)
				(pin passive line
					(at 44.45 -3.81 180)
					(length 2.54)
					(hide yes)
					(name "AVDDL"
						(effects
							(font
								(size 1.27 1.27)
							)
						)
					)
					(number "9"
						(effects
							(font
								(size 1.27 1.27)
							)
						)
					)
				)
				(pin power_in line
					(at 44.45 -6.35 180)
					(length 2.54)
					(name "AVDDL_PLL"
						(effects
							(font
								(size 1.27 1.27)
							)
						)
					)
					(number "44"
						(effects
							(font
								(size 1.27 1.27)
							)
						)
					)
				)
				(pin input line
					(at 44.45 -8.89 180)
					(length 2.54)
					(name "LDO_O"
						(effects
							(font
								(size 1.27 1.27)
							)
						)
					)
					(number "43"
						(effects
							(font
								(size 1.27 1.27)
							)
						)
					)
				)
				(pin bidirectional line
					(at 44.45 -13.97 180)
					(length 2.54)
					(name "TXRXP_A"
						(effects
							(font
								(size 1.27 1.27)
							)
						)
					)
					(number "2"
						(effects
							(font
								(size 1.27 1.27)
							)
						)
					)
				)
				(pin bidirectional line
					(at 44.45 -16.51 180)
					(length 2.54)
					(name "TXRXM_A"
						(effects
							(font
								(size 1.27 1.27)
							)
						)
					)
					(number "3"
						(effects
							(font
								(size 1.27 1.27)
							)
						)
					)
				)
				(pin bidirectional line
					(at 44.45 -20.32 180)
					(length 2.54)
					(name "TXRXP_B"
						(effects
							(font
								(size 1.27 1.27)
							)
						)
					)
					(number "5"
						(effects
							(font
								(size 1.27 1.27)
							)
						)
					)
				)
				(pin bidirectional line
					(at 44.45 -22.86 180)
					(length 2.54)
					(name "TXRXM_B"
						(effects
							(font
								(size 1.27 1.27)
							)
						)
					)
					(number "6"
						(effects
							(font
								(size 1.27 1.27)
							)
						)
					)
				)
				(pin bidirectional line
					(at 44.45 -26.67 180)
					(length 2.54)
					(name "TXRXP_C"
						(effects
							(font
								(size 1.27 1.27)
							)
						)
					)
					(number "7"
						(effects
							(font
								(size 1.27 1.27)
							)
						)
					)
				)
				(pin bidirectional line
					(at 44.45 -29.21 180)
					(length 2.54)
					(name "TXRXM_C"
						(effects
							(font
								(size 1.27 1.27)
							)
						)
					)
					(number "8"
						(effects
							(font
								(size 1.27 1.27)
							)
						)
					)
				)
				(pin bidirectional line
					(at 44.45 -33.02 180)
					(length 2.54)
					(name "TXRXP_D"
						(effects
							(font
								(size 1.27 1.27)
							)
						)
					)
					(number "10"
						(effects
							(font
								(size 1.27 1.27)
							)
						)
					)
				)
				(pin bidirectional line
					(at 44.45 -35.56 180)
					(length 2.54)
					(name "TXRXM_D"
						(effects
							(font
								(size 1.27 1.27)
							)
						)
					)
					(number "11"
						(effects
							(font
								(size 1.27 1.27)
							)
						)
					)
				)
				(pin bidirectional line
					(at 44.45 -41.91 180)
					(length 2.54)
					(name "LED1/PHYAD0/PME_N1"
						(effects
							(font
								(size 1.27 1.27)
							)
						)
					)
					(number "17"
						(effects
							(font
								(size 1.27 1.27)
							)
						)
					)
				)
				(pin bidirectional line
					(at 44.45 -44.45 180)
					(length 2.54)
					(name "LED2/PHYAD1"
						(effects
							(font
								(size 1.27 1.27)
							)
						)
					)
					(number "15"
						(effects
							(font
								(size 1.27 1.27)
							)
						)
					)
				)
				(pin output line
					(at 44.45 -49.53 180)
					(length 2.54)
					(name "ISET"
						(effects
							(font
								(size 1.27 1.27)
							)
						)
					)
					(number "48"
						(effects
							(font
								(size 1.27 1.27)
							)
						)
					)
				)
				(pin power_in line
					(at 44.45 -57.15 180)
					(length 2.54)
					(name "PAD_GND"
						(effects
							(font
								(size 1.27 1.27)
							)
						)
					)
					(number "49"
						(effects
							(font
								(size 1.27 1.27)
							)
						)
					)
				)
				(pin power_in line
					(at 44.45 -59.69 180)
					(length 2.54)
					(name "VSS"
						(effects
							(font
								(size 1.27 1.27)
							)
						)
					)
					(number "29"
						(effects
							(font
								(size 1.27 1.27)
							)
						)
					)
				)
			)
		)
	(symbol "antmicroInterfaceDriversReceiversTransceivers:SN65DP159RGZR"
			(exclude_from_sim no)
			(in_bom yes)
			(on_board yes)
			(property "Reference" "U"
				(at 50.8 0 0)
				(effects
					(font
						(size 1.27 1.27)
						(thickness 0.15)
					)
					(justify left bottom)
				)
			)
			(property "Value" "SN65DP159RGZR"
				(at 50.8 -5.08 0)
				(effects
					(font
						(size 1.27 1.27)
						(thickness 0.15)
					)
					(justify left bottom)
					(hide yes)
				)
			)
			(property "Footprint" "antmicro-footprints:VQFN-48_7x7mm_P0.5mm_EP4.1x4.1mm"
				(at 50.8 -7.62 0)
				(effects
					(font
						(size 1.27 1.27)
						(thickness 0.15)
					)
					(justify left bottom)
					(hide yes)
				)
			)
			(property "Datasheet" "https://www.ti.com/lit/ds/symlink/sn75dp159.pdf?ts=1728245191743&ref_url=https%253A%252F%252Fwww.mouser.de%252F"
				(at 50.8 -10.16 0)
				(effects
					(font
						(size 1.27 1.27)
						(thickness 0.15)
					)
					(justify left bottom)
					(hide yes)
				)
			)
			(property "Description" "Display Interface, Level Shifter Retimer, DVI, HDMI, I2C, 6 Gbps"
				(at 0 0 0)
				(effects
					(font
						(size 1.27 1.27)
					)
					(hide yes)
				)
			)
			(property "MPN" "SN65DP159RGZR "
				(at 50.8 -2.54 0)
				(effects
					(font
						(size 1.27 1.27)
						(thickness 0.15)
					)
					(justify left bottom)
				)
			)
			(property "Manufacturer" "Texas Instruments"
				(at 50.8 -12.7 0)
				(effects
					(font
						(size 1.27 1.27)
						(thickness 0.15)
					)
					(justify left bottom)
					(hide yes)
				)
			)
			(property "Author" "Antmicro"
				(at 50.8 -15.24 0)
				(effects
					(font
						(size 1.27 1.27)
						(thickness 0.15)
					)
					(justify left bottom)
					(hide yes)
				)
			)
			(property "License" "Apache-2.0"
				(at 50.8 -17.78 0)
				(effects
					(font
						(size 1.27 1.27)
						(thickness 0.15)
					)
					(justify left bottom)
					(hide yes)
				)
			)
			(property "ki_keywords" "SMT, IC, HDMI"
				(at 0 0 0)
				(effects
					(font
						(size 1.27 1.27)
					)
					(hide yes)
				)
			)
			(symbol "SN65DP159RGZR_1_1"
				(rectangle
					(start 2.54 2.54)
					(end 25.4 -77.47)
					(stroke
						(width 0.254)
						(type default)
					)
					(fill
						(type background)
					)
				)
				(pin power_in line
					(at 0 0 0)
					(length 2.54)
					(name "VCC"
						(effects
							(font
								(size 1.27 1.27)
							)
						)
					)
					(number "13"
						(effects
							(font
								(size 1.27 1.27)
							)
						)
					)
				)
				(pin passive line
					(at 0 0 0)
					(length 2.54)
					(hide yes)
					(name "VCC"
						(effects
							(font
								(size 1.27 1.27)
							)
						)
					)
					(number "43"
						(effects
							(font
								(size 1.27 1.27)
							)
						)
					)
				)
				(pin power_in line
					(at 0 -2.54 0)
					(length 2.54)
					(name "VDD"
						(effects
							(font
								(size 1.27 1.27)
							)
						)
					)
					(number "14"
						(effects
							(font
								(size 1.27 1.27)
							)
						)
					)
				)
				(pin passive line
					(at 0 -2.54 0)
					(length 2.54)
					(hide yes)
					(name "VDD"
						(effects
							(font
								(size 1.27 1.27)
							)
						)
					)
					(number "23"
						(effects
							(font
								(size 1.27 1.27)
							)
						)
					)
				)
				(pin passive line
					(at 0 -2.54 0)
					(length 2.54)
					(hide yes)
					(name "VDD"
						(effects
							(font
								(size 1.27 1.27)
							)
						)
					)
					(number "24"
						(effects
							(font
								(size 1.27 1.27)
							)
						)
					)
				)
				(pin passive line
					(at 0 -2.54 0)
					(length 2.54)
					(hide yes)
					(name "VDD"
						(effects
							(font
								(size 1.27 1.27)
							)
						)
					)
					(number "37"
						(effects
							(font
								(size 1.27 1.27)
							)
						)
					)
				)
				(pin passive line
					(at 0 -2.54 0)
					(length 2.54)
					(hide yes)
					(name "VDD"
						(effects
							(font
								(size 1.27 1.27)
							)
						)
					)
					(number "48"
						(effects
							(font
								(size 1.27 1.27)
							)
						)
					)
				)
				(pin input line
					(at 0 -6.35 0)
					(length 2.54)
					(name "IN_D0_P"
						(effects
							(font
								(size 1.27 1.27)
							)
						)
					)
					(number "8"
						(effects
							(font
								(size 1.27 1.27)
							)
						)
					)
				)
				(pin input line
					(at 0 -8.89 0)
					(length 2.54)
					(name "IN_D0_N"
						(effects
							(font
								(size 1.27 1.27)
							)
						)
					)
					(number "9"
						(effects
							(font
								(size 1.27 1.27)
							)
						)
					)
				)
				(pin input line
					(at 0 -11.43 0)
					(length 2.54)
					(name "IN_D1_P"
						(effects
							(font
								(size 1.27 1.27)
							)
						)
					)
					(number "5"
						(effects
							(font
								(size 1.27 1.27)
							)
						)
					)
				)
				(pin input line
					(at 0 -13.97 0)
					(length 2.54)
					(name "IN_D1_N"
						(effects
							(font
								(size 1.27 1.27)
							)
						)
					)
					(number "6"
						(effects
							(font
								(size 1.27 1.27)
							)
						)
					)
				)
				(pin input line
					(at 0 -16.51 0)
					(length 2.54)
					(name "IN_D2_P"
						(effects
							(font
								(size 1.27 1.27)
							)
						)
					)
					(number "2"
						(effects
							(font
								(size 1.27 1.27)
							)
						)
					)
				)
				(pin input line
					(at 0 -19.05 0)
					(length 2.54)
					(name "IN_D2_N"
						(effects
							(font
								(size 1.27 1.27)
							)
						)
					)
					(number "3"
						(effects
							(font
								(size 1.27 1.27)
							)
						)
					)
				)
				(pin input line
					(at 0 -21.59 0)
					(length 2.54)
					(name "IN_CLK_P"
						(effects
							(font
								(size 1.27 1.27)
							)
						)
					)
					(number "11"
						(effects
							(font
								(size 1.27 1.27)
							)
						)
					)
				)
				(pin input line
					(at 0 -24.13 0)
					(length 2.54)
					(name "IN_CLK_N"
						(effects
							(font
								(size 1.27 1.27)
							)
						)
					)
					(number "12"
						(effects
							(font
								(size 1.27 1.27)
							)
						)
					)
				)
				(pin output line
					(at 0 -27.94 0)
					(length 2.54)
					(name "HPD_SRC"
						(effects
							(font
								(size 1.27 1.27)
							)
						)
					)
					(number "4"
						(effects
							(font
								(size 1.27 1.27)
							)
						)
					)
				)
				(pin bidirectional line
					(at 0 -30.48 0)
					(length 2.54)
					(name "SDA_SRC"
						(effects
							(font
								(size 1.27 1.27)
							)
						)
					)
					(number "47"
						(effects
							(font
								(size 1.27 1.27)
							)
						)
					)
				)
				(pin bidirectional line
					(at 0 -33.02 0)
					(length 2.54)
					(name "SCL_SRC"
						(effects
							(font
								(size 1.27 1.27)
							)
						)
					)
					(number "46"
						(effects
							(font
								(size 1.27 1.27)
							)
						)
					)
				)
				(pin bidirectional line
					(at 0 -36.83 0)
					(length 2.54)
					(name "SDA_CTL"
						(effects
							(font
								(size 1.27 1.27)
							)
						)
					)
					(number "15"
						(effects
							(font
								(size 1.27 1.27)
							)
						)
					)
				)
				(pin bidirectional line
					(at 0 -39.37 0)
					(length 2.54)
					(name "SCL_CTL"
						(effects
							(font
								(size 1.27 1.27)
							)
						)
					)
					(number "16"
						(effects
							(font
								(size 1.27 1.27)
							)
						)
					)
				)
				(pin bidirectional line
					(at 0 -43.18 0)
					(length 2.54)
					(name "AUX_SRC_P"
						(effects
							(font
								(size 1.27 1.27)
							)
						)
					)
					(number "45"
						(effects
							(font
								(size 1.27 1.27)
							)
						)
					)
				)
				(pin bidirectional line
					(at 0 -45.72 0)
					(length 2.54)
					(name "AUX_SRC_N"
						(effects
							(font
								(size 1.27 1.27)
							)
						)
					)
					(number "44"
						(effects
							(font
								(size 1.27 1.27)
							)
						)
					)
				)
				(pin input line
					(at 0 -49.53 0)
					(length 2.54)
					(name "SWAP/POL"
						(effects
							(font
								(size 1.27 1.27)
							)
						)
					)
					(number "1"
						(effects
							(font
								(size 1.27 1.27)
							)
						)
					)
				)
				(pin input line
					(at 0 -52.07 0)
					(length 2.54)
					(name "I2C_EN/PIN"
						(effects
							(font
								(size 1.27 1.27)
							)
						)
					)
					(number "10"
						(effects
							(font
								(size 1.27 1.27)
							)
						)
					)
				)
				(pin input line
					(at 0 -54.61 0)
					(length 2.54)
					(name "PRE_SEL"
						(effects
							(font
								(size 1.27 1.27)
							)
						)
					)
					(number "20"
						(effects
							(font
								(size 1.27 1.27)
							)
						)
					)
				)
				(pin input line
					(at 0 -57.15 0)
					(length 2.54)
					(name "EQ_SEL/A0"
						(effects
							(font
								(size 1.27 1.27)
							)
						)
					)
					(number "21"
						(effects
							(font
								(size 1.27 1.27)
							)
						)
					)
				)
				(pin input line
					(at 0 -59.69 0)
					(length 2.54)
					(name "~{HDMI_SEL}/A1"
						(effects
							(font
								(size 1.27 1.27)
							)
						)
					)
					(number "27"
						(effects
							(font
								(size 1.27 1.27)
							)
						)
					)
				)
				(pin input line
					(at 0 -62.23 0)
					(length 2.54)
					(name "TX_TERM_CTL"
						(effects
							(font
								(size 1.27 1.27)
							)
						)
					)
					(number "36"
						(effects
							(font
								(size 1.27 1.27)
							)
						)
					)
				)
				(pin input line
					(at 0 -64.77 0)
					(length 2.54)
					(name "SLEW_CTL"
						(effects
							(font
								(size 1.27 1.27)
							)
						)
					)
					(number "40"
						(effects
							(font
								(size 1.27 1.27)
							)
						)
					)
				)
				(pin input line
					(at 0 -68.58 0)
					(length 2.54)
					(name "OE"
						(effects
							(font
								(size 1.27 1.27)
							)
						)
					)
					(number "42"
						(effects
							(font
								(size 1.27 1.27)
							)
						)
					)
				)
				(pin input line
					(at 0 -71.12 0)
					(length 2.54)
					(name "VSADJ"
						(effects
							(font
								(size 1.27 1.27)
							)
						)
					)
					(number "22"
						(effects
							(font
								(size 1.27 1.27)
							)
						)
					)
				)
				(pin passive line
					(at 0 -74.93 0)
					(length 2.54)
					(hide yes)
					(name "GND"
						(effects
							(font
								(size 1.27 1.27)
							)
						)
					)
					(number "19"
						(effects
							(font
								(size 1.27 1.27)
							)
						)
					)
				)
				(pin passive line
					(at 0 -74.93 0)
					(length 2.54)
					(hide yes)
					(name "GND"
						(effects
							(font
								(size 1.27 1.27)
							)
						)
					)
					(number "30"
						(effects
							(font
								(size 1.27 1.27)
							)
						)
					)
				)
				(pin passive line
					(at 0 -74.93 0)
					(length 2.54)
					(hide yes)
					(name "GND"
						(effects
							(font
								(size 1.27 1.27)
							)
						)
					)
					(number "41"
						(effects
							(font
								(size 1.27 1.27)
							)
						)
					)
				)
				(pin passive line
					(at 0 -74.93 0)
					(length 2.54)
					(hide yes)
					(name "GND"
						(effects
							(font
								(size 1.27 1.27)
							)
						)
					)
					(number "49"
						(effects
							(font
								(size 1.27 1.27)
							)
						)
					)
				)
				(pin power_in line
					(at 0 -74.93 0)
					(length 2.54)
					(name "GND"
						(effects
							(font
								(size 1.27 1.27)
							)
						)
					)
					(number "7"
						(effects
							(font
								(size 1.27 1.27)
							)
						)
					)
				)
				(pin no_connect line
					(at 25.4 -40.64 180)
					(length 2.54)
					(hide yes)
					(name "NC"
						(effects
							(font
								(size 1.27 1.27)
							)
						)
					)
					(number "17"
						(effects
							(font
								(size 1.27 1.27)
							)
						)
					)
				)
				(pin output line
					(at 27.94 -6.35 180)
					(length 2.54)
					(name "OUT_D0_P"
						(effects
							(font
								(size 1.27 1.27)
							)
						)
					)
					(number "29"
						(effects
							(font
								(size 1.27 1.27)
							)
						)
					)
				)
				(pin output line
					(at 27.94 -8.89 180)
					(length 2.54)
					(name "OUT_D0_N"
						(effects
							(font
								(size 1.27 1.27)
							)
						)
					)
					(number "28"
						(effects
							(font
								(size 1.27 1.27)
							)
						)
					)
				)
				(pin output line
					(at 27.94 -11.43 180)
					(length 2.54)
					(name "OUT_D1_P"
						(effects
							(font
								(size 1.27 1.27)
							)
						)
					)
					(number "32"
						(effects
							(font
								(size 1.27 1.27)
							)
						)
					)
				)
				(pin output line
					(at 27.94 -13.97 180)
					(length 2.54)
					(name "OUT_D1_N"
						(effects
							(font
								(size 1.27 1.27)
							)
						)
					)
					(number "31"
						(effects
							(font
								(size 1.27 1.27)
							)
						)
					)
				)
				(pin output line
					(at 27.94 -16.51 180)
					(length 2.54)
					(name "OUT_D2_P"
						(effects
							(font
								(size 1.27 1.27)
							)
						)
					)
					(number "35"
						(effects
							(font
								(size 1.27 1.27)
							)
						)
					)
				)
				(pin output line
					(at 27.94 -19.05 180)
					(length 2.54)
					(name "OUT_D2_N"
						(effects
							(font
								(size 1.27 1.27)
							)
						)
					)
					(number "34"
						(effects
							(font
								(size 1.27 1.27)
							)
						)
					)
				)
				(pin output line
					(at 27.94 -21.59 180)
					(length 2.54)
					(name "OUT_CLK_P"
						(effects
							(font
								(size 1.27 1.27)
							)
						)
					)
					(number "26"
						(effects
							(font
								(size 1.27 1.27)
							)
						)
					)
				)
				(pin output line
					(at 27.94 -24.13 180)
					(length 2.54)
					(name "OUT_CLK_N"
						(effects
							(font
								(size 1.27 1.27)
							)
						)
					)
					(number "25"
						(effects
							(font
								(size 1.27 1.27)
							)
						)
					)
				)
				(pin input line
					(at 27.94 -27.94 180)
					(length 2.54)
					(name "HPD_SNK"
						(effects
							(font
								(size 1.27 1.27)
							)
						)
					)
					(number "33"
						(effects
							(font
								(size 1.27 1.27)
							)
						)
					)
				)
				(pin bidirectional line
					(at 27.94 -30.48 180)
					(length 2.54)
					(name "SDA_SNK"
						(effects
							(font
								(size 1.27 1.27)
							)
						)
					)
					(number "39"
						(effects
							(font
								(size 1.27 1.27)
							)
						)
					)
				)
				(pin bidirectional line
					(at 27.94 -33.02 180)
					(length 2.54)
					(name "SCL_SNK"
						(effects
							(font
								(size 1.27 1.27)
							)
						)
					)
					(number "38"
						(effects
							(font
								(size 1.27 1.27)
							)
						)
					)
				)
				(pin output line
					(at 27.94 -36.83 180)
					(length 2.54)
					(name "CEC_EN"
						(effects
							(font
								(size 1.27 1.27)
							)
						)
					)
					(number "18"
						(effects
							(font
								(size 1.27 1.27)
							)
						)
					)
				)
			)
		)
	(symbol "antmicroLEDIndicationDiscrete:LED_G_0402_VLMTG1500-GS08"
			(pin_numbers
				(hide yes)
			)
			(pin_names
				(hide yes)
			)
			(exclude_from_sim no)
			(in_bom yes)
			(on_board yes)
			(property "Reference" "D"
				(at 22.86 -2.54 0)
				(effects
					(font
						(size 1.27 1.27)
						(thickness 0.15)
					)
					(justify left bottom)
				)
			)
			(property "Value" "LED_G_0402_VLMTG1500-GS08"
				(at 22.86 -7.62 0)
				(effects
					(font
						(size 1.27 1.27)
						(thickness 0.15)
					)
					(justify left bottom)
					(hide yes)
				)
			)
			(property "Footprint" "antmicro-footprints:LED_0402_1005Metric_G"
				(at 22.86 -10.16 0)
				(effects
					(font
						(size 1.27 1.27)
						(thickness 0.15)
					)
					(justify left bottom)
					(hide yes)
				)
			)
			(property "Datasheet" "https://www.vishay.com/docs/82554/vlmo1500.pdf"
				(at 22.86 -12.7 0)
				(effects
					(font
						(size 1.27 1.27)
						(thickness 0.15)
					)
					(justify left bottom)
					(hide yes)
				)
			)
			(property "Description" "LED, Green, SMD, 1005, 5 mA, 3.1 V, 535 nm"
				(at 0 0 0)
				(effects
					(font
						(size 1.27 1.27)
					)
					(hide yes)
				)
			)
			(property "MPN" "VLMTG1500-GS08"
				(at 22.86 -15.24 0)
				(effects
					(font
						(size 1.27 1.27)
						(thickness 0.15)
					)
					(justify left bottom)
					(hide yes)
				)
			)
			(property "Manufacturer" "Vishay"
				(at 22.86 -17.78 0)
				(effects
					(font
						(size 1.27 1.27)
						(thickness 0.15)
					)
					(justify left bottom)
					(hide yes)
				)
			)
			(property "Color" "Green"
				(at 22.86 -5.08 0)
				(effects
					(font
						(size 1.27 1.27)
					)
					(justify left bottom)
				)
			)
			(property "Author" "Antmicro"
				(at 22.86 -20.32 0)
				(effects
					(font
						(size 1.27 1.27)
						(thickness 0.15)
					)
					(justify left bottom)
					(hide yes)
				)
			)
			(property "License" "Apache-2.0"
				(at 22.86 -22.86 0)
				(effects
					(font
						(size 1.27 1.27)
						(thickness 0.15)
					)
					(justify left bottom)
					(hide yes)
				)
			)
			(property "ki_keywords" "SMT, DIODE, SEMICONDUCTOR, LED"
				(at 0 0 0)
				(effects
					(font
						(size 1.27 1.27)
					)
					(hide yes)
				)
			)
			(symbol "LED_G_0402_VLMTG1500-GS08_0_1"
				(polyline
					(pts
						(xy 1.905 0) (xy 0.635 0)
					)
					(stroke
						(width 0)
						(type default)
					)
					(fill
						(type none)
					)
				)
				(polyline
					(pts
						(xy 4.445 0) (xy 3.175 0)
					)
					(stroke
						(width 0)
						(type default)
					)
					(fill
						(type none)
					)
				)
			)
			(symbol "LED_G_0402_VLMTG1500-GS08_1_1"
				(polyline
					(pts
						(xy 1.143 2.286) (xy 1.143 1.778) (xy 1.143 2.286) (xy 1.651 2.286) (xy 1.143 2.286) (xy 2.159 1.27)
					)
					(stroke
						(width 0.254)
						(type default)
					)
					(fill
						(type none)
					)
				)
				(polyline
					(pts
						(xy 1.778 1.016) (xy 1.778 -1.016)
					)
					(stroke
						(width 0.254)
						(type default)
					)
					(fill
						(type none)
					)
				)
				(polyline
					(pts
						(xy 2.159 2.54) (xy 2.159 2.032) (xy 2.159 2.54) (xy 2.667 2.54) (xy 2.159 2.54) (xy 3.048 1.651)
					)
					(stroke
						(width 0.254)
						(type default)
					)
					(fill
						(type none)
					)
				)
				(polyline
					(pts
						(xy 3.302 1.016) (xy 3.302 -1.016) (xy 1.778 0) (xy 3.302 1.016)
					)
					(stroke
						(width 0.254)
						(type default)
					)
					(fill
						(type outline)
					)
				)
				(pin passive line
					(at 0 0 0)
					(length 0.635)
					(name "C"
						(effects
							(font
								(size 1.27 1.27)
							)
						)
					)
					(number "1"
						(effects
							(font
								(size 1.27 1.27)
							)
						)
					)
				)
				(pin passive line
					(at 5.08 0 180)
					(length 0.635)
					(name "A"
						(effects
							(font
								(size 1.27 1.27)
							)
						)
					)
					(number "2"
						(effects
							(font
								(size 1.27 1.27)
							)
						)
					)
				)
			)
		)
	(symbol "antmicroLEDIndicationDiscrete:LED_G_0603_KP-1608CGCK"
			(pin_numbers
				(hide yes)
			)
			(pin_names
				(hide yes)
			)
			(exclude_from_sim no)
			(in_bom yes)
			(on_board yes)
			(property "Reference" "D"
				(at 22.86 -2.54 0)
				(effects
					(font
						(size 1.27 1.27)
						(thickness 0.15)
					)
					(justify left bottom)
				)
			)
			(property "Value" "LED_G_0603_KP-1608CGCK"
				(at 22.86 -7.62 0)
				(effects
					(font
						(size 1.27 1.27)
						(thickness 0.15)
					)
					(justify left bottom)
					(hide yes)
				)
			)
			(property "Footprint" "antmicro-footprints:LED_0603_1608Metric_G"
				(at 22.86 -10.16 0)
				(effects
					(font
						(size 1.27 1.27)
						(thickness 0.15)
					)
					(justify left bottom)
					(hide yes)
				)
			)
			(property "Datasheet" "http://www.kingbright.com/attachments/file/psearch//000/00/00/KP-1608CGCK(Ver.23B).pdf"
				(at 22.86 -12.7 0)
				(effects
					(font
						(size 1.27 1.27)
						(thickness 0.15)
					)
					(justify left bottom)
					(hide yes)
				)
			)
			(property "Description" "LED, Green, SMD, 0603, 20 mA, 2.1 V, 570 nm"
				(at 0 0 0)
				(effects
					(font
						(size 1.27 1.27)
					)
					(hide yes)
				)
			)
			(property "MPN" "KP-1608CGCK"
				(at 22.86 -15.24 0)
				(effects
					(font
						(size 1.27 1.27)
						(thickness 0.15)
					)
					(justify left bottom)
					(hide yes)
				)
			)
			(property "Manufacturer" "Kingbright"
				(at 22.86 -17.78 0)
				(effects
					(font
						(size 1.27 1.27)
						(thickness 0.15)
					)
					(justify left bottom)
					(hide yes)
				)
			)
			(property "Color" "Green"
				(at 22.86 -5.08 0)
				(effects
					(font
						(size 1.27 1.27)
					)
					(justify left bottom)
				)
			)
			(property "Author" "Antmicro"
				(at 22.86 -20.32 0)
				(effects
					(font
						(size 1.27 1.27)
						(thickness 0.15)
					)
					(justify left bottom)
					(hide yes)
				)
			)
			(property "License" "Apache-2.0"
				(at 22.86 -22.86 0)
				(effects
					(font
						(size 1.27 1.27)
						(thickness 0.15)
					)
					(justify left bottom)
					(hide yes)
				)
			)
			(property "ki_keywords" "SMT, DIODE, SEMICONDUCTOR, LED"
				(at 0 0 0)
				(effects
					(font
						(size 1.27 1.27)
					)
					(hide yes)
				)
			)
			(symbol "LED_G_0603_KP-1608CGCK_0_1"
				(polyline
					(pts
						(xy 1.905 0) (xy 0.635 0)
					)
					(stroke
						(width 0)
						(type default)
					)
					(fill
						(type none)
					)
				)
				(polyline
					(pts
						(xy 4.445 0) (xy 3.175 0)
					)
					(stroke
						(width 0)
						(type default)
					)
					(fill
						(type none)
					)
				)
			)
			(symbol "LED_G_0603_KP-1608CGCK_1_1"
				(polyline
					(pts
						(xy 1.143 2.286) (xy 1.143 1.778) (xy 1.143 2.286) (xy 1.651 2.286) (xy 1.143 2.286) (xy 2.159 1.27)
					)
					(stroke
						(width 0.254)
						(type default)
					)
					(fill
						(type none)
					)
				)
				(polyline
					(pts
						(xy 1.778 1.016) (xy 1.778 -1.016)
					)
					(stroke
						(width 0.254)
						(type default)
					)
					(fill
						(type none)
					)
				)
				(polyline
					(pts
						(xy 2.159 2.54) (xy 2.159 2.032) (xy 2.159 2.54) (xy 2.667 2.54) (xy 2.159 2.54) (xy 3.048 1.651)
					)
					(stroke
						(width 0.254)
						(type default)
					)
					(fill
						(type none)
					)
				)
				(polyline
					(pts
						(xy 3.302 1.016) (xy 3.302 -1.016) (xy 1.778 0) (xy 3.302 1.016)
					)
					(stroke
						(width 0.254)
						(type default)
					)
					(fill
						(type outline)
					)
				)
				(pin passive line
					(at 0 0 0)
					(length 0.635)
					(name "C"
						(effects
							(font
								(size 1.27 1.27)
							)
						)
					)
					(number "1"
						(effects
							(font
								(size 1.27 1.27)
							)
						)
					)
				)
				(pin passive line
					(at 5.08 0 180)
					(length 0.635)
					(name "A"
						(effects
							(font
								(size 1.27 1.27)
							)
						)
					)
					(number "2"
						(effects
							(font
								(size 1.27 1.27)
							)
						)
					)
				)
			)
		)
	(symbol "antmicroLogicTranslatorsLevelShifters:NVT4858_XQFN"
			(exclude_from_sim no)
			(in_bom yes)
			(on_board yes)
			(property "Reference" "U"
				(at 53.34 -2.54 0)
				(effects
					(font
						(size 1.27 1.27)
						(thickness 0.15)
					)
					(justify left bottom)
				)
			)
			(property "Value" "NVT4858_XQFN"
				(at 53.34 -5.08 0)
				(effects
					(font
						(size 1.27 1.27)
						(thickness 0.15)
					)
					(justify left bottom)
					(hide yes)
				)
			)
			(property "Footprint" "antmicro-footprints:SOT1161-2"
				(at 53.34 -7.62 0)
				(effects
					(font
						(size 1.27 1.27)
						(thickness 0.15)
					)
					(justify left bottom)
					(hide yes)
				)
			)
			(property "Datasheet" "https://www.nxp.com/docs/en/data-sheet/NVT4858DS.pdf"
				(at 53.34 -10.16 0)
				(effects
					(font
						(size 1.27 1.27)
						(thickness 0.15)
					)
					(justify left bottom)
					(hide yes)
				)
			)
			(property "Description" "Level Translator, 4 Input, 1.08 V to 1.98 V, xQFN-16"
				(at 0 0 0)
				(effects
					(font
						(size 1.27 1.27)
					)
					(hide yes)
				)
			)
			(property "Manufacturer" "NXP"
				(at 53.34 -12.7 0)
				(effects
					(font
						(size 1.27 1.27)
						(thickness 0.15)
					)
					(justify left bottom)
					(hide yes)
				)
			)
			(property "MPN" "NVT4858HKZ"
				(at 53.34 -15.24 0)
				(effects
					(font
						(size 1.27 1.27)
						(thickness 0.15)
					)
					(justify left bottom)
				)
			)
			(property "Author" "Antmicro"
				(at 53.34 -17.78 0)
				(effects
					(font
						(size 1.27 1.27)
						(thickness 0.15)
					)
					(justify left bottom)
					(hide yes)
				)
			)
			(property "License" "Apache-2.0"
				(at 53.34 -20.32 0)
				(effects
					(font
						(size 1.27 1.27)
						(thickness 0.15)
					)
					(justify left bottom)
					(hide yes)
				)
			)
			(property "ki_keywords" "SMT, LEVEL-SHIFTER, IC, LOGIC"
				(at 0 0 0)
				(effects
					(font
						(size 1.27 1.27)
					)
					(hide yes)
				)
			)
			(symbol "NVT4858_XQFN_1_1"
				(rectangle
					(start 2.54 2.54)
					(end 16.51 -27.94)
					(stroke
						(width 0.254)
						(type default)
					)
					(fill
						(type background)
					)
				)
				(pin power_in line
					(at 0 0 0)
					(length 2.54)
					(name "VCC_{A}"
						(effects
							(font
								(size 1.27 1.27)
							)
						)
					)
					(number "15"
						(effects
							(font
								(size 1.27 1.27)
							)
						)
					)
				)
				(pin bidirectional line
					(at 0 -5.08 0)
					(length 2.54)
					(name "CMD_{A}"
						(effects
							(font
								(size 1.27 1.27)
							)
						)
					)
					(number "16"
						(effects
							(font
								(size 1.27 1.27)
							)
						)
					)
				)
				(pin input line
					(at 0 -7.62 0)
					(length 2.54)
					(name "CLK_{A}"
						(effects
							(font
								(size 1.27 1.27)
							)
						)
					)
					(number "5"
						(effects
							(font
								(size 1.27 1.27)
							)
						)
					)
				)
				(pin bidirectional line
					(at 0 -12.7 0)
					(length 2.54)
					(name "DAT0_{A}"
						(effects
							(font
								(size 1.27 1.27)
							)
						)
					)
					(number "3"
						(effects
							(font
								(size 1.27 1.27)
							)
						)
					)
				)
				(pin bidirectional line
					(at 0 -15.24 0)
					(length 2.54)
					(name "DAT1_{A}"
						(effects
							(font
								(size 1.27 1.27)
							)
						)
					)
					(number "4"
						(effects
							(font
								(size 1.27 1.27)
							)
						)
					)
				)
				(pin bidirectional line
					(at 0 -17.78 0)
					(length 2.54)
					(name "DAT2_{A}"
						(effects
							(font
								(size 1.27 1.27)
							)
						)
					)
					(number "1"
						(effects
							(font
								(size 1.27 1.27)
							)
						)
					)
				)
				(pin bidirectional line
					(at 0 -20.32 0)
					(length 2.54)
					(name "DAT3_{A}"
						(effects
							(font
								(size 1.27 1.27)
							)
						)
					)
					(number "2"
						(effects
							(font
								(size 1.27 1.27)
							)
						)
					)
				)
				(pin output line
					(at 0 -25.4 0)
					(length 2.54)
					(name "CLK_{FB}"
						(effects
							(font
								(size 1.27 1.27)
							)
						)
					)
					(number "6"
						(effects
							(font
								(size 1.27 1.27)
							)
						)
					)
				)
				(pin power_in line
					(at 19.05 0 180)
					(length 2.54)
					(name "VCC_{B}"
						(effects
							(font
								(size 1.27 1.27)
							)
						)
					)
					(number "14"
						(effects
							(font
								(size 1.27 1.27)
							)
						)
					)
				)
				(pin bidirectional line
					(at 19.05 -5.08 180)
					(length 2.54)
					(name "CMD_{B}"
						(effects
							(font
								(size 1.27 1.27)
							)
						)
					)
					(number "13"
						(effects
							(font
								(size 1.27 1.27)
							)
						)
					)
				)
				(pin output line
					(at 19.05 -7.62 180)
					(length 2.54)
					(name "CLK_{B}"
						(effects
							(font
								(size 1.27 1.27)
							)
						)
					)
					(number "8"
						(effects
							(font
								(size 1.27 1.27)
							)
						)
					)
				)
				(pin bidirectional line
					(at 19.05 -12.7 180)
					(length 2.54)
					(name "DAT0_{B}"
						(effects
							(font
								(size 1.27 1.27)
							)
						)
					)
					(number "10"
						(effects
							(font
								(size 1.27 1.27)
							)
						)
					)
				)
				(pin bidirectional line
					(at 19.05 -15.24 180)
					(length 2.54)
					(name "DAT1_{B}"
						(effects
							(font
								(size 1.27 1.27)
							)
						)
					)
					(number "9"
						(effects
							(font
								(size 1.27 1.27)
							)
						)
					)
				)
				(pin bidirectional line
					(at 19.05 -17.78 180)
					(length 2.54)
					(name "DAT2_{B}"
						(effects
							(font
								(size 1.27 1.27)
							)
						)
					)
					(number "12"
						(effects
							(font
								(size 1.27 1.27)
							)
						)
					)
				)
				(pin bidirectional line
					(at 19.05 -20.32 180)
					(length 2.54)
					(name "DAT3_{B}"
						(effects
							(font
								(size 1.27 1.27)
							)
						)
					)
					(number "11"
						(effects
							(font
								(size 1.27 1.27)
							)
						)
					)
				)
				(pin power_in line
					(at 19.05 -25.4 180)
					(length 2.54)
					(name "GND"
						(effects
							(font
								(size 1.27 1.27)
							)
						)
					)
					(number "7"
						(effects
							(font
								(size 1.27 1.27)
							)
						)
					)
				)
			)
		)
	(symbol "antmicroLogicTranslatorsLevelShifters:PCA9517ADP"
			(exclude_from_sim no)
			(in_bom yes)
			(on_board yes)
			(property "Reference" "U"
				(at 33.02 -2.54 0)
				(effects
					(font
						(size 1.27 1.27)
						(thickness 0.15)
					)
					(justify left bottom)
				)
			)
			(property "Value" "PCA9517ADP"
				(at 33.02 -5.08 0)
				(effects
					(font
						(size 1.27 1.27)
						(thickness 0.15)
					)
					(justify left bottom)
					(hide yes)
				)
			)
			(property "Footprint" "antmicro-footprints:TSSOP-8_3x3mm_P0.65mm"
				(at 33.02 -7.62 0)
				(effects
					(font
						(size 1.27 1.27)
						(thickness 0.15)
					)
					(justify left bottom)
					(hide yes)
				)
			)
			(property "Datasheet" "https://www.nxp.com/docs/en/data-sheet/PCA9517A.pdf"
				(at 33.02 -10.16 0)
				(effects
					(font
						(size 1.27 1.27)
						(thickness 0.15)
					)
					(justify left bottom)
					(hide yes)
				)
			)
			(property "Description" "Bus Repeater, 0.9 V to 5.5 V, TSSOP-8"
				(at 0 0 0)
				(effects
					(font
						(size 1.27 1.27)
					)
					(hide yes)
				)
			)
			(property "MPN" "PCA9517ADP,118"
				(at 33.02 -12.7 0)
				(effects
					(font
						(size 1.27 1.27)
						(thickness 0.15)
					)
					(justify left bottom)
				)
			)
			(property "Manufacturer" "NXP"
				(at 33.02 -15.24 0)
				(effects
					(font
						(size 1.27 1.27)
						(thickness 0.15)
					)
					(justify left bottom)
					(hide yes)
				)
			)
			(property "Author" "Antmicro"
				(at 33.02 -17.78 0)
				(effects
					(font
						(size 1.27 1.27)
						(thickness 0.15)
					)
					(justify left bottom)
					(hide yes)
				)
			)
			(property "License" "Apache-2.0"
				(at 33.02 -20.32 0)
				(effects
					(font
						(size 1.27 1.27)
						(thickness 0.15)
					)
					(justify left bottom)
					(hide yes)
				)
			)
			(property "ki_keywords" "SMT, LEVEL-SHIFTER, IC, I2C"
				(at 0 0 0)
				(effects
					(font
						(size 1.27 1.27)
					)
					(hide yes)
				)
			)
			(symbol "PCA9517ADP_1_1"
				(rectangle
					(start 15.24 2.54)
					(end 2.54 -10.16)
					(stroke
						(width 0.254)
						(type default)
					)
					(fill
						(type background)
					)
				)
				(pin power_in line
					(at 0 0 0)
					(length 2.54)
					(name "V_{CC(A)}"
						(effects
							(font
								(size 1.27 1.27)
							)
						)
					)
					(number "1"
						(effects
							(font
								(size 1.27 1.27)
							)
						)
					)
				)
				(pin input line
					(at 0 -2.54 0)
					(length 2.54)
					(name "SCLA"
						(effects
							(font
								(size 1.27 1.27)
							)
						)
					)
					(number "2"
						(effects
							(font
								(size 1.27 1.27)
							)
						)
					)
				)
				(pin bidirectional line
					(at 0 -5.08 0)
					(length 2.54)
					(name "SDAA"
						(effects
							(font
								(size 1.27 1.27)
							)
						)
					)
					(number "3"
						(effects
							(font
								(size 1.27 1.27)
							)
						)
					)
				)
				(pin power_in line
					(at 0 -7.62 0)
					(length 2.54)
					(name "GND"
						(effects
							(font
								(size 1.27 1.27)
							)
						)
					)
					(number "4"
						(effects
							(font
								(size 1.27 1.27)
							)
						)
					)
				)
				(pin power_in line
					(at 17.78 0 180)
					(length 2.54)
					(name "V_{CC(B)}"
						(effects
							(font
								(size 1.27 1.27)
							)
						)
					)
					(number "8"
						(effects
							(font
								(size 1.27 1.27)
							)
						)
					)
				)
				(pin input line
					(at 17.78 -2.54 180)
					(length 2.54)
					(name "SCLB"
						(effects
							(font
								(size 1.27 1.27)
							)
						)
					)
					(number "7"
						(effects
							(font
								(size 1.27 1.27)
							)
						)
					)
				)
				(pin bidirectional line
					(at 17.78 -5.08 180)
					(length 2.54)
					(name "SDAB"
						(effects
							(font
								(size 1.27 1.27)
							)
						)
					)
					(number "6"
						(effects
							(font
								(size 1.27 1.27)
							)
						)
					)
				)
				(pin input line
					(at 17.78 -7.62 180)
					(length 2.54)
					(name "EN"
						(effects
							(font
								(size 1.27 1.27)
							)
						)
					)
					(number "5"
						(effects
							(font
								(size 1.27 1.27)
							)
						)
					)
				)
			)
		)
	(symbol "antmicroLogicTranslatorsLevelShifters:TCA39306_VSSOP"
			(exclude_from_sim no)
			(in_bom yes)
			(on_board yes)
			(property "Reference" "U"
				(at 31.75 0 0)
				(effects
					(font
						(size 1.27 1.27)
						(thickness 0.15)
					)
					(justify left bottom)
				)
			)
			(property "Value" "TCA39306_VSSOP"
				(at 31.75 -2.54 0)
				(effects
					(font
						(size 1.27 1.27)
						(thickness 0.15)
					)
					(justify left bottom)
					(hide yes)
				)
			)
			(property "Footprint" "antmicro-footprints:VSSOP-8_2.3x2mm_P0.5mm"
				(at 31.75 -5.08 0)
				(effects
					(font
						(size 1.27 1.27)
						(thickness 0.15)
					)
					(justify left bottom)
					(hide yes)
				)
			)
			(property "Datasheet" "https://www.ti.com/lit/ds/symlink/tca39306.pdf?ts=1630428611843&ref_url=https%253A%252F%252Fwww.ti.com%252Fproduct%252FTCA39306"
				(at 31.75 -7.62 0)
				(effects
					(font
						(size 1.27 1.27)
						(thickness 0.15)
					)
					(justify left bottom)
					(hide yes)
				)
			)
			(property "Description" "Logic translator/level shifter"
				(at 0 0 0)
				(effects
					(font
						(size 1.27 1.27)
					)
					(hide yes)
				)
			)
			(property "MPN" "TCA39306DCUR"
				(at 31.75 -10.16 0)
				(effects
					(font
						(size 1.27 1.27)
						(thickness 0.15)
					)
					(justify left bottom)
				)
			)
			(property "Manufacturer" "Texas Instruments"
				(at 31.75 -12.7 0)
				(effects
					(font
						(size 1.27 1.27)
						(thickness 0.15)
					)
					(justify left bottom)
					(hide yes)
				)
			)
			(property "Author" "Antmicro"
				(at 31.75 -15.24 0)
				(effects
					(font
						(size 1.27 1.27)
						(thickness 0.15)
					)
					(justify left bottom)
					(hide yes)
				)
			)
			(property "License" "Apache-2.0"
				(at 31.75 -17.78 0)
				(effects
					(font
						(size 1.27 1.27)
						(thickness 0.15)
					)
					(justify left bottom)
					(hide yes)
				)
			)
			(property "ki_keywords" "SMT, LOGIC, IC, LEVEL-SHIFTER, VOLTAGE"
				(at 0 0 0)
				(effects
					(font
						(size 1.27 1.27)
					)
					(hide yes)
				)
			)
			(symbol "TCA39306_VSSOP_1_1"
				(rectangle
					(start 2.54 2.54)
					(end 15.24 -12.7)
					(stroke
						(width 0.254)
						(type default)
					)
					(fill
						(type background)
					)
				)
				(pin power_in line
					(at 0 0 0)
					(length 2.54)
					(name "Vref1"
						(effects
							(font
								(size 1.27 1.27)
							)
						)
					)
					(number "2"
						(effects
							(font
								(size 1.27 1.27)
							)
						)
					)
				)
				(pin bidirectional line
					(at 0 -3.81 0)
					(length 2.54)
					(name "SCL1"
						(effects
							(font
								(size 1.27 1.27)
							)
						)
					)
					(number "3"
						(effects
							(font
								(size 1.27 1.27)
							)
						)
					)
				)
				(pin bidirectional line
					(at 0 -6.35 0)
					(length 2.54)
					(name "SDA1"
						(effects
							(font
								(size 1.27 1.27)
							)
						)
					)
					(number "4"
						(effects
							(font
								(size 1.27 1.27)
							)
						)
					)
				)
				(pin power_in line
					(at 0 -10.16 0)
					(length 2.54)
					(name "GND"
						(effects
							(font
								(size 1.27 1.27)
							)
						)
					)
					(number "1"
						(effects
							(font
								(size 1.27 1.27)
							)
						)
					)
				)
				(pin power_in line
					(at 17.78 0 180)
					(length 2.54)
					(name "Vref2"
						(effects
							(font
								(size 1.27 1.27)
							)
						)
					)
					(number "7"
						(effects
							(font
								(size 1.27 1.27)
							)
						)
					)
				)
				(pin bidirectional line
					(at 17.78 -3.81 180)
					(length 2.54)
					(name "SCL2"
						(effects
							(font
								(size 1.27 1.27)
							)
						)
					)
					(number "6"
						(effects
							(font
								(size 1.27 1.27)
							)
						)
					)
				)
				(pin bidirectional line
					(at 17.78 -6.35 180)
					(length 2.54)
					(name "SDA2"
						(effects
							(font
								(size 1.27 1.27)
							)
						)
					)
					(number "5"
						(effects
							(font
								(size 1.27 1.27)
							)
						)
					)
				)
				(pin input line
					(at 17.78 -10.16 180)
					(length 2.54)
					(name "EN"
						(effects
							(font
								(size 1.27 1.27)
							)
						)
					)
					(number "8"
						(effects
							(font
								(size 1.27 1.27)
							)
						)
					)
				)
			)
		)
	(symbol "antmicroLogicTranslatorsLevelShifters:TXS0102DQER"
			(exclude_from_sim no)
			(in_bom yes)
			(on_board yes)
			(property "Reference" "U"
				(at 33.02 -5.08 0)
				(effects
					(font
						(size 1.27 1.27)
						(thickness 0.15)
					)
					(justify left bottom)
				)
			)
			(property "Value" "TXS0102DQER"
				(at 33.02 -7.62 0)
				(effects
					(font
						(size 1.27 1.27)
						(thickness 0.15)
					)
					(justify left bottom)
					(hide yes)
				)
			)
			(property "Footprint" "antmicro-footprints:X2SON8_1.4x1x0.32mm_P0.35mm"
				(at 33.02 -10.16 0)
				(effects
					(font
						(size 1.27 1.27)
						(thickness 0.15)
					)
					(justify left bottom)
					(hide yes)
				)
			)
			(property "Datasheet" "https://www.ti.com/lit/ds/symlink/txs0102.pdf?ts=1637914596981&ref_url=https%253A%252F%252Fwww.ti.com%252Fstore%252Fti%252Fen%252Fp%252Fproduct%252F%253Fp%253DTXS0102DCTR%2526keyMatch%253DTXS0102DCTR%2526tisearch%253Dsearch-everything%2526usecase%253DOPN"
				(at 33.02 -12.7 0)
				(effects
					(font
						(size 1.27 1.27)
						(thickness 0.15)
					)
					(justify left bottom)
					(hide yes)
				)
			)
			(property "Description" "Level shifter"
				(at 0 0 0)
				(effects
					(font
						(size 1.27 1.27)
					)
					(hide yes)
				)
			)
			(property "MPN" "TXS0102DQER"
				(at 33.02 -15.24 0)
				(effects
					(font
						(size 1.27 1.27)
						(thickness 0.15)
					)
					(justify left bottom)
				)
			)
			(property "Manufacturer" "Texas Instruments"
				(at 33.02 -17.78 0)
				(effects
					(font
						(size 1.27 1.27)
						(thickness 0.15)
					)
					(justify left bottom)
					(hide yes)
				)
			)
			(property "Author" "Antmicro"
				(at 33.02 -20.32 0)
				(effects
					(font
						(size 1.27 1.27)
						(thickness 0.15)
					)
					(justify left bottom)
					(hide yes)
				)
			)
			(property "License" "Apache-2.0"
				(at 33.02 -22.86 0)
				(effects
					(font
						(size 1.27 1.27)
						(thickness 0.15)
					)
					(justify left bottom)
					(hide yes)
				)
			)
			(property "ki_keywords" "IC"
				(at 0 0 0)
				(effects
					(font
						(size 1.27 1.27)
					)
					(hide yes)
				)
			)
			(symbol "TXS0102DQER_1_1"
				(rectangle
					(start 2.54 0)
					(end 15.24 -12.7)
					(stroke
						(width 0.254)
						(type default)
					)
					(fill
						(type background)
					)
				)
				(polyline
					(pts
						(xy 5.715 -7.62) (xy 6.985 -7.62)
					)
					(stroke
						(width 0.254)
						(type default)
					)
					(fill
						(type background)
					)
				)
				(polyline
					(pts
						(xy 6.985 -5.08) (xy 5.715 -5.08)
					)
					(stroke
						(width 0.254)
						(type default)
					)
					(fill
						(type background)
					)
				)
				(polyline
					(pts
						(xy 8.255 -4.445) (xy 6.985 -4.445) (xy 6.985 -5.715) (xy 8.255 -5.715)
					)
					(stroke
						(width 0.254)
						(type default)
					)
					(fill
						(type background)
					)
				)
				(polyline
					(pts
						(xy 8.255 -4.445) (xy 9.525 -3.81) (xy 9.525 -5.08) (xy 8.255 -4.445)
					)
					(stroke
						(width 0.254)
						(type default)
					)
					(fill
						(type background)
					)
				)
				(polyline
					(pts
						(xy 8.255 -5.08) (xy 8.255 -6.35) (xy 9.525 -5.715) (xy 8.255 -5.08)
					)
					(stroke
						(width 0.254)
						(type default)
					)
					(fill
						(type background)
					)
				)
				(polyline
					(pts
						(xy 8.255 -6.985) (xy 6.985 -6.985) (xy 6.985 -8.255) (xy 8.255 -8.255)
					)
					(stroke
						(width 0.254)
						(type default)
					)
					(fill
						(type background)
					)
				)
				(polyline
					(pts
						(xy 8.255 -6.985) (xy 9.525 -6.35) (xy 9.525 -7.62) (xy 8.255 -6.985)
					)
					(stroke
						(width 0.254)
						(type default)
					)
					(fill
						(type background)
					)
				)
				(polyline
					(pts
						(xy 8.255 -7.62) (xy 8.255 -8.89) (xy 9.525 -8.255) (xy 8.255 -7.62)
					)
					(stroke
						(width 0.254)
						(type default)
					)
					(fill
						(type background)
					)
				)
				(polyline
					(pts
						(xy 9.525 -4.445) (xy 10.795 -4.445) (xy 10.795 -5.715) (xy 9.525 -5.715)
					)
					(stroke
						(width 0.254)
						(type default)
					)
					(fill
						(type background)
					)
				)
				(polyline
					(pts
						(xy 9.525 -6.985) (xy 10.795 -6.985) (xy 10.795 -8.255) (xy 9.525 -8.255)
					)
					(stroke
						(width 0.254)
						(type default)
					)
					(fill
						(type background)
					)
				)
				(polyline
					(pts
						(xy 10.795 -5.08) (xy 12.065 -5.08)
					)
					(stroke
						(width 0.254)
						(type default)
					)
					(fill
						(type background)
					)
				)
				(polyline
					(pts
						(xy 12.065 -7.62) (xy 10.795 -7.62)
					)
					(stroke
						(width 0.254)
						(type default)
					)
					(fill
						(type background)
					)
				)
				(pin power_in line
					(at 0 -2.54 0)
					(length 2.54)
					(name "VCCA"
						(effects
							(font
								(size 1.27 1.27)
							)
						)
					)
					(number "1"
						(effects
							(font
								(size 1.27 1.27)
							)
						)
					)
				)
				(pin bidirectional line
					(at 0 -5.08 0)
					(length 2.54)
					(name "A1"
						(effects
							(font
								(size 1.27 1.27)
							)
						)
					)
					(number "2"
						(effects
							(font
								(size 1.27 1.27)
							)
						)
					)
				)
				(pin bidirectional line
					(at 0 -7.62 0)
					(length 2.54)
					(name "A2"
						(effects
							(font
								(size 1.27 1.27)
							)
						)
					)
					(number "3"
						(effects
							(font
								(size 1.27 1.27)
							)
						)
					)
				)
				(pin tri_state line
					(at 0 -10.16 0)
					(length 2.54)
					(name "OE"
						(effects
							(font
								(size 1.27 1.27)
							)
						)
					)
					(number "5"
						(effects
							(font
								(size 1.27 1.27)
							)
						)
					)
				)
				(pin power_in line
					(at 17.78 -2.54 180)
					(length 2.54)
					(name "VCCB"
						(effects
							(font
								(size 1.27 1.27)
							)
						)
					)
					(number "8"
						(effects
							(font
								(size 1.27 1.27)
							)
						)
					)
				)
				(pin bidirectional line
					(at 17.78 -5.08 180)
					(length 2.54)
					(name "B1"
						(effects
							(font
								(size 1.27 1.27)
							)
						)
					)
					(number "7"
						(effects
							(font
								(size 1.27 1.27)
							)
						)
					)
				)
				(pin bidirectional line
					(at 17.78 -7.62 180)
					(length 2.54)
					(name "B2"
						(effects
							(font
								(size 1.27 1.27)
							)
						)
					)
					(number "6"
						(effects
							(font
								(size 1.27 1.27)
							)
						)
					)
				)
				(pin power_in line
					(at 17.78 -10.16 180)
					(length 2.54)
					(name "GND"
						(effects
							(font
								(size 1.27 1.27)
							)
						)
					)
					(number "4"
						(effects
							(font
								(size 1.27 1.27)
							)
						)
					)
				)
			)
		)
	(symbol "antmicroLogicTranslatorsLevelShifters:TXU0304BQAR"
			(exclude_from_sim no)
			(in_bom yes)
			(on_board yes)
			(property "Reference" "U"
				(at 31.75 0 0)
				(effects
					(font
						(size 1.27 1.27)
						(thickness 0.15)
					)
					(justify left bottom)
				)
			)
			(property "Value" "TXU0304BQAR"
				(at 31.75 -2.54 0)
				(effects
					(font
						(size 1.27 1.27)
						(thickness 0.15)
					)
					(justify left bottom)
					(hide yes)
				)
			)
			(property "Footprint" "antmicro-footprints:DHVQFN-14-1EP_2.5x3mm"
				(at 31.75 -5.08 0)
				(effects
					(font
						(size 1.27 1.27)
						(thickness 0.15)
					)
					(justify left bottom)
					(hide yes)
				)
			)
			(property "Datasheet" "https://www.ti.com/lit/ds/symlink/txu0304.pdf?ts=1637748643258&ref_url=https%253A%252F%252Fwww.ti.com%252Fproduct%252FTXU0304"
				(at 31.75 -7.62 0)
				(effects
					(font
						(size 1.27 1.27)
						(thickness 0.15)
					)
					(justify left bottom)
					(hide yes)
				)
			)
			(property "Description" "Logic translator/level shifter"
				(at 0 0 0)
				(effects
					(font
						(size 1.27 1.27)
					)
					(hide yes)
				)
			)
			(property "MPN" "TXU0304BQAR"
				(at 31.75 -10.16 0)
				(effects
					(font
						(size 1.27 1.27)
						(thickness 0.15)
					)
					(justify left bottom)
				)
			)
			(property "Manufacturer" "Texas Instruments"
				(at 31.75 -12.7 0)
				(effects
					(font
						(size 1.27 1.27)
						(thickness 0.15)
					)
					(justify left bottom)
					(hide yes)
				)
			)
			(property "Author" "Antmicro"
				(at 31.75 -15.24 0)
				(effects
					(font
						(size 1.27 1.27)
						(thickness 0.15)
					)
					(justify left bottom)
					(hide yes)
				)
			)
			(property "License" "Apache-2.0"
				(at 31.75 -17.78 0)
				(effects
					(font
						(size 1.27 1.27)
						(thickness 0.15)
					)
					(justify left bottom)
					(hide yes)
				)
			)
			(property "ki_keywords" "SMT, LOGIC, IC, LEVEL-SHIFTER"
				(at 0 0 0)
				(effects
					(font
						(size 1.27 1.27)
					)
					(hide yes)
				)
			)
			(symbol "TXU0304BQAR_1_1"
				(rectangle
					(start 2.54 2.54)
					(end 15.24 -17.78)
					(stroke
						(width 0.254)
						(type default)
					)
					(fill
						(type background)
					)
				)
				(polyline
					(pts
						(xy 6.35 -7.62) (xy 10.16 -7.62)
					)
					(stroke
						(width 0.254)
						(type default)
					)
					(fill
						(type background)
					)
				)
				(polyline
					(pts
						(xy 6.35 -12.7) (xy 10.16 -12.7)
					)
					(stroke
						(width 0.254)
						(type default)
					)
					(fill
						(type background)
					)
				)
				(polyline
					(pts
						(xy 7.62 -4.445) (xy 7.62 -5.715) (xy 8.89 -5.08) (xy 7.62 -4.445)
					)
					(stroke
						(width 0.254)
						(type default)
					)
					(fill
						(type outline)
					)
				)
				(polyline
					(pts
						(xy 7.62 -6.985) (xy 7.62 -8.255) (xy 8.89 -7.62) (xy 7.62 -6.985)
					)
					(stroke
						(width 0.254)
						(type default)
					)
					(fill
						(type outline)
					)
				)
				(polyline
					(pts
						(xy 7.62 -12.7) (xy 8.89 -12.065) (xy 8.89 -13.335) (xy 7.62 -12.7)
					)
					(stroke
						(width 0.254)
						(type default)
					)
					(fill
						(type outline)
					)
				)
				(polyline
					(pts
						(xy 8.89 -10.16) (xy 7.62 -10.795) (xy 7.62 -9.525) (xy 8.89 -10.16)
					)
					(stroke
						(width 0.254)
						(type default)
					)
					(fill
						(type outline)
					)
				)
				(polyline
					(pts
						(xy 10.16 -5.08) (xy 6.35 -5.08)
					)
					(stroke
						(width 0.254)
						(type default)
					)
					(fill
						(type background)
					)
				)
				(polyline
					(pts
						(xy 10.16 -10.16) (xy 6.35 -10.16)
					)
					(stroke
						(width 0.254)
						(type default)
					)
					(fill
						(type background)
					)
				)
				(pin power_in line
					(at 0 0 0)
					(length 2.54)
					(name "VCCA"
						(effects
							(font
								(size 1.27 1.27)
							)
						)
					)
					(number "1"
						(effects
							(font
								(size 1.27 1.27)
							)
						)
					)
				)
				(pin input line
					(at 0 -5.08 0)
					(length 2.54)
					(name "A1"
						(effects
							(font
								(size 1.27 1.27)
							)
						)
					)
					(number "2"
						(effects
							(font
								(size 1.27 1.27)
							)
						)
					)
				)
				(pin input line
					(at 0 -7.62 0)
					(length 2.54)
					(name "A2"
						(effects
							(font
								(size 1.27 1.27)
							)
						)
					)
					(number "3"
						(effects
							(font
								(size 1.27 1.27)
							)
						)
					)
				)
				(pin input line
					(at 0 -10.16 0)
					(length 2.54)
					(name "A3"
						(effects
							(font
								(size 1.27 1.27)
							)
						)
					)
					(number "4"
						(effects
							(font
								(size 1.27 1.27)
							)
						)
					)
				)
				(pin output line
					(at 0 -12.7 0)
					(length 2.54)
					(name "A4Y"
						(effects
							(font
								(size 1.27 1.27)
							)
						)
					)
					(number "5"
						(effects
							(font
								(size 1.27 1.27)
							)
						)
					)
				)
				(pin power_in line
					(at 0 -15.24 0)
					(length 2.54)
					(name "GND"
						(effects
							(font
								(size 1.27 1.27)
							)
						)
					)
					(number "15"
						(effects
							(font
								(size 1.27 1.27)
							)
						)
					)
				)
				(pin passive line
					(at 0 -15.24 0)
					(length 2.54)
					(hide yes)
					(name "GND"
						(effects
							(font
								(size 1.27 1.27)
							)
						)
					)
					(number "7"
						(effects
							(font
								(size 1.27 1.27)
							)
						)
					)
				)
				(pin no_connect line
					(at 2.54 -2.54 0)
					(length 2.54)
					(hide yes)
					(name "NC"
						(effects
							(font
								(size 1.27 1.27)
							)
						)
					)
					(number "6"
						(effects
							(font
								(size 1.27 1.27)
							)
						)
					)
				)
				(pin no_connect line
					(at 15.24 -15.24 180)
					(length 2.54)
					(hide yes)
					(name "NC"
						(effects
							(font
								(size 1.27 1.27)
							)
						)
					)
					(number "9"
						(effects
							(font
								(size 1.27 1.27)
							)
						)
					)
				)
				(pin power_in line
					(at 17.78 0 180)
					(length 2.54)
					(name "VCCB"
						(effects
							(font
								(size 1.27 1.27)
							)
						)
					)
					(number "14"
						(effects
							(font
								(size 1.27 1.27)
							)
						)
					)
				)
				(pin tri_state line
					(at 17.78 -2.54 180)
					(length 2.54)
					(name "OE"
						(effects
							(font
								(size 1.27 1.27)
							)
						)
					)
					(number "8"
						(effects
							(font
								(size 1.27 1.27)
							)
						)
					)
				)
				(pin output line
					(at 17.78 -5.08 180)
					(length 2.54)
					(name "B1Y"
						(effects
							(font
								(size 1.27 1.27)
							)
						)
					)
					(number "13"
						(effects
							(font
								(size 1.27 1.27)
							)
						)
					)
				)
				(pin output line
					(at 17.78 -7.62 180)
					(length 2.54)
					(name "B2Y"
						(effects
							(font
								(size 1.27 1.27)
							)
						)
					)
					(number "12"
						(effects
							(font
								(size 1.27 1.27)
							)
						)
					)
				)
				(pin output line
					(at 17.78 -10.16 180)
					(length 2.54)
					(name "B3Y"
						(effects
							(font
								(size 1.27 1.27)
							)
						)
					)
					(number "11"
						(effects
							(font
								(size 1.27 1.27)
							)
						)
					)
				)
				(pin input line
					(at 17.78 -12.7 180)
					(length 2.54)
					(name "B4"
						(effects
							(font
								(size 1.27 1.27)
							)
						)
					)
					(number "10"
						(effects
							(font
								(size 1.27 1.27)
							)
						)
					)
				)
			)
		)
	(symbol "antmicroMechanicalParts:Heatsink_ATS-61500R-C2-R0"
			(pin_names
				(hide yes)
			)
			(exclude_from_sim no)
			(in_bom yes)
			(on_board yes)
			(property "Reference" "H"
				(at 17.78 -2.54 0)
				(effects
					(font
						(size 1.27 1.27)
						(thickness 0.15)
					)
					(justify left bottom)
				)
			)
			(property "Value" "Heatsink_ATS-61500R-C2-R0"
				(at 17.78 -5.08 0)
				(effects
					(font
						(size 1.27 1.27)
						(thickness 0.15)
					)
					(justify left bottom)
				)
			)
			(property "Footprint" "antmicro-footprints:Heatsink_ATS-61500R-C2-R0"
				(at 17.78 -7.62 0)
				(effects
					(font
						(size 1.27 1.27)
						(thickness 0.15)
					)
					(justify left bottom)
					(hide yes)
				)
			)
			(property "Datasheet" "https://www.qats.com/DataSheet/ATS-61500-Series-C2-R0"
				(at 17.78 -10.16 0)
				(effects
					(font
						(size 1.27 1.27)
						(thickness 0.15)
					)
					(justify left bottom)
					(hide yes)
				)
			)
			(property "Description" "Heat Sinks fanSINK Assembly with Mounting Hardware"
				(at 0 0 0)
				(effects
					(font
						(size 1.27 1.27)
					)
					(hide yes)
				)
			)
			(property "MPN" "ATS-61500R-C2-R0"
				(at 17.78 -12.7 0)
				(effects
					(font
						(size 1.27 1.27)
						(thickness 0.15)
					)
					(justify left bottom)
					(hide yes)
				)
			)
			(property "Manufacturer" "Advanced Thermal Solutions"
				(at 17.78 -15.24 0)
				(effects
					(font
						(size 1.27 1.27)
						(thickness 0.15)
					)
					(justify left bottom)
					(hide yes)
				)
			)
			(property "Author" "Antmicro"
				(at 17.78 -17.78 0)
				(effects
					(font
						(size 1.27 1.27)
						(thickness 0.15)
					)
					(justify left bottom)
					(hide yes)
				)
			)
			(property "License" "Apache-2.0"
				(at 17.78 -20.32 0)
				(effects
					(font
						(size 1.27 1.27)
						(thickness 0.15)
					)
					(justify left bottom)
					(hide yes)
				)
			)
			(property "ki_keywords" "HEATSINK"
				(at 0 0 0)
				(effects
					(font
						(size 1.27 1.27)
					)
					(hide yes)
				)
			)
			(property "ki_fp_filters" "Heatsink_*"
				(at 0 0 0)
				(effects
					(font
						(size 1.27 1.27)
					)
					(hide yes)
				)
			)
			(symbol "Heatsink_ATS-61500R-C2-R0_0_1"
				(polyline
					(pts
						(xy 0 0) (xy 0.635 0) (xy 0.635 -3.175) (xy 1.27 -3.175) (xy 1.27 0) (xy 1.905 0) (xy 1.905 -3.175)
						(xy 2.54 -3.175) (xy 2.54 0) (xy 3.175 0) (xy 3.175 -3.175) (xy 3.81 -3.175) (xy 3.81 0) (xy 4.445 0)
						(xy 4.445 -3.175) (xy 5.08 -3.175) (xy 5.08 0) (xy 5.715 0) (xy 5.715 -4.445) (xy 0 -4.445) (xy 0 0)
					)
					(stroke
						(width 0)
						(type default)
					)
					(fill
						(type background)
					)
				)
			)
		)
	(symbol "antmicroMechanicalParts:Lightpipe_Mentor_1296.2013"
			(exclude_from_sim no)
			(in_bom yes)
			(on_board yes)
			(property "Reference" "H"
				(at 20.32 -2.54 0)
				(effects
					(font
						(size 1.27 1.27)
						(thickness 0.15)
					)
					(justify left bottom)
				)
			)
			(property "Value" "Lightpipe_Mentor_1296.2013"
				(at 20.32 -5.08 0)
				(effects
					(font
						(size 1.27 1.27)
						(thickness 0.15)
					)
					(justify left bottom)
				)
			)
			(property "Footprint" "antmicro-footprints:Mech_Lightpipe_Mentor_1296.2013"
				(at 20.32 -7.62 0)
				(effects
					(font
						(size 1.27 1.27)
						(thickness 0.15)
					)
					(justify left bottom)
					(hide yes)
				)
			)
			(property "Datasheet" "https://docs.rs-online.com/e47b/0900766b813f6efb.pdf"
				(at 20.32 -10.16 0)
				(effects
					(font
						(size 1.27 1.27)
						(thickness 0.15)
					)
					(justify left bottom)
					(hide yes)
				)
			)
			(property "Description" "Light Pipe, Miniature Triple Line, 14.45 mm, 3 Pipes, Circular, PC Board, Transparent"
				(at 0 0 0)
				(effects
					(font
						(size 1.27 1.27)
					)
					(hide yes)
				)
			)
			(property "Manufacturer" "Mentor Worldwide"
				(at 20.32 -12.7 0)
				(effects
					(font
						(size 1.27 1.27)
						(thickness 0.15)
					)
					(justify left bottom)
					(hide yes)
				)
			)
			(property "MPN" "1296.2013"
				(at 20.32 -15.24 0)
				(effects
					(font
						(size 1.27 1.27)
						(thickness 0.15)
					)
					(justify left bottom)
					(hide yes)
				)
			)
			(property "Author" "Antmicro"
				(at 20.32 -17.78 0)
				(effects
					(font
						(size 1.27 1.27)
						(thickness 0.15)
					)
					(justify left bottom)
					(hide yes)
				)
			)
			(property "License" "Apache-2.0"
				(at 20.32 -20.32 0)
				(effects
					(font
						(size 1.27 1.27)
						(thickness 0.15)
					)
					(justify left bottom)
					(hide yes)
				)
			)
			(property "ki_keywords" "HORIZONTAL, THT, MECHANICAL, MODULE"
				(at 0 0 0)
				(effects
					(font
						(size 1.27 1.27)
					)
					(hide yes)
				)
			)
			(symbol "Lightpipe_Mentor_1296.2013_1_1"
				(rectangle
					(start 5.08 -2.54)
					(end -5.08 3.81)
					(stroke
						(width 0.254)
						(type default)
					)
					(fill
						(type background)
					)
				)
				(text "Horizontal"
					(at -5.08 1.524 0)
					(effects
						(font
							(size 1.27 1.27)
							(thickness 0.15)
						)
						(justify left bottom)
					)
				)
				(text "lightguide"
					(at -4.826 -0.508 0)
					(effects
						(font
							(size 1.27 1.27)
							(thickness 0.15)
						)
						(justify left bottom)
					)
				)
				(text "1x3"
					(at -1.905 -2.54 0)
					(effects
						(font
							(size 1.27 1.27)
							(thickness 0.15)
						)
						(justify left bottom)
					)
				)
			)
		)
	(symbol "antmicroMemory:AT24CS01_SOT23"
			(exclude_from_sim no)
			(in_bom yes)
			(on_board yes)
			(property "Reference" "U"
				(at 35.56 -2.54 0)
				(effects
					(font
						(size 1.27 1.27)
						(thickness 0.15)
					)
					(justify left bottom)
				)
			)
			(property "Value" "AT24CS01_SOT23"
				(at 35.56 -5.08 0)
				(effects
					(font
						(size 1.27 1.27)
						(thickness 0.15)
					)
					(justify left bottom)
					(hide yes)
				)
			)
			(property "Footprint" "antmicro-footprints:SOT-23-5"
				(at 35.56 -7.62 0)
				(effects
					(font
						(size 1.27 1.27)
						(thickness 0.15)
					)
					(justify left bottom)
					(hide yes)
				)
			)
			(property "Datasheet" "http://ww1.microchip.com/downloads/en/devicedoc/Atmel-8815-SEEPROM-AT24CS01-02-Datasheet.pdf"
				(at 35.56 -10.16 0)
				(effects
					(font
						(size 1.27 1.27)
						(thickness 0.15)
					)
					(justify left bottom)
					(hide yes)
				)
			)
			(property "Description" "EEPROM Memory IC 1Kbit I²C 1 MHz 550 ns SOT-23-5"
				(at 0 0 0)
				(effects
					(font
						(size 1.27 1.27)
					)
					(hide yes)
				)
			)
			(property "Manufacturer" "Atmel"
				(at 35.56 -12.7 0)
				(effects
					(font
						(size 1.27 1.27)
						(thickness 0.15)
					)
					(justify left bottom)
					(hide yes)
				)
			)
			(property "MPN" "AT24CS01-ST"
				(at 35.56 -15.24 0)
				(effects
					(font
						(size 1.27 1.27)
						(thickness 0.15)
					)
					(justify left bottom)
				)
			)
			(property "Author" "Antmicro"
				(at 35.56 -17.78 0)
				(effects
					(font
						(size 1.27 1.27)
						(thickness 0.15)
					)
					(justify left bottom)
					(hide yes)
				)
			)
			(property "License" "Apache-2.0"
				(at 35.56 -20.32 0)
				(effects
					(font
						(size 1.27 1.27)
						(thickness 0.15)
					)
					(justify left bottom)
					(hide yes)
				)
			)
			(property "ki_keywords" "IC"
				(at 0 0 0)
				(effects
					(font
						(size 1.27 1.27)
					)
					(hide yes)
				)
			)
			(symbol "AT24CS01_SOT23_1_1"
				(rectangle
					(start 2.54 -7.62)
					(end 17.78 2.54)
					(stroke
						(width 0.254)
						(type default)
					)
					(fill
						(type background)
					)
				)
				(pin passive line
					(at 0 0 0)
					(length 2.54)
					(name "SDA"
						(effects
							(font
								(size 1.27 1.27)
							)
						)
					)
					(number "3"
						(effects
							(font
								(size 1.27 1.27)
							)
						)
					)
				)
				(pin passive line
					(at 0 -2.54 0)
					(length 2.54)
					(name "SCL"
						(effects
							(font
								(size 1.27 1.27)
							)
						)
					)
					(number "1"
						(effects
							(font
								(size 1.27 1.27)
							)
						)
					)
				)
				(pin passive line
					(at 0 -5.08 0)
					(length 2.54)
					(name "WP"
						(effects
							(font
								(size 1.27 1.27)
							)
						)
					)
					(number "5"
						(effects
							(font
								(size 1.27 1.27)
							)
						)
					)
				)
				(pin passive line
					(at 20.32 0 180)
					(length 2.54)
					(name "VCC"
						(effects
							(font
								(size 1.27 1.27)
							)
						)
					)
					(number "4"
						(effects
							(font
								(size 1.27 1.27)
							)
						)
					)
				)
				(pin passive line
					(at 20.32 -2.54 180)
					(length 2.54)
					(name "GND"
						(effects
							(font
								(size 1.27 1.27)
							)
						)
					)
					(number "2"
						(effects
							(font
								(size 1.27 1.27)
							)
						)
					)
				)
			)
		)
	(symbol "antmicroMemory:IS66WVH16M8DALL-166B1LI"
			(exclude_from_sim no)
			(in_bom yes)
			(on_board yes)
			(property "Reference" "U"
				(at 45.72 -5.08 0)
				(effects
					(font
						(size 1.27 1.27)
						(thickness 0.15)
					)
					(justify left bottom)
				)
			)
			(property "Value" "IS66WVH16M8DALL-166B1LI"
				(at 45.72 -10.16 0)
				(effects
					(font
						(size 1.27 1.27)
						(thickness 0.15)
					)
					(justify left bottom)
					(hide yes)
				)
			)
			(property "Footprint" "antmicro-footprints:FBGA-25-24_6x8mm_Layout5x5_P1mm"
				(at 45.72 -12.7 0)
				(effects
					(font
						(size 1.27 1.27)
						(thickness 0.15)
					)
					(justify left bottom)
					(hide yes)
				)
			)
			(property "Datasheet" "https://www.issi.com/WW/pdf/66-67WVH16M8DALL-BLL.pdf"
				(at 45.72 -15.24 0)
				(effects
					(font
						(size 1.27 1.27)
						(thickness 0.15)
					)
					(justify left bottom)
					(hide yes)
				)
			)
			(property "Description" "DRAM 128Mb, HyperRAM, 16Mbx8, 1.8V, 166MHz, 24-ball TFBGA, RoHS"
				(at 0 0 0)
				(effects
					(font
						(size 1.27 1.27)
					)
					(hide yes)
				)
			)
			(property "Manufacturer" "ISSI"
				(at 45.72 -17.78 0)
				(effects
					(font
						(size 1.27 1.27)
						(thickness 0.15)
					)
					(justify left bottom)
					(hide yes)
				)
			)
			(property "MPN" "IS66WVH16M8DALL-166B1LI"
				(at 45.72 -7.62 0)
				(effects
					(font
						(size 1.27 1.27)
						(thickness 0.15)
					)
					(justify left bottom)
				)
			)
			(property "Author" "Antmicro"
				(at 45.72 -20.32 0)
				(effects
					(font
						(size 1.27 1.27)
						(thickness 0.15)
					)
					(justify left bottom)
					(hide yes)
				)
			)
			(property "License" "Apache-2.0"
				(at 45.72 -22.86 0)
				(effects
					(font
						(size 1.27 1.27)
						(thickness 0.15)
					)
					(justify left bottom)
					(hide yes)
				)
			)
			(property "ki_keywords" "SMT, MEMORY, IC, DRAM, HYPERBUS, HYPERRAM"
				(at 0 0 0)
				(effects
					(font
						(size 1.27 1.27)
					)
					(hide yes)
				)
			)
			(symbol "IS66WVH16M8DALL-166B1LI_1_1"
				(rectangle
					(start 2.54 2.54)
					(end 27.94 -40.64)
					(stroke
						(width 0.254)
						(type default)
					)
					(fill
						(type background)
					)
				)
				(pin input line
					(at 0 0 0)
					(length 2.54)
					(name "~{RESET}"
						(effects
							(font
								(size 1.27 1.27)
							)
						)
					)
					(number "A4"
						(effects
							(font
								(size 1.27 1.27)
							)
						)
					)
				)
				(pin input line
					(at 0 -2.54 0)
					(length 2.54)
					(name "~{CS}"
						(effects
							(font
								(size 1.27 1.27)
							)
						)
					)
					(number "A3"
						(effects
							(font
								(size 1.27 1.27)
							)
						)
					)
				)
				(pin input line
					(at 0 -7.62 0)
					(length 2.54)
					(name "CK+"
						(effects
							(font
								(size 1.27 1.27)
							)
						)
					)
					(number "B2"
						(effects
							(font
								(size 1.27 1.27)
							)
						)
					)
				)
				(pin input line
					(at 0 -10.16 0)
					(length 2.54)
					(name "CK-"
						(effects
							(font
								(size 1.27 1.27)
							)
						)
					)
					(number "B1"
						(effects
							(font
								(size 1.27 1.27)
							)
						)
					)
				)
				(pin bidirectional line
					(at 0 -15.24 0)
					(length 2.54)
					(name "DQ0"
						(effects
							(font
								(size 1.27 1.27)
							)
						)
					)
					(number "D3"
						(effects
							(font
								(size 1.27 1.27)
							)
						)
					)
				)
				(pin bidirectional line
					(at 0 -17.78 0)
					(length 2.54)
					(name "DQ1"
						(effects
							(font
								(size 1.27 1.27)
							)
						)
					)
					(number "D2"
						(effects
							(font
								(size 1.27 1.27)
							)
						)
					)
				)
				(pin bidirectional line
					(at 0 -20.32 0)
					(length 2.54)
					(name "DQ2"
						(effects
							(font
								(size 1.27 1.27)
							)
						)
					)
					(number "C4"
						(effects
							(font
								(size 1.27 1.27)
							)
						)
					)
				)
				(pin bidirectional line
					(at 0 -22.86 0)
					(length 2.54)
					(name "DQ3"
						(effects
							(font
								(size 1.27 1.27)
							)
						)
					)
					(number "D4"
						(effects
							(font
								(size 1.27 1.27)
							)
						)
					)
				)
				(pin bidirectional line
					(at 0 -25.4 0)
					(length 2.54)
					(name "DQ4"
						(effects
							(font
								(size 1.27 1.27)
							)
						)
					)
					(number "D5"
						(effects
							(font
								(size 1.27 1.27)
							)
						)
					)
				)
				(pin bidirectional line
					(at 0 -27.94 0)
					(length 2.54)
					(name "DQ5"
						(effects
							(font
								(size 1.27 1.27)
							)
						)
					)
					(number "E3"
						(effects
							(font
								(size 1.27 1.27)
							)
						)
					)
				)
				(pin bidirectional line
					(at 0 -30.48 0)
					(length 2.54)
					(name "DQ6"
						(effects
							(font
								(size 1.27 1.27)
							)
						)
					)
					(number "E2"
						(effects
							(font
								(size 1.27 1.27)
							)
						)
					)
				)
				(pin bidirectional line
					(at 0 -33.02 0)
					(length 2.54)
					(name "DQ7"
						(effects
							(font
								(size 1.27 1.27)
							)
						)
					)
					(number "E1"
						(effects
							(font
								(size 1.27 1.27)
							)
						)
					)
				)
				(pin bidirectional line
					(at 0 -38.1 0)
					(length 2.54)
					(name "RWDS"
						(effects
							(font
								(size 1.27 1.27)
							)
						)
					)
					(number "C3"
						(effects
							(font
								(size 1.27 1.27)
							)
						)
					)
				)
				(pin no_connect line
					(at 27.94 -26.67 180)
					(length 2.54)
					(hide yes)
					(name "NC"
						(effects
							(font
								(size 1.27 1.27)
							)
						)
					)
					(number "B5"
						(effects
							(font
								(size 1.27 1.27)
							)
						)
					)
				)
				(pin no_connect line
					(at 27.94 -27.94 180)
					(length 2.54)
					(hide yes)
					(name "NC"
						(effects
							(font
								(size 1.27 1.27)
							)
						)
					)
					(number "A5"
						(effects
							(font
								(size 1.27 1.27)
							)
						)
					)
				)
				(pin no_connect line
					(at 27.94 -29.21 180)
					(length 2.54)
					(hide yes)
					(name "NC"
						(effects
							(font
								(size 1.27 1.27)
							)
						)
					)
					(number "A2"
						(effects
							(font
								(size 1.27 1.27)
							)
						)
					)
				)
				(pin no_connect line
					(at 27.94 -30.48 180)
					(length 2.54)
					(hide yes)
					(name "NC"
						(effects
							(font
								(size 1.27 1.27)
							)
						)
					)
					(number "C5"
						(effects
							(font
								(size 1.27 1.27)
							)
						)
					)
				)
				(pin no_connect line
					(at 27.94 -31.75 180)
					(length 2.54)
					(hide yes)
					(name "NC"
						(effects
							(font
								(size 1.27 1.27)
							)
						)
					)
					(number "C2"
						(effects
							(font
								(size 1.27 1.27)
							)
						)
					)
				)
				(pin power_in line
					(at 30.48 0 180)
					(length 2.54)
					(name "VCC"
						(effects
							(font
								(size 1.27 1.27)
							)
						)
					)
					(number "B4"
						(effects
							(font
								(size 1.27 1.27)
							)
						)
					)
				)
				(pin power_in line
					(at 30.48 -2.54 180)
					(length 2.54)
					(name "VCCQ"
						(effects
							(font
								(size 1.27 1.27)
							)
						)
					)
					(number "D1"
						(effects
							(font
								(size 1.27 1.27)
							)
						)
					)
				)
				(pin passive line
					(at 30.48 -2.54 180)
					(length 2.54)
					(hide yes)
					(name "VCCQ"
						(effects
							(font
								(size 1.27 1.27)
							)
						)
					)
					(number "E4"
						(effects
							(font
								(size 1.27 1.27)
							)
						)
					)
				)
				(pin power_in line
					(at 30.48 -35.56 180)
					(length 2.54)
					(name "VSSQ"
						(effects
							(font
								(size 1.27 1.27)
							)
						)
					)
					(number "C1"
						(effects
							(font
								(size 1.27 1.27)
							)
						)
					)
				)
				(pin passive line
					(at 30.48 -35.56 180)
					(length 2.54)
					(hide yes)
					(name "VSSQ"
						(effects
							(font
								(size 1.27 1.27)
							)
						)
					)
					(number "E5"
						(effects
							(font
								(size 1.27 1.27)
							)
						)
					)
				)
				(pin power_in line
					(at 30.48 -38.1 180)
					(length 2.54)
					(name "VSS"
						(effects
							(font
								(size 1.27 1.27)
							)
						)
					)
					(number "B3"
						(effects
							(font
								(size 1.27 1.27)
							)
						)
					)
				)
			)
		)
	(symbol "antmicroMemory:M24C64-F_DFN8"
			(exclude_from_sim no)
			(in_bom yes)
			(on_board yes)
			(property "Reference" "U"
				(at 38.1 -2.54 0)
				(effects
					(font
						(size 1.27 1.27)
						(thickness 0.15)
					)
					(justify left bottom)
				)
			)
			(property "Value" "M24C64-F_DFN8"
				(at 38.1 -15.24 0)
				(effects
					(font
						(size 1.27 1.27)
						(thickness 0.15)
					)
					(justify left bottom)
					(hide yes)
				)
			)
			(property "Footprint" "antmicro-footprints:DFN-8-1EP_3x2mm_P0.5mm_EP1.36x1.46mm"
				(at 38.1 -7.62 0)
				(effects
					(font
						(size 1.27 1.27)
						(thickness 0.15)
					)
					(justify left bottom)
					(hide yes)
				)
			)
			(property "Datasheet" "https://eu.mouser.com/datasheet/2/389/cd00259166-1797197.pdf"
				(at 38.1 -10.16 0)
				(effects
					(font
						(size 1.27 1.27)
						(thickness 0.15)
					)
					(justify left bottom)
					(hide yes)
				)
			)
			(property "Description" "EEPROM, 8K x 8bit, Serial I2C (2-Wire), 1 MHz, UFDFPN, 8 Pins"
				(at 0 0 0)
				(effects
					(font
						(size 1.27 1.27)
					)
					(hide yes)
				)
			)
			(property "Manufacturer" "STMicroelectronics"
				(at 38.1 -12.7 0)
				(effects
					(font
						(size 1.27 1.27)
						(thickness 0.15)
					)
					(justify left bottom)
					(hide yes)
				)
			)
			(property "MPN" "M24C64-FMC6TG"
				(at 38.1 -5.08 0)
				(effects
					(font
						(size 1.27 1.27)
						(thickness 0.15)
					)
					(justify left bottom)
				)
			)
			(property "Author" "Antmicro"
				(at 38.1 -17.78 0)
				(effects
					(font
						(size 1.27 1.27)
						(thickness 0.15)
					)
					(justify left bottom)
					(hide yes)
				)
			)
			(property "License" "Apache-2.0"
				(at 38.1 -20.32 0)
				(effects
					(font
						(size 1.27 1.27)
						(thickness 0.15)
					)
					(justify left bottom)
					(hide yes)
				)
			)
			(property "ki_keywords" "SMT, MEMORY, IC, STORAGE, I2C"
				(at 0 0 0)
				(effects
					(font
						(size 1.27 1.27)
					)
					(hide yes)
				)
			)
			(property "ki_fp_filters" "UFDFPN8DFN8_2X3_STM UFDFPN8DFN8_2X3_STM-M UFDFPN8DFN8_2X3_STM-L"
				(at 0 0 0)
				(effects
					(font
						(size 1.27 1.27)
					)
					(hide yes)
				)
			)
			(symbol "M24C64-F_DFN8_1_1"
				(rectangle
					(start 2.54 2.54)
					(end 12.7 -13.97)
					(stroke
						(width 0.254)
						(type default)
					)
					(fill
						(type background)
					)
				)
				(pin input line
					(at 0 0 0)
					(length 2.54)
					(name "SCL"
						(effects
							(font
								(size 1.27 1.27)
							)
						)
					)
					(number "6"
						(effects
							(font
								(size 1.27 1.27)
							)
						)
					)
				)
				(pin bidirectional line
					(at 0 -2.54 0)
					(length 2.54)
					(name "SDA"
						(effects
							(font
								(size 1.27 1.27)
							)
						)
					)
					(number "5"
						(effects
							(font
								(size 1.27 1.27)
							)
						)
					)
				)
				(pin input line
					(at 0 -6.35 0)
					(length 2.54)
					(name "E0"
						(effects
							(font
								(size 1.27 1.27)
							)
						)
					)
					(number "1"
						(effects
							(font
								(size 1.27 1.27)
							)
						)
					)
				)
				(pin input line
					(at 0 -8.89 0)
					(length 2.54)
					(name "E1"
						(effects
							(font
								(size 1.27 1.27)
							)
						)
					)
					(number "2"
						(effects
							(font
								(size 1.27 1.27)
							)
						)
					)
				)
				(pin input line
					(at 0 -11.43 0)
					(length 2.54)
					(name "E2"
						(effects
							(font
								(size 1.27 1.27)
							)
						)
					)
					(number "3"
						(effects
							(font
								(size 1.27 1.27)
							)
						)
					)
				)
				(pin power_in line
					(at 15.24 0 180)
					(length 2.54)
					(name "VCC"
						(effects
							(font
								(size 1.27 1.27)
							)
						)
					)
					(number "8"
						(effects
							(font
								(size 1.27 1.27)
							)
						)
					)
				)
				(pin input line
					(at 15.24 -5.08 180)
					(length 2.54)
					(name "~{WC}"
						(effects
							(font
								(size 1.27 1.27)
							)
						)
					)
					(number "7"
						(effects
							(font
								(size 1.27 1.27)
							)
						)
					)
				)
				(pin power_in line
					(at 15.24 -11.43 180)
					(length 2.54)
					(name "VSS"
						(effects
							(font
								(size 1.27 1.27)
							)
						)
					)
					(number "4"
						(effects
							(font
								(size 1.27 1.27)
							)
						)
					)
				)
				(pin passive line
					(at 15.24 -11.43 180)
					(length 2.54)
					(hide yes)
					(name "VSS"
						(effects
							(font
								(size 1.27 1.27)
							)
						)
					)
					(number "9"
						(effects
							(font
								(size 1.27 1.27)
							)
						)
					)
				)
			)
		)
	(symbol "antmicroMemory:W25Q128JWEIQ"
			(exclude_from_sim no)
			(in_bom yes)
			(on_board yes)
			(property "Reference" "U"
				(at 40.64 -2.54 0)
				(effects
					(font
						(size 1.27 1.27)
						(thickness 0.15)
					)
					(justify left bottom)
				)
			)
			(property "Value" "W25Q128JWEIQ"
				(at 40.64 -7.62 0)
				(effects
					(font
						(size 1.27 1.27)
						(thickness 0.15)
					)
					(justify left bottom)
					(hide yes)
				)
			)
			(property "Footprint" "antmicro-footprints:WSON-8_6x8x0.5mm_P1.27mm"
				(at 40.64 -10.16 0)
				(effects
					(font
						(size 1.27 1.27)
						(thickness 0.15)
					)
					(justify left bottom)
					(hide yes)
				)
			)
			(property "Datasheet" "https://www.winbond.com/resource-files/W25Q128JW_RevG_07292021%20Plus.pdf"
				(at 40.64 -12.7 0)
				(effects
					(font
						(size 1.27 1.27)
						(thickness 0.15)
					)
					(justify left bottom)
					(hide yes)
				)
			)
			(property "Description" "FLASH - NOR Memory IC 128Mbit SPI - Quad I/O, QPI 133 MHz 8-WSON (5x6)"
				(at 0 0 0)
				(effects
					(font
						(size 1.27 1.27)
					)
					(hide yes)
				)
			)
			(property "Manufacturer" "Winbond"
				(at 40.64 -15.24 0)
				(effects
					(font
						(size 1.27 1.27)
						(thickness 0.15)
					)
					(justify left bottom)
					(hide yes)
				)
			)
			(property "MPN" "W25Q128JWEIQ TR"
				(at 40.64 -5.08 0)
				(effects
					(font
						(size 1.27 1.27)
						(thickness 0.15)
					)
					(justify left bottom)
				)
			)
			(property "Author" "Antmicro"
				(at 40.64 -17.78 0)
				(effects
					(font
						(size 1.27 1.27)
						(thickness 0.15)
					)
					(justify left bottom)
					(hide yes)
				)
			)
			(property "License" "Apache-2.0"
				(at 40.64 -20.32 0)
				(effects
					(font
						(size 1.27 1.27)
						(thickness 0.15)
					)
					(justify left bottom)
					(hide yes)
				)
			)
			(property "ki_keywords" "SMT, MEMORY, IC"
				(at 0 0 0)
				(effects
					(font
						(size 1.27 1.27)
					)
					(hide yes)
				)
			)
			(symbol "W25Q128JWEIQ_1_1"
				(rectangle
					(start 2.54 2.54)
					(end 17.78 -15.24)
					(stroke
						(width 0.254)
						(type default)
					)
					(fill
						(type background)
					)
				)
				(pin bidirectional line
					(at 0 0 0)
					(length 2.54)
					(name "DI/IO0"
						(effects
							(font
								(size 1.27 1.27)
							)
						)
					)
					(number "5"
						(effects
							(font
								(size 1.27 1.27)
							)
						)
					)
				)
				(pin bidirectional line
					(at 0 -2.54 0)
					(length 2.54)
					(name "DO/IO1"
						(effects
							(font
								(size 1.27 1.27)
							)
						)
					)
					(number "2"
						(effects
							(font
								(size 1.27 1.27)
							)
						)
					)
				)
				(pin bidirectional line
					(at 0 -5.08 0)
					(length 2.54)
					(name "~{WP}/IO2"
						(effects
							(font
								(size 1.27 1.27)
							)
						)
					)
					(number "3"
						(effects
							(font
								(size 1.27 1.27)
							)
						)
					)
				)
				(pin bidirectional line
					(at 0 -7.62 0)
					(length 2.54)
					(name "~{HOLD}/IO3"
						(effects
							(font
								(size 1.27 1.27)
							)
						)
					)
					(number "7"
						(effects
							(font
								(size 1.27 1.27)
							)
						)
					)
				)
				(pin input line
					(at 0 -10.16 0)
					(length 2.54)
					(name "SCK"
						(effects
							(font
								(size 1.27 1.27)
							)
						)
					)
					(number "6"
						(effects
							(font
								(size 1.27 1.27)
							)
						)
					)
				)
				(pin input line
					(at 0 -12.7 0)
					(length 2.54)
					(name "~{CS}"
						(effects
							(font
								(size 1.27 1.27)
							)
						)
					)
					(number "1"
						(effects
							(font
								(size 1.27 1.27)
							)
						)
					)
				)
				(pin no_connect line
					(at 17.78 -10.16 180)
					(length 2.54)
					(hide yes)
					(name "EP"
						(effects
							(font
								(size 1.27 1.27)
							)
						)
					)
					(number "9"
						(effects
							(font
								(size 1.27 1.27)
							)
						)
					)
				)
				(pin power_in line
					(at 20.32 0 180)
					(length 2.54)
					(name "V_{CC}"
						(effects
							(font
								(size 1.27 1.27)
							)
						)
					)
					(number "8"
						(effects
							(font
								(size 1.27 1.27)
							)
						)
					)
				)
				(pin power_in line
					(at 20.32 -12.7 180)
					(length 2.54)
					(name "V_{SS}"
						(effects
							(font
								(size 1.27 1.27)
							)
						)
					)
					(number "4"
						(effects
							(font
								(size 1.27 1.27)
							)
						)
					)
				)
			)
		)
	(symbol "antmicroMemoryConnectorsPCCardSockets:Bus_DDR5_DDR504111002KQ"
			(exclude_from_sim no)
			(in_bom yes)
			(on_board yes)
			(property "Reference" "J"
				(at 45.72 -2.54 0)
				(effects
					(font
						(size 1.27 1.27)
						(thickness 0.15)
					)
					(justify left bottom)
				)
			)
			(property "Value" "Bus_DDR5_DDR504111002KQ"
				(at 45.72 -5.08 0)
				(effects
					(font
						(size 1.27 1.27)
						(thickness 0.15)
					)
					(justify left bottom)
					(hide yes)
				)
			)
			(property "Footprint" "antmicro-footprints:Bus_DDR5_Socket_Amphenol_DDR504111002KQ"
				(at 45.72 -7.62 0)
				(effects
					(font
						(size 1.27 1.27)
						(thickness 0.15)
					)
					(justify left bottom)
					(hide yes)
				)
			)
			(property "Datasheet" "https://www.amphenol-icc.com/ddr5-smt-ddr504111002kq.html"
				(at 45.72 -10.16 0)
				(effects
					(font
						(size 1.27 1.27)
						(thickness 0.15)
					)
					(justify left bottom)
					(hide yes)
				)
			)
			(property "Description" "Memory Card Connector, DDR5 DIMM, Latched, 288 Contacts, Copper Alloy, Gold Plated Contacts"
				(at 0 0 0)
				(effects
					(font
						(size 1.27 1.27)
					)
					(hide yes)
				)
			)
			(property "Manufacturer" "Amphenol"
				(at 45.72 -12.7 0)
				(effects
					(font
						(size 1.27 1.27)
						(thickness 0.15)
					)
					(justify left bottom)
					(hide yes)
				)
			)
			(property "MPN" "DDR504111002KQ"
				(at 45.72 -15.24 0)
				(effects
					(font
						(size 1.27 1.27)
						(thickness 0.15)
					)
					(justify left bottom)
				)
			)
			(property "Author" "Antmicro"
				(at 45.72 -17.78 0)
				(effects
					(font
						(size 1.27 1.27)
						(thickness 0.15)
					)
					(justify left bottom)
					(hide yes)
				)
			)
			(property "License" "Apache-2.0"
				(at 45.72 -20.32 0)
				(effects
					(font
						(size 1.27 1.27)
						(thickness 0.15)
					)
					(justify left bottom)
					(hide yes)
				)
			)
			(property "ki_locked" ""
				(at 0 0 0)
				(effects
					(font
						(size 1.27 1.27)
					)
				)
			)
			(property "ki_keywords" "VERTICAL, SMT, CONNECTOR, DDR"
				(at 0 0 0)
				(effects
					(font
						(size 1.27 1.27)
					)
					(hide yes)
				)
			)
			(symbol "Bus_DDR5_DDR504111002KQ_1_1"
				(rectangle
					(start 3.81 2.54)
					(end 26.67 -162.56)
					(stroke
						(width 0.254)
						(type default)
					)
					(fill
						(type background)
					)
				)
				(pin input line
					(at 0 0 0)
					(length 3.81)
					(name "DQ0_A"
						(effects
							(font
								(size 1.27 1.27)
							)
						)
					)
					(number "7"
						(effects
							(font
								(size 1.27 1.27)
							)
						)
					)
				)
				(pin input line
					(at 0 -2.54 0)
					(length 3.81)
					(name "DQ1_A"
						(effects
							(font
								(size 1.27 1.27)
							)
						)
					)
					(number "9"
						(effects
							(font
								(size 1.27 1.27)
							)
						)
					)
				)
				(pin input line
					(at 0 -5.08 0)
					(length 3.81)
					(name "DQ2_A"
						(effects
							(font
								(size 1.27 1.27)
							)
						)
					)
					(number "152"
						(effects
							(font
								(size 1.27 1.27)
							)
						)
					)
				)
				(pin input line
					(at 0 -7.62 0)
					(length 3.81)
					(name "DQ3_A"
						(effects
							(font
								(size 1.27 1.27)
							)
						)
					)
					(number "154"
						(effects
							(font
								(size 1.27 1.27)
							)
						)
					)
				)
				(pin input line
					(at 0 -10.16 0)
					(length 3.81)
					(name "DQS0_A_T"
						(effects
							(font
								(size 1.27 1.27)
							)
						)
					)
					(number "11"
						(effects
							(font
								(size 1.27 1.27)
							)
						)
					)
				)
				(pin input line
					(at 0 -12.7 0)
					(length 3.81)
					(name "DQS0_A_C"
						(effects
							(font
								(size 1.27 1.27)
							)
						)
					)
					(number "12"
						(effects
							(font
								(size 1.27 1.27)
							)
						)
					)
				)
				(pin input line
					(at 0 -15.24 0)
					(length 3.81)
					(name "DQ4_A"
						(effects
							(font
								(size 1.27 1.27)
							)
						)
					)
					(number "14"
						(effects
							(font
								(size 1.27 1.27)
							)
						)
					)
				)
				(pin input line
					(at 0 -17.78 0)
					(length 3.81)
					(name "DQ5_A"
						(effects
							(font
								(size 1.27 1.27)
							)
						)
					)
					(number "16"
						(effects
							(font
								(size 1.27 1.27)
							)
						)
					)
				)
				(pin input line
					(at 0 -20.32 0)
					(length 3.81)
					(name "DQ6_A"
						(effects
							(font
								(size 1.27 1.27)
							)
						)
					)
					(number "159"
						(effects
							(font
								(size 1.27 1.27)
							)
						)
					)
				)
				(pin input line
					(at 0 -22.86 0)
					(length 3.81)
					(name "DQ7_A"
						(effects
							(font
								(size 1.27 1.27)
							)
						)
					)
					(number "161"
						(effects
							(font
								(size 1.27 1.27)
							)
						)
					)
				)
				(pin input line
					(at 0 -25.4 0)
					(length 3.81)
					(name "DQS5_A_T"
						(effects
							(font
								(size 1.27 1.27)
							)
						)
					)
					(number "157"
						(effects
							(font
								(size 1.27 1.27)
							)
						)
					)
				)
				(pin input line
					(at 0 -27.94 0)
					(length 3.81)
					(name "DQS5_A_C"
						(effects
							(font
								(size 1.27 1.27)
							)
						)
					)
					(number "156"
						(effects
							(font
								(size 1.27 1.27)
							)
						)
					)
				)
				(pin input line
					(at 0 -33.02 0)
					(length 3.81)
					(name "DQ8_A"
						(effects
							(font
								(size 1.27 1.27)
							)
						)
					)
					(number "18"
						(effects
							(font
								(size 1.27 1.27)
							)
						)
					)
				)
				(pin input line
					(at 0 -35.56 0)
					(length 3.81)
					(name "DQ9_A"
						(effects
							(font
								(size 1.27 1.27)
							)
						)
					)
					(number "20"
						(effects
							(font
								(size 1.27 1.27)
							)
						)
					)
				)
				(pin input line
					(at 0 -38.1 0)
					(length 3.81)
					(name "DQ10_A"
						(effects
							(font
								(size 1.27 1.27)
							)
						)
					)
					(number "163"
						(effects
							(font
								(size 1.27 1.27)
							)
						)
					)
				)
				(pin input line
					(at 0 -40.64 0)
					(length 3.81)
					(name "DQ11_A"
						(effects
							(font
								(size 1.27 1.27)
							)
						)
					)
					(number "165"
						(effects
							(font
								(size 1.27 1.27)
							)
						)
					)
				)
				(pin input line
					(at 0 -43.18 0)
					(length 3.81)
					(name "DQS1_A_T"
						(effects
							(font
								(size 1.27 1.27)
							)
						)
					)
					(number "22"
						(effects
							(font
								(size 1.27 1.27)
							)
						)
					)
				)
				(pin input line
					(at 0 -45.72 0)
					(length 3.81)
					(name "DQS1_A_C"
						(effects
							(font
								(size 1.27 1.27)
							)
						)
					)
					(number "23"
						(effects
							(font
								(size 1.27 1.27)
							)
						)
					)
				)
				(pin input line
					(at 0 -48.26 0)
					(length 3.81)
					(name "DQ12_A"
						(effects
							(font
								(size 1.27 1.27)
							)
						)
					)
					(number "25"
						(effects
							(font
								(size 1.27 1.27)
							)
						)
					)
				)
				(pin input line
					(at 0 -50.8 0)
					(length 3.81)
					(name "DQ13_A"
						(effects
							(font
								(size 1.27 1.27)
							)
						)
					)
					(number "27"
						(effects
							(font
								(size 1.27 1.27)
							)
						)
					)
				)
				(pin input line
					(at 0 -53.34 0)
					(length 3.81)
					(name "DQ14_A"
						(effects
							(font
								(size 1.27 1.27)
							)
						)
					)
					(number "170"
						(effects
							(font
								(size 1.27 1.27)
							)
						)
					)
				)
				(pin input line
					(at 0 -55.88 0)
					(length 3.81)
					(name "DQ15_A"
						(effects
							(font
								(size 1.27 1.27)
							)
						)
					)
					(number "172"
						(effects
							(font
								(size 1.27 1.27)
							)
						)
					)
				)
				(pin input line
					(at 0 -58.42 0)
					(length 3.81)
					(name "DQS6_A_T"
						(effects
							(font
								(size 1.27 1.27)
							)
						)
					)
					(number "168"
						(effects
							(font
								(size 1.27 1.27)
							)
						)
					)
				)
				(pin input line
					(at 0 -60.96 0)
					(length 3.81)
					(name "DQS6_A_C"
						(effects
							(font
								(size 1.27 1.27)
							)
						)
					)
					(number "167"
						(effects
							(font
								(size 1.27 1.27)
							)
						)
					)
				)
				(pin input line
					(at 0 -66.04 0)
					(length 3.81)
					(name "DQ16_A"
						(effects
							(font
								(size 1.27 1.27)
							)
						)
					)
					(number "29"
						(effects
							(font
								(size 1.27 1.27)
							)
						)
					)
				)
				(pin input line
					(at 0 -68.58 0)
					(length 3.81)
					(name "DQ17_A"
						(effects
							(font
								(size 1.27 1.27)
							)
						)
					)
					(number "31"
						(effects
							(font
								(size 1.27 1.27)
							)
						)
					)
				)
				(pin input line
					(at 0 -71.12 0)
					(length 3.81)
					(name "DQ18_A"
						(effects
							(font
								(size 1.27 1.27)
							)
						)
					)
					(number "174"
						(effects
							(font
								(size 1.27 1.27)
							)
						)
					)
				)
				(pin input line
					(at 0 -73.66 0)
					(length 3.81)
					(name "DQ19_A"
						(effects
							(font
								(size 1.27 1.27)
							)
						)
					)
					(number "176"
						(effects
							(font
								(size 1.27 1.27)
							)
						)
					)
				)
				(pin input line
					(at 0 -76.2 0)
					(length 3.81)
					(name "DQS2_A_T"
						(effects
							(font
								(size 1.27 1.27)
							)
						)
					)
					(number "33"
						(effects
							(font
								(size 1.27 1.27)
							)
						)
					)
				)
				(pin input line
					(at 0 -78.74 0)
					(length 3.81)
					(name "DQS2_A_C"
						(effects
							(font
								(size 1.27 1.27)
							)
						)
					)
					(number "34"
						(effects
							(font
								(size 1.27 1.27)
							)
						)
					)
				)
				(pin input line
					(at 0 -81.28 0)
					(length 3.81)
					(name "DQ20_A"
						(effects
							(font
								(size 1.27 1.27)
							)
						)
					)
					(number "36"
						(effects
							(font
								(size 1.27 1.27)
							)
						)
					)
				)
				(pin input line
					(at 0 -83.82 0)
					(length 3.81)
					(name "DQ21_A"
						(effects
							(font
								(size 1.27 1.27)
							)
						)
					)
					(number "38"
						(effects
							(font
								(size 1.27 1.27)
							)
						)
					)
				)
				(pin input line
					(at 0 -86.36 0)
					(length 3.81)
					(name "DQ22_A"
						(effects
							(font
								(size 1.27 1.27)
							)
						)
					)
					(number "181"
						(effects
							(font
								(size 1.27 1.27)
							)
						)
					)
				)
				(pin input line
					(at 0 -88.9 0)
					(length 3.81)
					(name "DQ23_A"
						(effects
							(font
								(size 1.27 1.27)
							)
						)
					)
					(number "183"
						(effects
							(font
								(size 1.27 1.27)
							)
						)
					)
				)
				(pin input line
					(at 0 -91.44 0)
					(length 3.81)
					(name "DQS7_A_T"
						(effects
							(font
								(size 1.27 1.27)
							)
						)
					)
					(number "179"
						(effects
							(font
								(size 1.27 1.27)
							)
						)
					)
				)
				(pin input line
					(at 0 -93.98 0)
					(length 3.81)
					(name "DQS7_A_C"
						(effects
							(font
								(size 1.27 1.27)
							)
						)
					)
					(number "178"
						(effects
							(font
								(size 1.27 1.27)
							)
						)
					)
				)
				(pin input line
					(at 0 -99.06 0)
					(length 3.81)
					(name "DQ24_A"
						(effects
							(font
								(size 1.27 1.27)
							)
						)
					)
					(number "40"
						(effects
							(font
								(size 1.27 1.27)
							)
						)
					)
				)
				(pin input line
					(at 0 -101.6 0)
					(length 3.81)
					(name "DQ25_A"
						(effects
							(font
								(size 1.27 1.27)
							)
						)
					)
					(number "42"
						(effects
							(font
								(size 1.27 1.27)
							)
						)
					)
				)
				(pin input line
					(at 0 -104.14 0)
					(length 3.81)
					(name "DQ26_A"
						(effects
							(font
								(size 1.27 1.27)
							)
						)
					)
					(number "185"
						(effects
							(font
								(size 1.27 1.27)
							)
						)
					)
				)
				(pin input line
					(at 0 -106.68 0)
					(length 3.81)
					(name "DQ27_A"
						(effects
							(font
								(size 1.27 1.27)
							)
						)
					)
					(number "187"
						(effects
							(font
								(size 1.27 1.27)
							)
						)
					)
				)
				(pin input line
					(at 0 -109.22 0)
					(length 3.81)
					(name "DQS3_A_T"
						(effects
							(font
								(size 1.27 1.27)
							)
						)
					)
					(number "44"
						(effects
							(font
								(size 1.27 1.27)
							)
						)
					)
				)
				(pin input line
					(at 0 -111.76 0)
					(length 3.81)
					(name "DQS3_A_C"
						(effects
							(font
								(size 1.27 1.27)
							)
						)
					)
					(number "45"
						(effects
							(font
								(size 1.27 1.27)
							)
						)
					)
				)
				(pin input line
					(at 0 -114.3 0)
					(length 3.81)
					(name "DQ28_A"
						(effects
							(font
								(size 1.27 1.27)
							)
						)
					)
					(number "47"
						(effects
							(font
								(size 1.27 1.27)
							)
						)
					)
				)
				(pin input line
					(at 0 -116.84 0)
					(length 3.81)
					(name "DQ29_A"
						(effects
							(font
								(size 1.27 1.27)
							)
						)
					)
					(number "49"
						(effects
							(font
								(size 1.27 1.27)
							)
						)
					)
				)
				(pin input line
					(at 0 -119.38 0)
					(length 3.81)
					(name "DQ30_A"
						(effects
							(font
								(size 1.27 1.27)
							)
						)
					)
					(number "192"
						(effects
							(font
								(size 1.27 1.27)
							)
						)
					)
				)
				(pin input line
					(at 0 -121.92 0)
					(length 3.81)
					(name "DQ31_A"
						(effects
							(font
								(size 1.27 1.27)
							)
						)
					)
					(number "194"
						(effects
							(font
								(size 1.27 1.27)
							)
						)
					)
				)
				(pin input line
					(at 0 -124.46 0)
					(length 3.81)
					(name "DQS8_A_T"
						(effects
							(font
								(size 1.27 1.27)
							)
						)
					)
					(number "190"
						(effects
							(font
								(size 1.27 1.27)
							)
						)
					)
				)
				(pin input line
					(at 0 -127 0)
					(length 3.81)
					(name "DQS8_A_C"
						(effects
							(font
								(size 1.27 1.27)
							)
						)
					)
					(number "189"
						(effects
							(font
								(size 1.27 1.27)
							)
						)
					)
				)
				(pin input line
					(at 0 -132.08 0)
					(length 3.81)
					(name "CB0_A"
						(effects
							(font
								(size 1.27 1.27)
							)
						)
					)
					(number "51"
						(effects
							(font
								(size 1.27 1.27)
							)
						)
					)
				)
				(pin input line
					(at 0 -134.62 0)
					(length 3.81)
					(name "CB1_A"
						(effects
							(font
								(size 1.27 1.27)
							)
						)
					)
					(number "53"
						(effects
							(font
								(size 1.27 1.27)
							)
						)
					)
				)
				(pin input line
					(at 0 -137.16 0)
					(length 3.81)
					(name "CB2_A"
						(effects
							(font
								(size 1.27 1.27)
							)
						)
					)
					(number "196"
						(effects
							(font
								(size 1.27 1.27)
							)
						)
					)
				)
				(pin input line
					(at 0 -139.7 0)
					(length 3.81)
					(name "CB3_A"
						(effects
							(font
								(size 1.27 1.27)
							)
						)
					)
					(number "198"
						(effects
							(font
								(size 1.27 1.27)
							)
						)
					)
				)
				(pin input line
					(at 0 -142.24 0)
					(length 3.81)
					(name "DQS4_A_T"
						(effects
							(font
								(size 1.27 1.27)
							)
						)
					)
					(number "55"
						(effects
							(font
								(size 1.27 1.27)
							)
						)
					)
				)
				(pin input line
					(at 0 -144.78 0)
					(length 3.81)
					(name "DQS4_A_C"
						(effects
							(font
								(size 1.27 1.27)
							)
						)
					)
					(number "56"
						(effects
							(font
								(size 1.27 1.27)
							)
						)
					)
				)
				(pin input line
					(at 0 -147.32 0)
					(length 3.81)
					(name "CB4_A"
						(effects
							(font
								(size 1.27 1.27)
							)
						)
					)
					(number "58"
						(effects
							(font
								(size 1.27 1.27)
							)
						)
					)
				)
				(pin input line
					(at 0 -149.86 0)
					(length 3.81)
					(name "CB5_A"
						(effects
							(font
								(size 1.27 1.27)
							)
						)
					)
					(number "60"
						(effects
							(font
								(size 1.27 1.27)
							)
						)
					)
				)
				(pin input line
					(at 0 -152.4 0)
					(length 3.81)
					(name "CB6_A"
						(effects
							(font
								(size 1.27 1.27)
							)
						)
					)
					(number "203"
						(effects
							(font
								(size 1.27 1.27)
							)
						)
					)
				)
				(pin input line
					(at 0 -154.94 0)
					(length 3.81)
					(name "CB7_A"
						(effects
							(font
								(size 1.27 1.27)
							)
						)
					)
					(number "205"
						(effects
							(font
								(size 1.27 1.27)
							)
						)
					)
				)
				(pin input line
					(at 0 -157.48 0)
					(length 3.81)
					(name "DQS9_A_T"
						(effects
							(font
								(size 1.27 1.27)
							)
						)
					)
					(number "201"
						(effects
							(font
								(size 1.27 1.27)
							)
						)
					)
				)
				(pin input line
					(at 0 -160.02 0)
					(length 3.81)
					(name "DQS9_A_C"
						(effects
							(font
								(size 1.27 1.27)
							)
						)
					)
					(number "200"
						(effects
							(font
								(size 1.27 1.27)
							)
						)
					)
				)
				(pin input line
					(at 30.48 0 180)
					(length 3.81)
					(name "DQ0_B"
						(effects
							(font
								(size 1.27 1.27)
							)
						)
					)
					(number "100"
						(effects
							(font
								(size 1.27 1.27)
							)
						)
					)
				)
				(pin input line
					(at 30.48 -2.54 180)
					(length 3.81)
					(name "DQ1_B"
						(effects
							(font
								(size 1.27 1.27)
							)
						)
					)
					(number "102"
						(effects
							(font
								(size 1.27 1.27)
							)
						)
					)
				)
				(pin input line
					(at 30.48 -5.08 180)
					(length 3.81)
					(name "DQ2_B"
						(effects
							(font
								(size 1.27 1.27)
							)
						)
					)
					(number "245"
						(effects
							(font
								(size 1.27 1.27)
							)
						)
					)
				)
				(pin input line
					(at 30.48 -7.62 180)
					(length 3.81)
					(name "DQ3_B"
						(effects
							(font
								(size 1.27 1.27)
							)
						)
					)
					(number "247"
						(effects
							(font
								(size 1.27 1.27)
							)
						)
					)
				)
				(pin input line
					(at 30.48 -10.16 180)
					(length 3.81)
					(name "DQS0_B_T"
						(effects
							(font
								(size 1.27 1.27)
							)
						)
					)
					(number "104"
						(effects
							(font
								(size 1.27 1.27)
							)
						)
					)
				)
				(pin input line
					(at 30.48 -12.7 180)
					(length 3.81)
					(name "DQS0_B_C"
						(effects
							(font
								(size 1.27 1.27)
							)
						)
					)
					(number "105"
						(effects
							(font
								(size 1.27 1.27)
							)
						)
					)
				)
				(pin input line
					(at 30.48 -15.24 180)
					(length 3.81)
					(name "DQ4_B"
						(effects
							(font
								(size 1.27 1.27)
							)
						)
					)
					(number "107"
						(effects
							(font
								(size 1.27 1.27)
							)
						)
					)
				)
				(pin input line
					(at 30.48 -17.78 180)
					(length 3.81)
					(name "DQ5_B"
						(effects
							(font
								(size 1.27 1.27)
							)
						)
					)
					(number "109"
						(effects
							(font
								(size 1.27 1.27)
							)
						)
					)
				)
				(pin input line
					(at 30.48 -20.32 180)
					(length 3.81)
					(name "DQ6_B"
						(effects
							(font
								(size 1.27 1.27)
							)
						)
					)
					(number "252"
						(effects
							(font
								(size 1.27 1.27)
							)
						)
					)
				)
				(pin input line
					(at 30.48 -22.86 180)
					(length 3.81)
					(name "DQ7_B"
						(effects
							(font
								(size 1.27 1.27)
							)
						)
					)
					(number "254"
						(effects
							(font
								(size 1.27 1.27)
							)
						)
					)
				)
				(pin input line
					(at 30.48 -25.4 180)
					(length 3.81)
					(name "DQS5_B_T"
						(effects
							(font
								(size 1.27 1.27)
							)
						)
					)
					(number "250"
						(effects
							(font
								(size 1.27 1.27)
							)
						)
					)
				)
				(pin input line
					(at 30.48 -27.94 180)
					(length 3.81)
					(name "DQS5_B_C"
						(effects
							(font
								(size 1.27 1.27)
							)
						)
					)
					(number "249"
						(effects
							(font
								(size 1.27 1.27)
							)
						)
					)
				)
				(pin input line
					(at 30.48 -33.02 180)
					(length 3.81)
					(name "DQ8_B"
						(effects
							(font
								(size 1.27 1.27)
							)
						)
					)
					(number "111"
						(effects
							(font
								(size 1.27 1.27)
							)
						)
					)
				)
				(pin input line
					(at 30.48 -35.56 180)
					(length 3.81)
					(name "DQ9_B"
						(effects
							(font
								(size 1.27 1.27)
							)
						)
					)
					(number "113"
						(effects
							(font
								(size 1.27 1.27)
							)
						)
					)
				)
				(pin input line
					(at 30.48 -38.1 180)
					(length 3.81)
					(name "DQ10_B"
						(effects
							(font
								(size 1.27 1.27)
							)
						)
					)
					(number "256"
						(effects
							(font
								(size 1.27 1.27)
							)
						)
					)
				)
				(pin input line
					(at 30.48 -40.64 180)
					(length 3.81)
					(name "DQ11_B"
						(effects
							(font
								(size 1.27 1.27)
							)
						)
					)
					(number "258"
						(effects
							(font
								(size 1.27 1.27)
							)
						)
					)
				)
				(pin input line
					(at 30.48 -43.18 180)
					(length 3.81)
					(name "DQS1_B_T"
						(effects
							(font
								(size 1.27 1.27)
							)
						)
					)
					(number "115"
						(effects
							(font
								(size 1.27 1.27)
							)
						)
					)
				)
				(pin input line
					(at 30.48 -45.72 180)
					(length 3.81)
					(name "DQS1_B_C"
						(effects
							(font
								(size 1.27 1.27)
							)
						)
					)
					(number "116"
						(effects
							(font
								(size 1.27 1.27)
							)
						)
					)
				)
				(pin input line
					(at 30.48 -48.26 180)
					(length 3.81)
					(name "DQ12_B"
						(effects
							(font
								(size 1.27 1.27)
							)
						)
					)
					(number "118"
						(effects
							(font
								(size 1.27 1.27)
							)
						)
					)
				)
				(pin input line
					(at 30.48 -50.8 180)
					(length 3.81)
					(name "DQ13_B"
						(effects
							(font
								(size 1.27 1.27)
							)
						)
					)
					(number "120"
						(effects
							(font
								(size 1.27 1.27)
							)
						)
					)
				)
				(pin input line
					(at 30.48 -53.34 180)
					(length 3.81)
					(name "DQ14_B"
						(effects
							(font
								(size 1.27 1.27)
							)
						)
					)
					(number "263"
						(effects
							(font
								(size 1.27 1.27)
							)
						)
					)
				)
				(pin input line
					(at 30.48 -55.88 180)
					(length 3.81)
					(name "DQ15_B"
						(effects
							(font
								(size 1.27 1.27)
							)
						)
					)
					(number "265"
						(effects
							(font
								(size 1.27 1.27)
							)
						)
					)
				)
				(pin input line
					(at 30.48 -58.42 180)
					(length 3.81)
					(name "DQS6_B_T"
						(effects
							(font
								(size 1.27 1.27)
							)
						)
					)
					(number "261"
						(effects
							(font
								(size 1.27 1.27)
							)
						)
					)
				)
				(pin input line
					(at 30.48 -60.96 180)
					(length 3.81)
					(name "DQS6_B_C"
						(effects
							(font
								(size 1.27 1.27)
							)
						)
					)
					(number "260"
						(effects
							(font
								(size 1.27 1.27)
							)
						)
					)
				)
				(pin input line
					(at 30.48 -66.04 180)
					(length 3.81)
					(name "DQ16_B"
						(effects
							(font
								(size 1.27 1.27)
							)
						)
					)
					(number "122"
						(effects
							(font
								(size 1.27 1.27)
							)
						)
					)
				)
				(pin input line
					(at 30.48 -68.58 180)
					(length 3.81)
					(name "DQ17_B"
						(effects
							(font
								(size 1.27 1.27)
							)
						)
					)
					(number "124"
						(effects
							(font
								(size 1.27 1.27)
							)
						)
					)
				)
				(pin input line
					(at 30.48 -71.12 180)
					(length 3.81)
					(name "DQ18_B"
						(effects
							(font
								(size 1.27 1.27)
							)
						)
					)
					(number "267"
						(effects
							(font
								(size 1.27 1.27)
							)
						)
					)
				)
				(pin input line
					(at 30.48 -73.66 180)
					(length 3.81)
					(name "DQ19_B"
						(effects
							(font
								(size 1.27 1.27)
							)
						)
					)
					(number "269"
						(effects
							(font
								(size 1.27 1.27)
							)
						)
					)
				)
				(pin input line
					(at 30.48 -76.2 180)
					(length 3.81)
					(name "DQS2_B_T"
						(effects
							(font
								(size 1.27 1.27)
							)
						)
					)
					(number "126"
						(effects
							(font
								(size 1.27 1.27)
							)
						)
					)
				)
				(pin input line
					(at 30.48 -78.74 180)
					(length 3.81)
					(name "DQS2_B_C"
						(effects
							(font
								(size 1.27 1.27)
							)
						)
					)
					(number "127"
						(effects
							(font
								(size 1.27 1.27)
							)
						)
					)
				)
				(pin input line
					(at 30.48 -81.28 180)
					(length 3.81)
					(name "DQ20_B"
						(effects
							(font
								(size 1.27 1.27)
							)
						)
					)
					(number "129"
						(effects
							(font
								(size 1.27 1.27)
							)
						)
					)
				)
				(pin input line
					(at 30.48 -83.82 180)
					(length 3.81)
					(name "DQ21_B"
						(effects
							(font
								(size 1.27 1.27)
							)
						)
					)
					(number "131"
						(effects
							(font
								(size 1.27 1.27)
							)
						)
					)
				)
				(pin input line
					(at 30.48 -86.36 180)
					(length 3.81)
					(name "DQ22_B"
						(effects
							(font
								(size 1.27 1.27)
							)
						)
					)
					(number "274"
						(effects
							(font
								(size 1.27 1.27)
							)
						)
					)
				)
				(pin input line
					(at 30.48 -88.9 180)
					(length 3.81)
					(name "DQ23_B"
						(effects
							(font
								(size 1.27 1.27)
							)
						)
					)
					(number "276"
						(effects
							(font
								(size 1.27 1.27)
							)
						)
					)
				)
				(pin input line
					(at 30.48 -91.44 180)
					(length 3.81)
					(name "DQS7_B_T"
						(effects
							(font
								(size 1.27 1.27)
							)
						)
					)
					(number "272"
						(effects
							(font
								(size 1.27 1.27)
							)
						)
					)
				)
				(pin input line
					(at 30.48 -93.98 180)
					(length 3.81)
					(name "DQS7_B_C"
						(effects
							(font
								(size 1.27 1.27)
							)
						)
					)
					(number "271"
						(effects
							(font
								(size 1.27 1.27)
							)
						)
					)
				)
				(pin input line
					(at 30.48 -99.06 180)
					(length 3.81)
					(name "DQ24_B"
						(effects
							(font
								(size 1.27 1.27)
							)
						)
					)
					(number "133"
						(effects
							(font
								(size 1.27 1.27)
							)
						)
					)
				)
				(pin input line
					(at 30.48 -101.6 180)
					(length 3.81)
					(name "DQ25_B"
						(effects
							(font
								(size 1.27 1.27)
							)
						)
					)
					(number "135"
						(effects
							(font
								(size 1.27 1.27)
							)
						)
					)
				)
				(pin input line
					(at 30.48 -104.14 180)
					(length 3.81)
					(name "DQ26_B"
						(effects
							(font
								(size 1.27 1.27)
							)
						)
					)
					(number "278"
						(effects
							(font
								(size 1.27 1.27)
							)
						)
					)
				)
				(pin input line
					(at 30.48 -106.68 180)
					(length 3.81)
					(name "DQ27_B"
						(effects
							(font
								(size 1.27 1.27)
							)
						)
					)
					(number "280"
						(effects
							(font
								(size 1.27 1.27)
							)
						)
					)
				)
				(pin input line
					(at 30.48 -109.22 180)
					(length 3.81)
					(name "DQS3_B_T"
						(effects
							(font
								(size 1.27 1.27)
							)
						)
					)
					(number "137"
						(effects
							(font
								(size 1.27 1.27)
							)
						)
					)
				)
				(pin input line
					(at 30.48 -111.76 180)
					(length 3.81)
					(name "DQS3_B_C"
						(effects
							(font
								(size 1.27 1.27)
							)
						)
					)
					(number "138"
						(effects
							(font
								(size 1.27 1.27)
							)
						)
					)
				)
				(pin input line
					(at 30.48 -114.3 180)
					(length 3.81)
					(name "DQ28_B"
						(effects
							(font
								(size 1.27 1.27)
							)
						)
					)
					(number "140"
						(effects
							(font
								(size 1.27 1.27)
							)
						)
					)
				)
				(pin input line
					(at 30.48 -116.84 180)
					(length 3.81)
					(name "DQ29_B"
						(effects
							(font
								(size 1.27 1.27)
							)
						)
					)
					(number "142"
						(effects
							(font
								(size 1.27 1.27)
							)
						)
					)
				)
				(pin input line
					(at 30.48 -119.38 180)
					(length 3.81)
					(name "DQ30_B"
						(effects
							(font
								(size 1.27 1.27)
							)
						)
					)
					(number "285"
						(effects
							(font
								(size 1.27 1.27)
							)
						)
					)
				)
				(pin input line
					(at 30.48 -121.92 180)
					(length 3.81)
					(name "DQ31_B"
						(effects
							(font
								(size 1.27 1.27)
							)
						)
					)
					(number "287"
						(effects
							(font
								(size 1.27 1.27)
							)
						)
					)
				)
				(pin input line
					(at 30.48 -124.46 180)
					(length 3.81)
					(name "DQS8_B_T"
						(effects
							(font
								(size 1.27 1.27)
							)
						)
					)
					(number "283"
						(effects
							(font
								(size 1.27 1.27)
							)
						)
					)
				)
				(pin input line
					(at 30.48 -127 180)
					(length 3.81)
					(name "DQS8_B_C"
						(effects
							(font
								(size 1.27 1.27)
							)
						)
					)
					(number "282"
						(effects
							(font
								(size 1.27 1.27)
							)
						)
					)
				)
				(pin input line
					(at 30.48 -132.08 180)
					(length 3.81)
					(name "CB0_B"
						(effects
							(font
								(size 1.27 1.27)
							)
						)
					)
					(number "96"
						(effects
							(font
								(size 1.27 1.27)
							)
						)
					)
				)
				(pin input line
					(at 30.48 -134.62 180)
					(length 3.81)
					(name "CB1_B"
						(effects
							(font
								(size 1.27 1.27)
							)
						)
					)
					(number "98"
						(effects
							(font
								(size 1.27 1.27)
							)
						)
					)
				)
				(pin input line
					(at 30.48 -137.16 180)
					(length 3.81)
					(name "CB2_B"
						(effects
							(font
								(size 1.27 1.27)
							)
						)
					)
					(number "241"
						(effects
							(font
								(size 1.27 1.27)
							)
						)
					)
				)
				(pin input line
					(at 30.48 -139.7 180)
					(length 3.81)
					(name "CB3_B"
						(effects
							(font
								(size 1.27 1.27)
							)
						)
					)
					(number "243"
						(effects
							(font
								(size 1.27 1.27)
							)
						)
					)
				)
				(pin input line
					(at 30.48 -142.24 180)
					(length 3.81)
					(name "DQS4_B_T"
						(effects
							(font
								(size 1.27 1.27)
							)
						)
					)
					(number "239"
						(effects
							(font
								(size 1.27 1.27)
							)
						)
					)
				)
				(pin input line
					(at 30.48 -144.78 180)
					(length 3.81)
					(name "DQS4_B_C"
						(effects
							(font
								(size 1.27 1.27)
							)
						)
					)
					(number "238"
						(effects
							(font
								(size 1.27 1.27)
							)
						)
					)
				)
				(pin input line
					(at 30.48 -147.32 180)
					(length 3.81)
					(name "CB4_B"
						(effects
							(font
								(size 1.27 1.27)
							)
						)
					)
					(number "89"
						(effects
							(font
								(size 1.27 1.27)
							)
						)
					)
				)
				(pin input line
					(at 30.48 -149.86 180)
					(length 3.81)
					(name "CB5_B"
						(effects
							(font
								(size 1.27 1.27)
							)
						)
					)
					(number "91"
						(effects
							(font
								(size 1.27 1.27)
							)
						)
					)
				)
				(pin input line
					(at 30.48 -152.4 180)
					(length 3.81)
					(name "CB6_B"
						(effects
							(font
								(size 1.27 1.27)
							)
						)
					)
					(number "234"
						(effects
							(font
								(size 1.27 1.27)
							)
						)
					)
				)
				(pin input line
					(at 30.48 -154.94 180)
					(length 3.81)
					(name "CB7_B"
						(effects
							(font
								(size 1.27 1.27)
							)
						)
					)
					(number "236"
						(effects
							(font
								(size 1.27 1.27)
							)
						)
					)
				)
				(pin input line
					(at 30.48 -157.48 180)
					(length 3.81)
					(name "DQS9_B_T"
						(effects
							(font
								(size 1.27 1.27)
							)
						)
					)
					(number "93"
						(effects
							(font
								(size 1.27 1.27)
							)
						)
					)
				)
				(pin input line
					(at 30.48 -160.02 180)
					(length 3.81)
					(name "DQS9_B_C"
						(effects
							(font
								(size 1.27 1.27)
							)
						)
					)
					(number "94"
						(effects
							(font
								(size 1.27 1.27)
							)
						)
					)
				)
			)
			(symbol "Bus_DDR5_DDR504111002KQ_2_1"
				(rectangle
					(start 3.81 2.54)
					(end 26.67 -63.5)
					(stroke
						(width 0.254)
						(type default)
					)
					(fill
						(type background)
					)
				)
				(pin power_in line
					(at 0 0 0)
					(length 3.81)
					(name "VIN_BULK"
						(effects
							(font
								(size 1.27 1.27)
							)
						)
					)
					(number "1"
						(effects
							(font
								(size 1.27 1.27)
							)
						)
					)
				)
				(pin passive line
					(at 0 0 0)
					(length 3.81)
					(hide yes)
					(name "VIN_BULK"
						(effects
							(font
								(size 1.27 1.27)
							)
						)
					)
					(number "145"
						(effects
							(font
								(size 1.27 1.27)
							)
						)
					)
				)
				(pin passive line
					(at 0 0 0)
					(length 3.81)
					(hide yes)
					(name "VIN_BULK"
						(effects
							(font
								(size 1.27 1.27)
							)
						)
					)
					(number "146"
						(effects
							(font
								(size 1.27 1.27)
							)
						)
					)
				)
				(pin power_in line
					(at 0 -2.54 0)
					(length 3.81)
					(name "VIN_MGMT"
						(effects
							(font
								(size 1.27 1.27)
							)
						)
					)
					(number "3"
						(effects
							(font
								(size 1.27 1.27)
							)
						)
					)
				)
				(pin input line
					(at 0 -5.08 0)
					(length 3.81)
					(name "PCAMP"
						(effects
							(font
								(size 1.27 1.27)
							)
						)
					)
					(number "147"
						(effects
							(font
								(size 1.27 1.27)
							)
						)
					)
				)
				(pin input line
					(at 0 -10.16 0)
					(length 3.81)
					(name "DLBDQ"
						(effects
							(font
								(size 1.27 1.27)
							)
						)
					)
					(number "86"
						(effects
							(font
								(size 1.27 1.27)
							)
						)
					)
				)
				(pin input line
					(at 0 -12.7 0)
					(length 3.81)
					(name "DLBDQS"
						(effects
							(font
								(size 1.27 1.27)
							)
						)
					)
					(number "87"
						(effects
							(font
								(size 1.27 1.27)
							)
						)
					)
				)
				(pin input line
					(at 0 -15.24 0)
					(length 3.81)
					(name "RESET_N"
						(effects
							(font
								(size 1.27 1.27)
							)
						)
					)
					(number "207"
						(effects
							(font
								(size 1.27 1.27)
							)
						)
					)
				)
				(pin input line
					(at 0 -20.32 0)
					(length 3.81)
					(name "CA0_A"
						(effects
							(font
								(size 1.27 1.27)
							)
						)
					)
					(number "66"
						(effects
							(font
								(size 1.27 1.27)
							)
						)
					)
				)
				(pin input line
					(at 0 -22.86 0)
					(length 3.81)
					(name "CA1_A"
						(effects
							(font
								(size 1.27 1.27)
							)
						)
					)
					(number "211"
						(effects
							(font
								(size 1.27 1.27)
							)
						)
					)
				)
				(pin input line
					(at 0 -25.4 0)
					(length 3.81)
					(name "CA2_A"
						(effects
							(font
								(size 1.27 1.27)
							)
						)
					)
					(number "68"
						(effects
							(font
								(size 1.27 1.27)
							)
						)
					)
				)
				(pin input line
					(at 0 -27.94 0)
					(length 3.81)
					(name "CA3_A"
						(effects
							(font
								(size 1.27 1.27)
							)
						)
					)
					(number "213"
						(effects
							(font
								(size 1.27 1.27)
							)
						)
					)
				)
				(pin input line
					(at 0 -30.48 0)
					(length 3.81)
					(name "CA4_A"
						(effects
							(font
								(size 1.27 1.27)
							)
						)
					)
					(number "70"
						(effects
							(font
								(size 1.27 1.27)
							)
						)
					)
				)
				(pin input line
					(at 0 -33.02 0)
					(length 3.81)
					(name "CA5_A"
						(effects
							(font
								(size 1.27 1.27)
							)
						)
					)
					(number "215"
						(effects
							(font
								(size 1.27 1.27)
							)
						)
					)
				)
				(pin input line
					(at 0 -35.56 0)
					(length 3.81)
					(name "CA6_A"
						(effects
							(font
								(size 1.27 1.27)
							)
						)
					)
					(number "72"
						(effects
							(font
								(size 1.27 1.27)
							)
						)
					)
				)
				(pin input line
					(at 0 -38.1 0)
					(length 3.81)
					(name "PAR_A"
						(effects
							(font
								(size 1.27 1.27)
							)
						)
					)
					(number "74"
						(effects
							(font
								(size 1.27 1.27)
							)
						)
					)
				)
				(pin input line
					(at 0 -40.64 0)
					(length 3.81)
					(name "CS0_A_N"
						(effects
							(font
								(size 1.27 1.27)
							)
						)
					)
					(number "64"
						(effects
							(font
								(size 1.27 1.27)
							)
						)
					)
				)
				(pin input line
					(at 0 -43.18 0)
					(length 3.81)
					(name "CS1_A_N"
						(effects
							(font
								(size 1.27 1.27)
							)
						)
					)
					(number "209"
						(effects
							(font
								(size 1.27 1.27)
							)
						)
					)
				)
				(pin passive line
					(at 0 -53.34 0)
					(length 3.81)
					(hide yes)
					(name "VSS_DET"
						(effects
							(font
								(size 1.27 1.27)
							)
						)
					)
					(number "75"
						(effects
							(font
								(size 1.27 1.27)
							)
						)
					)
				)
				(pin power_in line
					(at 0 -55.88 0)
					(length 3.81)
					(name "VSS"
						(effects
							(font
								(size 1.27 1.27)
							)
						)
					)
					(number "10"
						(effects
							(font
								(size 1.27 1.27)
							)
						)
					)
				)
				(pin passive line
					(at 0 -55.88 0)
					(length 3.81)
					(hide yes)
					(name "VSS"
						(effects
							(font
								(size 1.27 1.27)
							)
						)
					)
					(number "101"
						(effects
							(font
								(size 1.27 1.27)
							)
						)
					)
				)
				(pin passive line
					(at 0 -55.88 0)
					(length 3.81)
					(hide yes)
					(name "VSS"
						(effects
							(font
								(size 1.27 1.27)
							)
						)
					)
					(number "103"
						(effects
							(font
								(size 1.27 1.27)
							)
						)
					)
				)
				(pin passive line
					(at 0 -55.88 0)
					(length 3.81)
					(hide yes)
					(name "VSS"
						(effects
							(font
								(size 1.27 1.27)
							)
						)
					)
					(number "106"
						(effects
							(font
								(size 1.27 1.27)
							)
						)
					)
				)
				(pin passive line
					(at 0 -55.88 0)
					(length 3.81)
					(hide yes)
					(name "VSS"
						(effects
							(font
								(size 1.27 1.27)
							)
						)
					)
					(number "108"
						(effects
							(font
								(size 1.27 1.27)
							)
						)
					)
				)
				(pin passive line
					(at 0 -55.88 0)
					(length 3.81)
					(hide yes)
					(name "VSS"
						(effects
							(font
								(size 1.27 1.27)
							)
						)
					)
					(number "110"
						(effects
							(font
								(size 1.27 1.27)
							)
						)
					)
				)
				(pin passive line
					(at 0 -55.88 0)
					(length 3.81)
					(hide yes)
					(name "VSS"
						(effects
							(font
								(size 1.27 1.27)
							)
						)
					)
					(number "112"
						(effects
							(font
								(size 1.27 1.27)
							)
						)
					)
				)
				(pin passive line
					(at 0 -55.88 0)
					(length 3.81)
					(hide yes)
					(name "VSS"
						(effects
							(font
								(size 1.27 1.27)
							)
						)
					)
					(number "114"
						(effects
							(font
								(size 1.27 1.27)
							)
						)
					)
				)
				(pin passive line
					(at 0 -55.88 0)
					(length 3.81)
					(hide yes)
					(name "VSS"
						(effects
							(font
								(size 1.27 1.27)
							)
						)
					)
					(number "117"
						(effects
							(font
								(size 1.27 1.27)
							)
						)
					)
				)
				(pin passive line
					(at 0 -55.88 0)
					(length 3.81)
					(hide yes)
					(name "VSS"
						(effects
							(font
								(size 1.27 1.27)
							)
						)
					)
					(number "119"
						(effects
							(font
								(size 1.27 1.27)
							)
						)
					)
				)
				(pin passive line
					(at 0 -55.88 0)
					(length 3.81)
					(hide yes)
					(name "VSS"
						(effects
							(font
								(size 1.27 1.27)
							)
						)
					)
					(number "121"
						(effects
							(font
								(size 1.27 1.27)
							)
						)
					)
				)
				(pin passive line
					(at 0 -55.88 0)
					(length 3.81)
					(hide yes)
					(name "VSS"
						(effects
							(font
								(size 1.27 1.27)
							)
						)
					)
					(number "123"
						(effects
							(font
								(size 1.27 1.27)
							)
						)
					)
				)
				(pin passive line
					(at 0 -55.88 0)
					(length 3.81)
					(hide yes)
					(name "VSS"
						(effects
							(font
								(size 1.27 1.27)
							)
						)
					)
					(number "125"
						(effects
							(font
								(size 1.27 1.27)
							)
						)
					)
				)
				(pin passive line
					(at 0 -55.88 0)
					(length 3.81)
					(hide yes)
					(name "VSS"
						(effects
							(font
								(size 1.27 1.27)
							)
						)
					)
					(number "128"
						(effects
							(font
								(size 1.27 1.27)
							)
						)
					)
				)
				(pin passive line
					(at 0 -55.88 0)
					(length 3.81)
					(hide yes)
					(name "VSS"
						(effects
							(font
								(size 1.27 1.27)
							)
						)
					)
					(number "13"
						(effects
							(font
								(size 1.27 1.27)
							)
						)
					)
				)
				(pin passive line
					(at 0 -55.88 0)
					(length 3.81)
					(hide yes)
					(name "VSS"
						(effects
							(font
								(size 1.27 1.27)
							)
						)
					)
					(number "130"
						(effects
							(font
								(size 1.27 1.27)
							)
						)
					)
				)
				(pin passive line
					(at 0 -55.88 0)
					(length 3.81)
					(hide yes)
					(name "VSS"
						(effects
							(font
								(size 1.27 1.27)
							)
						)
					)
					(number "132"
						(effects
							(font
								(size 1.27 1.27)
							)
						)
					)
				)
				(pin passive line
					(at 0 -55.88 0)
					(length 3.81)
					(hide yes)
					(name "VSS"
						(effects
							(font
								(size 1.27 1.27)
							)
						)
					)
					(number "134"
						(effects
							(font
								(size 1.27 1.27)
							)
						)
					)
				)
				(pin passive line
					(at 0 -55.88 0)
					(length 3.81)
					(hide yes)
					(name "VSS"
						(effects
							(font
								(size 1.27 1.27)
							)
						)
					)
					(number "136"
						(effects
							(font
								(size 1.27 1.27)
							)
						)
					)
				)
				(pin passive line
					(at 0 -55.88 0)
					(length 3.81)
					(hide yes)
					(name "VSS"
						(effects
							(font
								(size 1.27 1.27)
							)
						)
					)
					(number "139"
						(effects
							(font
								(size 1.27 1.27)
							)
						)
					)
				)
				(pin passive line
					(at 0 -55.88 0)
					(length 3.81)
					(hide yes)
					(name "VSS"
						(effects
							(font
								(size 1.27 1.27)
							)
						)
					)
					(number "141"
						(effects
							(font
								(size 1.27 1.27)
							)
						)
					)
				)
				(pin passive line
					(at 0 -55.88 0)
					(length 3.81)
					(hide yes)
					(name "VSS"
						(effects
							(font
								(size 1.27 1.27)
							)
						)
					)
					(number "143"
						(effects
							(font
								(size 1.27 1.27)
							)
						)
					)
				)
				(pin passive line
					(at 0 -55.88 0)
					(length 3.81)
					(hide yes)
					(name "VSS"
						(effects
							(font
								(size 1.27 1.27)
							)
						)
					)
					(number "15"
						(effects
							(font
								(size 1.27 1.27)
							)
						)
					)
				)
				(pin passive line
					(at 0 -55.88 0)
					(length 3.81)
					(hide yes)
					(name "VSS"
						(effects
							(font
								(size 1.27 1.27)
							)
						)
					)
					(number "151"
						(effects
							(font
								(size 1.27 1.27)
							)
						)
					)
				)
				(pin passive line
					(at 0 -55.88 0)
					(length 3.81)
					(hide yes)
					(name "VSS"
						(effects
							(font
								(size 1.27 1.27)
							)
						)
					)
					(number "153"
						(effects
							(font
								(size 1.27 1.27)
							)
						)
					)
				)
				(pin passive line
					(at 0 -55.88 0)
					(length 3.81)
					(hide yes)
					(name "VSS"
						(effects
							(font
								(size 1.27 1.27)
							)
						)
					)
					(number "155"
						(effects
							(font
								(size 1.27 1.27)
							)
						)
					)
				)
				(pin passive line
					(at 0 -55.88 0)
					(length 3.81)
					(hide yes)
					(name "VSS"
						(effects
							(font
								(size 1.27 1.27)
							)
						)
					)
					(number "158"
						(effects
							(font
								(size 1.27 1.27)
							)
						)
					)
				)
				(pin passive line
					(at 0 -55.88 0)
					(length 3.81)
					(hide yes)
					(name "VSS"
						(effects
							(font
								(size 1.27 1.27)
							)
						)
					)
					(number "160"
						(effects
							(font
								(size 1.27 1.27)
							)
						)
					)
				)
				(pin passive line
					(at 0 -55.88 0)
					(length 3.81)
					(hide yes)
					(name "VSS"
						(effects
							(font
								(size 1.27 1.27)
							)
						)
					)
					(number "162"
						(effects
							(font
								(size 1.27 1.27)
							)
						)
					)
				)
				(pin passive line
					(at 0 -55.88 0)
					(length 3.81)
					(hide yes)
					(name "VSS"
						(effects
							(font
								(size 1.27 1.27)
							)
						)
					)
					(number "164"
						(effects
							(font
								(size 1.27 1.27)
							)
						)
					)
				)
				(pin passive line
					(at 0 -55.88 0)
					(length 3.81)
					(hide yes)
					(name "VSS"
						(effects
							(font
								(size 1.27 1.27)
							)
						)
					)
					(number "166"
						(effects
							(font
								(size 1.27 1.27)
							)
						)
					)
				)
				(pin passive line
					(at 0 -55.88 0)
					(length 3.81)
					(hide yes)
					(name "VSS"
						(effects
							(font
								(size 1.27 1.27)
							)
						)
					)
					(number "169"
						(effects
							(font
								(size 1.27 1.27)
							)
						)
					)
				)
				(pin passive line
					(at 0 -55.88 0)
					(length 3.81)
					(hide yes)
					(name "VSS"
						(effects
							(font
								(size 1.27 1.27)
							)
						)
					)
					(number "17"
						(effects
							(font
								(size 1.27 1.27)
							)
						)
					)
				)
				(pin passive line
					(at 0 -55.88 0)
					(length 3.81)
					(hide yes)
					(name "VSS"
						(effects
							(font
								(size 1.27 1.27)
							)
						)
					)
					(number "171"
						(effects
							(font
								(size 1.27 1.27)
							)
						)
					)
				)
				(pin passive line
					(at 0 -55.88 0)
					(length 3.81)
					(hide yes)
					(name "VSS"
						(effects
							(font
								(size 1.27 1.27)
							)
						)
					)
					(number "173"
						(effects
							(font
								(size 1.27 1.27)
							)
						)
					)
				)
				(pin passive line
					(at 0 -55.88 0)
					(length 3.81)
					(hide yes)
					(name "VSS"
						(effects
							(font
								(size 1.27 1.27)
							)
						)
					)
					(number "175"
						(effects
							(font
								(size 1.27 1.27)
							)
						)
					)
				)
				(pin passive line
					(at 0 -55.88 0)
					(length 3.81)
					(hide yes)
					(name "VSS"
						(effects
							(font
								(size 1.27 1.27)
							)
						)
					)
					(number "177"
						(effects
							(font
								(size 1.27 1.27)
							)
						)
					)
				)
				(pin passive line
					(at 0 -55.88 0)
					(length 3.81)
					(hide yes)
					(name "VSS"
						(effects
							(font
								(size 1.27 1.27)
							)
						)
					)
					(number "180"
						(effects
							(font
								(size 1.27 1.27)
							)
						)
					)
				)
				(pin passive line
					(at 0 -55.88 0)
					(length 3.81)
					(hide yes)
					(name "VSS"
						(effects
							(font
								(size 1.27 1.27)
							)
						)
					)
					(number "182"
						(effects
							(font
								(size 1.27 1.27)
							)
						)
					)
				)
				(pin passive line
					(at 0 -55.88 0)
					(length 3.81)
					(hide yes)
					(name "VSS"
						(effects
							(font
								(size 1.27 1.27)
							)
						)
					)
					(number "184"
						(effects
							(font
								(size 1.27 1.27)
							)
						)
					)
				)
				(pin passive line
					(at 0 -55.88 0)
					(length 3.81)
					(hide yes)
					(name "VSS"
						(effects
							(font
								(size 1.27 1.27)
							)
						)
					)
					(number "186"
						(effects
							(font
								(size 1.27 1.27)
							)
						)
					)
				)
				(pin passive line
					(at 0 -55.88 0)
					(length 3.81)
					(hide yes)
					(name "VSS"
						(effects
							(font
								(size 1.27 1.27)
							)
						)
					)
					(number "188"
						(effects
							(font
								(size 1.27 1.27)
							)
						)
					)
				)
				(pin passive line
					(at 0 -55.88 0)
					(length 3.81)
					(hide yes)
					(name "VSS"
						(effects
							(font
								(size 1.27 1.27)
							)
						)
					)
					(number "19"
						(effects
							(font
								(size 1.27 1.27)
							)
						)
					)
				)
				(pin passive line
					(at 0 -55.88 0)
					(length 3.81)
					(hide yes)
					(name "VSS"
						(effects
							(font
								(size 1.27 1.27)
							)
						)
					)
					(number "191"
						(effects
							(font
								(size 1.27 1.27)
							)
						)
					)
				)
				(pin passive line
					(at 0 -55.88 0)
					(length 3.81)
					(hide yes)
					(name "VSS"
						(effects
							(font
								(size 1.27 1.27)
							)
						)
					)
					(number "193"
						(effects
							(font
								(size 1.27 1.27)
							)
						)
					)
				)
				(pin passive line
					(at 0 -55.88 0)
					(length 3.81)
					(hide yes)
					(name "VSS"
						(effects
							(font
								(size 1.27 1.27)
							)
						)
					)
					(number "195"
						(effects
							(font
								(size 1.27 1.27)
							)
						)
					)
				)
				(pin passive line
					(at 0 -55.88 0)
					(length 3.81)
					(hide yes)
					(name "VSS"
						(effects
							(font
								(size 1.27 1.27)
							)
						)
					)
					(number "197"
						(effects
							(font
								(size 1.27 1.27)
							)
						)
					)
				)
				(pin passive line
					(at 0 -55.88 0)
					(length 3.81)
					(hide yes)
					(name "VSS"
						(effects
							(font
								(size 1.27 1.27)
							)
						)
					)
					(number "199"
						(effects
							(font
								(size 1.27 1.27)
							)
						)
					)
				)
				(pin passive line
					(at 0 -55.88 0)
					(length 3.81)
					(hide yes)
					(name "VSS"
						(effects
							(font
								(size 1.27 1.27)
							)
						)
					)
					(number "202"
						(effects
							(font
								(size 1.27 1.27)
							)
						)
					)
				)
				(pin passive line
					(at 0 -55.88 0)
					(length 3.81)
					(hide yes)
					(name "VSS"
						(effects
							(font
								(size 1.27 1.27)
							)
						)
					)
					(number "204"
						(effects
							(font
								(size 1.27 1.27)
							)
						)
					)
				)
				(pin passive line
					(at 0 -55.88 0)
					(length 3.81)
					(hide yes)
					(name "VSS"
						(effects
							(font
								(size 1.27 1.27)
							)
						)
					)
					(number "206"
						(effects
							(font
								(size 1.27 1.27)
							)
						)
					)
				)
				(pin passive line
					(at 0 -55.88 0)
					(length 3.81)
					(hide yes)
					(name "VSS"
						(effects
							(font
								(size 1.27 1.27)
							)
						)
					)
					(number "208"
						(effects
							(font
								(size 1.27 1.27)
							)
						)
					)
				)
				(pin passive line
					(at 0 -55.88 0)
					(length 3.81)
					(hide yes)
					(name "VSS"
						(effects
							(font
								(size 1.27 1.27)
							)
						)
					)
					(number "21"
						(effects
							(font
								(size 1.27 1.27)
							)
						)
					)
				)
				(pin passive line
					(at 0 -55.88 0)
					(length 3.81)
					(hide yes)
					(name "VSS"
						(effects
							(font
								(size 1.27 1.27)
							)
						)
					)
					(number "210"
						(effects
							(font
								(size 1.27 1.27)
							)
						)
					)
				)
				(pin passive line
					(at 0 -55.88 0)
					(length 3.81)
					(hide yes)
					(name "VSS"
						(effects
							(font
								(size 1.27 1.27)
							)
						)
					)
					(number "212"
						(effects
							(font
								(size 1.27 1.27)
							)
						)
					)
				)
				(pin passive line
					(at 0 -55.88 0)
					(length 3.81)
					(hide yes)
					(name "VSS"
						(effects
							(font
								(size 1.27 1.27)
							)
						)
					)
					(number "214"
						(effects
							(font
								(size 1.27 1.27)
							)
						)
					)
				)
				(pin passive line
					(at 0 -55.88 0)
					(length 3.81)
					(hide yes)
					(name "VSS"
						(effects
							(font
								(size 1.27 1.27)
							)
						)
					)
					(number "216"
						(effects
							(font
								(size 1.27 1.27)
							)
						)
					)
				)
				(pin passive line
					(at 0 -55.88 0)
					(length 3.81)
					(hide yes)
					(name "VSS"
						(effects
							(font
								(size 1.27 1.27)
							)
						)
					)
					(number "219"
						(effects
							(font
								(size 1.27 1.27)
							)
						)
					)
				)
				(pin passive line
					(at 0 -55.88 0)
					(length 3.81)
					(hide yes)
					(name "VSS"
						(effects
							(font
								(size 1.27 1.27)
							)
						)
					)
					(number "222"
						(effects
							(font
								(size 1.27 1.27)
							)
						)
					)
				)
				(pin passive line
					(at 0 -55.88 0)
					(length 3.81)
					(hide yes)
					(name "VSS"
						(effects
							(font
								(size 1.27 1.27)
							)
						)
					)
					(number "224"
						(effects
							(font
								(size 1.27 1.27)
							)
						)
					)
				)
				(pin passive line
					(at 0 -55.88 0)
					(length 3.81)
					(hide yes)
					(name "VSS"
						(effects
							(font
								(size 1.27 1.27)
							)
						)
					)
					(number "226"
						(effects
							(font
								(size 1.27 1.27)
							)
						)
					)
				)
				(pin passive line
					(at 0 -55.88 0)
					(length 3.81)
					(hide yes)
					(name "VSS"
						(effects
							(font
								(size 1.27 1.27)
							)
						)
					)
					(number "228"
						(effects
							(font
								(size 1.27 1.27)
							)
						)
					)
				)
				(pin passive line
					(at 0 -55.88 0)
					(length 3.81)
					(hide yes)
					(name "VSS"
						(effects
							(font
								(size 1.27 1.27)
							)
						)
					)
					(number "230"
						(effects
							(font
								(size 1.27 1.27)
							)
						)
					)
				)
				(pin passive line
					(at 0 -55.88 0)
					(length 3.81)
					(hide yes)
					(name "VSS"
						(effects
							(font
								(size 1.27 1.27)
							)
						)
					)
					(number "233"
						(effects
							(font
								(size 1.27 1.27)
							)
						)
					)
				)
				(pin passive line
					(at 0 -55.88 0)
					(length 3.81)
					(hide yes)
					(name "VSS"
						(effects
							(font
								(size 1.27 1.27)
							)
						)
					)
					(number "235"
						(effects
							(font
								(size 1.27 1.27)
							)
						)
					)
				)
				(pin passive line
					(at 0 -55.88 0)
					(length 3.81)
					(hide yes)
					(name "VSS"
						(effects
							(font
								(size 1.27 1.27)
							)
						)
					)
					(number "237"
						(effects
							(font
								(size 1.27 1.27)
							)
						)
					)
				)
				(pin passive line
					(at 0 -55.88 0)
					(length 3.81)
					(hide yes)
					(name "VSS"
						(effects
							(font
								(size 1.27 1.27)
							)
						)
					)
					(number "24"
						(effects
							(font
								(size 1.27 1.27)
							)
						)
					)
				)
				(pin passive line
					(at 0 -55.88 0)
					(length 3.81)
					(hide yes)
					(name "VSS"
						(effects
							(font
								(size 1.27 1.27)
							)
						)
					)
					(number "240"
						(effects
							(font
								(size 1.27 1.27)
							)
						)
					)
				)
				(pin passive line
					(at 0 -55.88 0)
					(length 3.81)
					(hide yes)
					(name "VSS"
						(effects
							(font
								(size 1.27 1.27)
							)
						)
					)
					(number "242"
						(effects
							(font
								(size 1.27 1.27)
							)
						)
					)
				)
				(pin passive line
					(at 0 -55.88 0)
					(length 3.81)
					(hide yes)
					(name "VSS"
						(effects
							(font
								(size 1.27 1.27)
							)
						)
					)
					(number "244"
						(effects
							(font
								(size 1.27 1.27)
							)
						)
					)
				)
				(pin passive line
					(at 0 -55.88 0)
					(length 3.81)
					(hide yes)
					(name "VSS"
						(effects
							(font
								(size 1.27 1.27)
							)
						)
					)
					(number "246"
						(effects
							(font
								(size 1.27 1.27)
							)
						)
					)
				)
				(pin passive line
					(at 0 -55.88 0)
					(length 3.81)
					(hide yes)
					(name "VSS"
						(effects
							(font
								(size 1.27 1.27)
							)
						)
					)
					(number "248"
						(effects
							(font
								(size 1.27 1.27)
							)
						)
					)
				)
				(pin passive line
					(at 0 -55.88 0)
					(length 3.81)
					(hide yes)
					(name "VSS"
						(effects
							(font
								(size 1.27 1.27)
							)
						)
					)
					(number "251"
						(effects
							(font
								(size 1.27 1.27)
							)
						)
					)
				)
				(pin passive line
					(at 0 -55.88 0)
					(length 3.81)
					(hide yes)
					(name "VSS"
						(effects
							(font
								(size 1.27 1.27)
							)
						)
					)
					(number "253"
						(effects
							(font
								(size 1.27 1.27)
							)
						)
					)
				)
				(pin passive line
					(at 0 -55.88 0)
					(length 3.81)
					(hide yes)
					(name "VSS"
						(effects
							(font
								(size 1.27 1.27)
							)
						)
					)
					(number "255"
						(effects
							(font
								(size 1.27 1.27)
							)
						)
					)
				)
				(pin passive line
					(at 0 -55.88 0)
					(length 3.81)
					(hide yes)
					(name "VSS"
						(effects
							(font
								(size 1.27 1.27)
							)
						)
					)
					(number "257"
						(effects
							(font
								(size 1.27 1.27)
							)
						)
					)
				)
				(pin passive line
					(at 0 -55.88 0)
					(length 3.81)
					(hide yes)
					(name "VSS"
						(effects
							(font
								(size 1.27 1.27)
							)
						)
					)
					(number "259"
						(effects
							(font
								(size 1.27 1.27)
							)
						)
					)
				)
				(pin passive line
					(at 0 -55.88 0)
					(length 3.81)
					(hide yes)
					(name "VSS"
						(effects
							(font
								(size 1.27 1.27)
							)
						)
					)
					(number "26"
						(effects
							(font
								(size 1.27 1.27)
							)
						)
					)
				)
				(pin passive line
					(at 0 -55.88 0)
					(length 3.81)
					(hide yes)
					(name "VSS"
						(effects
							(font
								(size 1.27 1.27)
							)
						)
					)
					(number "262"
						(effects
							(font
								(size 1.27 1.27)
							)
						)
					)
				)
				(pin passive line
					(at 0 -55.88 0)
					(length 3.81)
					(hide yes)
					(name "VSS"
						(effects
							(font
								(size 1.27 1.27)
							)
						)
					)
					(number "264"
						(effects
							(font
								(size 1.27 1.27)
							)
						)
					)
				)
				(pin passive line
					(at 0 -55.88 0)
					(length 3.81)
					(hide yes)
					(name "VSS"
						(effects
							(font
								(size 1.27 1.27)
							)
						)
					)
					(number "266"
						(effects
							(font
								(size 1.27 1.27)
							)
						)
					)
				)
				(pin passive line
					(at 0 -55.88 0)
					(length 3.81)
					(hide yes)
					(name "VSS"
						(effects
							(font
								(size 1.27 1.27)
							)
						)
					)
					(number "268"
						(effects
							(font
								(size 1.27 1.27)
							)
						)
					)
				)
				(pin passive line
					(at 0 -55.88 0)
					(length 3.81)
					(hide yes)
					(name "VSS"
						(effects
							(font
								(size 1.27 1.27)
							)
						)
					)
					(number "270"
						(effects
							(font
								(size 1.27 1.27)
							)
						)
					)
				)
				(pin passive line
					(at 0 -55.88 0)
					(length 3.81)
					(hide yes)
					(name "VSS"
						(effects
							(font
								(size 1.27 1.27)
							)
						)
					)
					(number "273"
						(effects
							(font
								(size 1.27 1.27)
							)
						)
					)
				)
				(pin passive line
					(at 0 -55.88 0)
					(length 3.81)
					(hide yes)
					(name "VSS"
						(effects
							(font
								(size 1.27 1.27)
							)
						)
					)
					(number "275"
						(effects
							(font
								(size 1.27 1.27)
							)
						)
					)
				)
				(pin passive line
					(at 0 -55.88 0)
					(length 3.81)
					(hide yes)
					(name "VSS"
						(effects
							(font
								(size 1.27 1.27)
							)
						)
					)
					(number "277"
						(effects
							(font
								(size 1.27 1.27)
							)
						)
					)
				)
				(pin passive line
					(at 0 -55.88 0)
					(length 3.81)
					(hide yes)
					(name "VSS"
						(effects
							(font
								(size 1.27 1.27)
							)
						)
					)
					(number "279"
						(effects
							(font
								(size 1.27 1.27)
							)
						)
					)
				)
				(pin passive line
					(at 0 -55.88 0)
					(length 3.81)
					(hide yes)
					(name "VSS"
						(effects
							(font
								(size 1.27 1.27)
							)
						)
					)
					(number "28"
						(effects
							(font
								(size 1.27 1.27)
							)
						)
					)
				)
				(pin passive line
					(at 0 -55.88 0)
					(length 3.81)
					(hide yes)
					(name "VSS"
						(effects
							(font
								(size 1.27 1.27)
							)
						)
					)
					(number "281"
						(effects
							(font
								(size 1.27 1.27)
							)
						)
					)
				)
				(pin passive line
					(at 0 -55.88 0)
					(length 3.81)
					(hide yes)
					(name "VSS"
						(effects
							(font
								(size 1.27 1.27)
							)
						)
					)
					(number "284"
						(effects
							(font
								(size 1.27 1.27)
							)
						)
					)
				)
				(pin passive line
					(at 0 -55.88 0)
					(length 3.81)
					(hide yes)
					(name "VSS"
						(effects
							(font
								(size 1.27 1.27)
							)
						)
					)
					(number "286"
						(effects
							(font
								(size 1.27 1.27)
							)
						)
					)
				)
				(pin passive line
					(at 0 -55.88 0)
					(length 3.81)
					(hide yes)
					(name "VSS"
						(effects
							(font
								(size 1.27 1.27)
							)
						)
					)
					(number "288"
						(effects
							(font
								(size 1.27 1.27)
							)
						)
					)
				)
				(pin passive line
					(at 0 -55.88 0)
					(length 3.81)
					(hide yes)
					(name "VSS"
						(effects
							(font
								(size 1.27 1.27)
							)
						)
					)
					(number "30"
						(effects
							(font
								(size 1.27 1.27)
							)
						)
					)
				)
				(pin passive line
					(at 0 -55.88 0)
					(length 3.81)
					(hide yes)
					(name "VSS"
						(effects
							(font
								(size 1.27 1.27)
							)
						)
					)
					(number "32"
						(effects
							(font
								(size 1.27 1.27)
							)
						)
					)
				)
				(pin passive line
					(at 0 -55.88 0)
					(length 3.81)
					(hide yes)
					(name "VSS"
						(effects
							(font
								(size 1.27 1.27)
							)
						)
					)
					(number "35"
						(effects
							(font
								(size 1.27 1.27)
							)
						)
					)
				)
				(pin passive line
					(at 0 -55.88 0)
					(length 3.81)
					(hide yes)
					(name "VSS"
						(effects
							(font
								(size 1.27 1.27)
							)
						)
					)
					(number "37"
						(effects
							(font
								(size 1.27 1.27)
							)
						)
					)
				)
				(pin passive line
					(at 0 -55.88 0)
					(length 3.81)
					(hide yes)
					(name "VSS"
						(effects
							(font
								(size 1.27 1.27)
							)
						)
					)
					(number "39"
						(effects
							(font
								(size 1.27 1.27)
							)
						)
					)
				)
				(pin passive line
					(at 0 -55.88 0)
					(length 3.81)
					(hide yes)
					(name "VSS"
						(effects
							(font
								(size 1.27 1.27)
							)
						)
					)
					(number "41"
						(effects
							(font
								(size 1.27 1.27)
							)
						)
					)
				)
				(pin passive line
					(at 0 -55.88 0)
					(length 3.81)
					(hide yes)
					(name "VSS"
						(effects
							(font
								(size 1.27 1.27)
							)
						)
					)
					(number "43"
						(effects
							(font
								(size 1.27 1.27)
							)
						)
					)
				)
				(pin passive line
					(at 0 -55.88 0)
					(length 3.81)
					(hide yes)
					(name "VSS"
						(effects
							(font
								(size 1.27 1.27)
							)
						)
					)
					(number "46"
						(effects
							(font
								(size 1.27 1.27)
							)
						)
					)
				)
				(pin passive line
					(at 0 -55.88 0)
					(length 3.81)
					(hide yes)
					(name "VSS"
						(effects
							(font
								(size 1.27 1.27)
							)
						)
					)
					(number "48"
						(effects
							(font
								(size 1.27 1.27)
							)
						)
					)
				)
				(pin passive line
					(at 0 -55.88 0)
					(length 3.81)
					(hide yes)
					(name "VSS"
						(effects
							(font
								(size 1.27 1.27)
							)
						)
					)
					(number "50"
						(effects
							(font
								(size 1.27 1.27)
							)
						)
					)
				)
				(pin passive line
					(at 0 -55.88 0)
					(length 3.81)
					(hide yes)
					(name "VSS"
						(effects
							(font
								(size 1.27 1.27)
							)
						)
					)
					(number "52"
						(effects
							(font
								(size 1.27 1.27)
							)
						)
					)
				)
				(pin passive line
					(at 0 -55.88 0)
					(length 3.81)
					(hide yes)
					(name "VSS"
						(effects
							(font
								(size 1.27 1.27)
							)
						)
					)
					(number "54"
						(effects
							(font
								(size 1.27 1.27)
							)
						)
					)
				)
				(pin passive line
					(at 0 -55.88 0)
					(length 3.81)
					(hide yes)
					(name "VSS"
						(effects
							(font
								(size 1.27 1.27)
							)
						)
					)
					(number "57"
						(effects
							(font
								(size 1.27 1.27)
							)
						)
					)
				)
				(pin passive line
					(at 0 -55.88 0)
					(length 3.81)
					(hide yes)
					(name "VSS"
						(effects
							(font
								(size 1.27 1.27)
							)
						)
					)
					(number "59"
						(effects
							(font
								(size 1.27 1.27)
							)
						)
					)
				)
				(pin passive line
					(at 0 -55.88 0)
					(length 3.81)
					(hide yes)
					(name "VSS"
						(effects
							(font
								(size 1.27 1.27)
							)
						)
					)
					(number "6"
						(effects
							(font
								(size 1.27 1.27)
							)
						)
					)
				)
				(pin passive line
					(at 0 -55.88 0)
					(length 3.81)
					(hide yes)
					(name "VSS"
						(effects
							(font
								(size 1.27 1.27)
							)
						)
					)
					(number "61"
						(effects
							(font
								(size 1.27 1.27)
							)
						)
					)
				)
				(pin passive line
					(at 0 -55.88 0)
					(length 3.81)
					(hide yes)
					(name "VSS"
						(effects
							(font
								(size 1.27 1.27)
							)
						)
					)
					(number "63"
						(effects
							(font
								(size 1.27 1.27)
							)
						)
					)
				)
				(pin passive line
					(at 0 -55.88 0)
					(length 3.81)
					(hide yes)
					(name "VSS"
						(effects
							(font
								(size 1.27 1.27)
							)
						)
					)
					(number "65"
						(effects
							(font
								(size 1.27 1.27)
							)
						)
					)
				)
				(pin passive line
					(at 0 -55.88 0)
					(length 3.81)
					(hide yes)
					(name "VSS"
						(effects
							(font
								(size 1.27 1.27)
							)
						)
					)
					(number "67"
						(effects
							(font
								(size 1.27 1.27)
							)
						)
					)
				)
				(pin passive line
					(at 0 -55.88 0)
					(length 3.81)
					(hide yes)
					(name "VSS"
						(effects
							(font
								(size 1.27 1.27)
							)
						)
					)
					(number "69"
						(effects
							(font
								(size 1.27 1.27)
							)
						)
					)
				)
				(pin passive line
					(at 0 -55.88 0)
					(length 3.81)
					(hide yes)
					(name "VSS"
						(effects
							(font
								(size 1.27 1.27)
							)
						)
					)
					(number "71"
						(effects
							(font
								(size 1.27 1.27)
							)
						)
					)
				)
				(pin passive line
					(at 0 -55.88 0)
					(length 3.81)
					(hide yes)
					(name "VSS"
						(effects
							(font
								(size 1.27 1.27)
							)
						)
					)
					(number "73"
						(effects
							(font
								(size 1.27 1.27)
							)
						)
					)
				)
				(pin passive line
					(at 0 -55.88 0)
					(length 3.81)
					(hide yes)
					(name "VSS"
						(effects
							(font
								(size 1.27 1.27)
							)
						)
					)
					(number "77"
						(effects
							(font
								(size 1.27 1.27)
							)
						)
					)
				)
				(pin passive line
					(at 0 -55.88 0)
					(length 3.81)
					(hide yes)
					(name "VSS"
						(effects
							(font
								(size 1.27 1.27)
							)
						)
					)
					(number "79"
						(effects
							(font
								(size 1.27 1.27)
							)
						)
					)
				)
				(pin passive line
					(at 0 -55.88 0)
					(length 3.81)
					(hide yes)
					(name "VSS"
						(effects
							(font
								(size 1.27 1.27)
							)
						)
					)
					(number "8"
						(effects
							(font
								(size 1.27 1.27)
							)
						)
					)
				)
				(pin passive line
					(at 0 -55.88 0)
					(length 3.81)
					(hide yes)
					(name "VSS"
						(effects
							(font
								(size 1.27 1.27)
							)
						)
					)
					(number "81"
						(effects
							(font
								(size 1.27 1.27)
							)
						)
					)
				)
				(pin passive line
					(at 0 -55.88 0)
					(length 3.81)
					(hide yes)
					(name "VSS"
						(effects
							(font
								(size 1.27 1.27)
							)
						)
					)
					(number "83"
						(effects
							(font
								(size 1.27 1.27)
							)
						)
					)
				)
				(pin passive line
					(at 0 -55.88 0)
					(length 3.81)
					(hide yes)
					(name "VSS"
						(effects
							(font
								(size 1.27 1.27)
							)
						)
					)
					(number "85"
						(effects
							(font
								(size 1.27 1.27)
							)
						)
					)
				)
				(pin passive line
					(at 0 -55.88 0)
					(length 3.81)
					(hide yes)
					(name "VSS"
						(effects
							(font
								(size 1.27 1.27)
							)
						)
					)
					(number "88"
						(effects
							(font
								(size 1.27 1.27)
							)
						)
					)
				)
				(pin passive line
					(at 0 -55.88 0)
					(length 3.81)
					(hide yes)
					(name "VSS"
						(effects
							(font
								(size 1.27 1.27)
							)
						)
					)
					(number "90"
						(effects
							(font
								(size 1.27 1.27)
							)
						)
					)
				)
				(pin passive line
					(at 0 -55.88 0)
					(length 3.81)
					(hide yes)
					(name "VSS"
						(effects
							(font
								(size 1.27 1.27)
							)
						)
					)
					(number "92"
						(effects
							(font
								(size 1.27 1.27)
							)
						)
					)
				)
				(pin passive line
					(at 0 -55.88 0)
					(length 3.81)
					(hide yes)
					(name "VSS"
						(effects
							(font
								(size 1.27 1.27)
							)
						)
					)
					(number "95"
						(effects
							(font
								(size 1.27 1.27)
							)
						)
					)
				)
				(pin passive line
					(at 0 -55.88 0)
					(length 3.81)
					(hide yes)
					(name "VSS"
						(effects
							(font
								(size 1.27 1.27)
							)
						)
					)
					(number "97"
						(effects
							(font
								(size 1.27 1.27)
							)
						)
					)
				)
				(pin passive line
					(at 0 -55.88 0)
					(length 3.81)
					(hide yes)
					(name "VSS"
						(effects
							(font
								(size 1.27 1.27)
							)
						)
					)
					(number "99"
						(effects
							(font
								(size 1.27 1.27)
							)
						)
					)
				)
				(pin no_connect line
					(at 3.81 -45.72 0)
					(length 3.81)
					(hide yes)
					(name "RFU"
						(effects
							(font
								(size 1.27 1.27)
							)
						)
					)
					(number "150"
						(effects
							(font
								(size 1.27 1.27)
							)
						)
					)
				)
				(pin no_connect line
					(at 3.81 -48.26 0)
					(length 3.81)
					(hide yes)
					(name "RFU"
						(effects
							(font
								(size 1.27 1.27)
							)
						)
					)
					(number "2"
						(effects
							(font
								(size 1.27 1.27)
							)
						)
					)
				)
				(pin no_connect line
					(at 3.81 -50.8 0)
					(length 3.81)
					(hide yes)
					(name "RFU"
						(effects
							(font
								(size 1.27 1.27)
							)
						)
					)
					(number "144"
						(effects
							(font
								(size 1.27 1.27)
							)
						)
					)
				)
				(pin no_connect line
					(at 26.67 -45.72 180)
					(length 3.81)
					(hide yes)
					(name "RFU"
						(effects
							(font
								(size 1.27 1.27)
							)
						)
					)
					(number "149"
						(effects
							(font
								(size 1.27 1.27)
							)
						)
					)
				)
				(pin no_connect line
					(at 26.67 -48.26 180)
					(length 3.81)
					(hide yes)
					(name "RFU"
						(effects
							(font
								(size 1.27 1.27)
							)
						)
					)
					(number "232"
						(effects
							(font
								(size 1.27 1.27)
							)
						)
					)
				)
				(pin no_connect line
					(at 26.67 -50.8 180)
					(length 3.81)
					(hide yes)
					(name "RFU"
						(effects
							(font
								(size 1.27 1.27)
							)
						)
					)
					(number "220"
						(effects
							(font
								(size 1.27 1.27)
							)
						)
					)
				)
				(pin no_connect line
					(at 26.67 -53.34 180)
					(length 3.81)
					(hide yes)
					(name "RFU"
						(effects
							(font
								(size 1.27 1.27)
							)
						)
					)
					(number "231"
						(effects
							(font
								(size 1.27 1.27)
							)
						)
					)
				)
				(pin input line
					(at 30.48 0 180)
					(length 3.81)
					(name "HSA"
						(effects
							(font
								(size 1.27 1.27)
							)
						)
					)
					(number "148"
						(effects
							(font
								(size 1.27 1.27)
							)
						)
					)
				)
				(pin input line
					(at 30.48 -2.54 180)
					(length 3.81)
					(name "HSDA"
						(effects
							(font
								(size 1.27 1.27)
							)
						)
					)
					(number "5"
						(effects
							(font
								(size 1.27 1.27)
							)
						)
					)
				)
				(pin input line
					(at 30.48 -5.08 180)
					(length 3.81)
					(name "HSCL"
						(effects
							(font
								(size 1.27 1.27)
							)
						)
					)
					(number "4"
						(effects
							(font
								(size 1.27 1.27)
							)
						)
					)
				)
				(pin input line
					(at 30.48 -10.16 180)
					(length 3.81)
					(name "ALERT_N"
						(effects
							(font
								(size 1.27 1.27)
							)
						)
					)
					(number "62"
						(effects
							(font
								(size 1.27 1.27)
							)
						)
					)
				)
				(pin input line
					(at 30.48 -12.7 180)
					(length 3.81)
					(name "CK_T"
						(effects
							(font
								(size 1.27 1.27)
							)
						)
					)
					(number "217"
						(effects
							(font
								(size 1.27 1.27)
							)
						)
					)
				)
				(pin input line
					(at 30.48 -15.24 180)
					(length 3.81)
					(name "CK_C"
						(effects
							(font
								(size 1.27 1.27)
							)
						)
					)
					(number "218"
						(effects
							(font
								(size 1.27 1.27)
							)
						)
					)
				)
				(pin input line
					(at 30.48 -20.32 180)
					(length 3.81)
					(name "CA0_B"
						(effects
							(font
								(size 1.27 1.27)
							)
						)
					)
					(number "76"
						(effects
							(font
								(size 1.27 1.27)
							)
						)
					)
				)
				(pin input line
					(at 30.48 -22.86 180)
					(length 3.81)
					(name "CA1_B"
						(effects
							(font
								(size 1.27 1.27)
							)
						)
					)
					(number "221"
						(effects
							(font
								(size 1.27 1.27)
							)
						)
					)
				)
				(pin input line
					(at 30.48 -25.4 180)
					(length 3.81)
					(name "CA2_B"
						(effects
							(font
								(size 1.27 1.27)
							)
						)
					)
					(number "78"
						(effects
							(font
								(size 1.27 1.27)
							)
						)
					)
				)
				(pin input line
					(at 30.48 -27.94 180)
					(length 3.81)
					(name "CA3_B"
						(effects
							(font
								(size 1.27 1.27)
							)
						)
					)
					(number "223"
						(effects
							(font
								(size 1.27 1.27)
							)
						)
					)
				)
				(pin input line
					(at 30.48 -30.48 180)
					(length 3.81)
					(name "CA4_B"
						(effects
							(font
								(size 1.27 1.27)
							)
						)
					)
					(number "80"
						(effects
							(font
								(size 1.27 1.27)
							)
						)
					)
				)
				(pin input line
					(at 30.48 -33.02 180)
					(length 3.81)
					(name "CA5_B"
						(effects
							(font
								(size 1.27 1.27)
							)
						)
					)
					(number "225"
						(effects
							(font
								(size 1.27 1.27)
							)
						)
					)
				)
				(pin input line
					(at 30.48 -35.56 180)
					(length 3.81)
					(name "CA6_B"
						(effects
							(font
								(size 1.27 1.27)
							)
						)
					)
					(number "82"
						(effects
							(font
								(size 1.27 1.27)
							)
						)
					)
				)
				(pin input line
					(at 30.48 -38.1 180)
					(length 3.81)
					(name "PAR_B"
						(effects
							(font
								(size 1.27 1.27)
							)
						)
					)
					(number "227"
						(effects
							(font
								(size 1.27 1.27)
							)
						)
					)
				)
				(pin input line
					(at 30.48 -40.64 180)
					(length 3.81)
					(name "CS0_B_N"
						(effects
							(font
								(size 1.27 1.27)
							)
						)
					)
					(number "84"
						(effects
							(font
								(size 1.27 1.27)
							)
						)
					)
				)
				(pin input line
					(at 30.48 -43.18 180)
					(length 3.81)
					(name "CS1_B_N"
						(effects
							(font
								(size 1.27 1.27)
							)
						)
					)
					(number "229"
						(effects
							(font
								(size 1.27 1.27)
							)
						)
					)
				)
				(pin passive line
					(at 30.48 -55.88 180)
					(length 3.81)
					(name "SH"
						(effects
							(font
								(size 1.27 1.27)
							)
						)
					)
					(number "S1"
						(effects
							(font
								(size 1.27 1.27)
							)
						)
					)
				)
				(pin passive line
					(at 30.48 -58.42 180)
					(length 3.81)
					(name "SH"
						(effects
							(font
								(size 1.27 1.27)
							)
						)
					)
					(number "S2"
						(effects
							(font
								(size 1.27 1.27)
							)
						)
					)
				)
				(pin passive line
					(at 30.48 -60.96 180)
					(length 3.81)
					(name "SH"
						(effects
							(font
								(size 1.27 1.27)
							)
						)
					)
					(number "S3"
						(effects
							(font
								(size 1.27 1.27)
							)
						)
					)
				)
			)
		)
	(symbol "antmicroMemoryConnectorsPCCardSockets:Bus_DDR5_DDR504111002KQ_CUSTOM_1xDetectPin"
			(exclude_from_sim no)
			(in_bom yes)
			(on_board yes)
			(property "Reference" "J"
				(at 45.72 -2.54 0)
				(effects
					(font
						(size 1.27 1.27)
						(thickness 0.15)
					)
					(justify left bottom)
				)
			)
			(property "Value" "Bus_DDR5_DDR504111002KQ_CUSTOM_1xDetectPin"
				(at 45.72 -5.08 0)
				(effects
					(font
						(size 1.27 1.27)
						(thickness 0.15)
					)
					(justify left bottom)
					(hide yes)
				)
			)
			(property "Footprint" "antmicro-footprints:Bus_DDR5_Socket_Amphenol_DDR504111002KQ"
				(at 45.72 -7.62 0)
				(effects
					(font
						(size 1.27 1.27)
						(thickness 0.15)
					)
					(justify left bottom)
					(hide yes)
				)
			)
			(property "Datasheet" "https://www.amphenol-icc.com/ddr5-smt-ddr504111002kq.html"
				(at 45.72 -10.16 0)
				(effects
					(font
						(size 1.27 1.27)
						(thickness 0.15)
					)
					(justify left bottom)
					(hide yes)
				)
			)
			(property "Description" "Memory Card Connector, DDR5 DIMM, Latched, 288 Contacts, Copper Alloy, Gold Plated Contacts"
				(at 0 0 0)
				(effects
					(font
						(size 1.27 1.27)
					)
					(hide yes)
				)
			)
			(property "Manufacturer" "Amphenol"
				(at 45.72 -12.7 0)
				(effects
					(font
						(size 1.27 1.27)
						(thickness 0.15)
					)
					(justify left bottom)
					(hide yes)
				)
			)
			(property "MPN" "DDR504111002KQ"
				(at 45.72 -15.24 0)
				(effects
					(font
						(size 1.27 1.27)
						(thickness 0.15)
					)
					(justify left bottom)
				)
			)
			(property "Author" "Antmicro"
				(at 45.72 -17.78 0)
				(effects
					(font
						(size 1.27 1.27)
						(thickness 0.15)
					)
					(justify left bottom)
					(hide yes)
				)
			)
			(property "License" "Apache-2.0"
				(at 45.72 -20.32 0)
				(effects
					(font
						(size 1.27 1.27)
						(thickness 0.15)
					)
					(justify left bottom)
					(hide yes)
				)
			)
			(property "ki_locked" ""
				(at 0 0 0)
				(effects
					(font
						(size 1.27 1.27)
					)
				)
			)
			(property "ki_keywords" "VERTICAL, SMT, CONNECTOR, DDR"
				(at 0 0 0)
				(effects
					(font
						(size 1.27 1.27)
					)
					(hide yes)
				)
			)
			(symbol "Bus_DDR5_DDR504111002KQ_CUSTOM_1xDetectPin_1_1"
				(rectangle
					(start 3.81 2.54)
					(end 26.67 -162.56)
					(stroke
						(width 0.254)
						(type default)
					)
					(fill
						(type background)
					)
				)
				(pin input line
					(at 0 0 0)
					(length 3.81)
					(name "DQ0_A"
						(effects
							(font
								(size 1.27 1.27)
							)
						)
					)
					(number "7"
						(effects
							(font
								(size 1.27 1.27)
							)
						)
					)
				)
				(pin input line
					(at 0 -2.54 0)
					(length 3.81)
					(name "DQ1_A"
						(effects
							(font
								(size 1.27 1.27)
							)
						)
					)
					(number "9"
						(effects
							(font
								(size 1.27 1.27)
							)
						)
					)
				)
				(pin input line
					(at 0 -5.08 0)
					(length 3.81)
					(name "DQ2_A"
						(effects
							(font
								(size 1.27 1.27)
							)
						)
					)
					(number "152"
						(effects
							(font
								(size 1.27 1.27)
							)
						)
					)
				)
				(pin input line
					(at 0 -7.62 0)
					(length 3.81)
					(name "DQ3_A"
						(effects
							(font
								(size 1.27 1.27)
							)
						)
					)
					(number "154"
						(effects
							(font
								(size 1.27 1.27)
							)
						)
					)
				)
				(pin input line
					(at 0 -10.16 0)
					(length 3.81)
					(name "DQS0_A_T"
						(effects
							(font
								(size 1.27 1.27)
							)
						)
					)
					(number "11"
						(effects
							(font
								(size 1.27 1.27)
							)
						)
					)
				)
				(pin input line
					(at 0 -12.7 0)
					(length 3.81)
					(name "DQS0_A_C"
						(effects
							(font
								(size 1.27 1.27)
							)
						)
					)
					(number "12"
						(effects
							(font
								(size 1.27 1.27)
							)
						)
					)
				)
				(pin input line
					(at 0 -15.24 0)
					(length 3.81)
					(name "DQ4_A"
						(effects
							(font
								(size 1.27 1.27)
							)
						)
					)
					(number "14"
						(effects
							(font
								(size 1.27 1.27)
							)
						)
					)
				)
				(pin input line
					(at 0 -17.78 0)
					(length 3.81)
					(name "DQ5_A"
						(effects
							(font
								(size 1.27 1.27)
							)
						)
					)
					(number "16"
						(effects
							(font
								(size 1.27 1.27)
							)
						)
					)
				)
				(pin input line
					(at 0 -20.32 0)
					(length 3.81)
					(name "DQ6_A"
						(effects
							(font
								(size 1.27 1.27)
							)
						)
					)
					(number "159"
						(effects
							(font
								(size 1.27 1.27)
							)
						)
					)
				)
				(pin input line
					(at 0 -22.86 0)
					(length 3.81)
					(name "DQ7_A"
						(effects
							(font
								(size 1.27 1.27)
							)
						)
					)
					(number "161"
						(effects
							(font
								(size 1.27 1.27)
							)
						)
					)
				)
				(pin input line
					(at 0 -25.4 0)
					(length 3.81)
					(name "DQS5_A_T"
						(effects
							(font
								(size 1.27 1.27)
							)
						)
					)
					(number "157"
						(effects
							(font
								(size 1.27 1.27)
							)
						)
					)
				)
				(pin input line
					(at 0 -27.94 0)
					(length 3.81)
					(name "DQS5_A_C"
						(effects
							(font
								(size 1.27 1.27)
							)
						)
					)
					(number "156"
						(effects
							(font
								(size 1.27 1.27)
							)
						)
					)
				)
				(pin input line
					(at 0 -33.02 0)
					(length 3.81)
					(name "DQ8_A"
						(effects
							(font
								(size 1.27 1.27)
							)
						)
					)
					(number "18"
						(effects
							(font
								(size 1.27 1.27)
							)
						)
					)
				)
				(pin input line
					(at 0 -35.56 0)
					(length 3.81)
					(name "DQ9_A"
						(effects
							(font
								(size 1.27 1.27)
							)
						)
					)
					(number "20"
						(effects
							(font
								(size 1.27 1.27)
							)
						)
					)
				)
				(pin input line
					(at 0 -38.1 0)
					(length 3.81)
					(name "DQ10_A"
						(effects
							(font
								(size 1.27 1.27)
							)
						)
					)
					(number "163"
						(effects
							(font
								(size 1.27 1.27)
							)
						)
					)
				)
				(pin input line
					(at 0 -40.64 0)
					(length 3.81)
					(name "DQ11_A"
						(effects
							(font
								(size 1.27 1.27)
							)
						)
					)
					(number "165"
						(effects
							(font
								(size 1.27 1.27)
							)
						)
					)
				)
				(pin input line
					(at 0 -43.18 0)
					(length 3.81)
					(name "DQS1_A_T"
						(effects
							(font
								(size 1.27 1.27)
							)
						)
					)
					(number "22"
						(effects
							(font
								(size 1.27 1.27)
							)
						)
					)
				)
				(pin input line
					(at 0 -45.72 0)
					(length 3.81)
					(name "DQS1_A_C"
						(effects
							(font
								(size 1.27 1.27)
							)
						)
					)
					(number "23"
						(effects
							(font
								(size 1.27 1.27)
							)
						)
					)
				)
				(pin input line
					(at 0 -48.26 0)
					(length 3.81)
					(name "DQ12_A"
						(effects
							(font
								(size 1.27 1.27)
							)
						)
					)
					(number "25"
						(effects
							(font
								(size 1.27 1.27)
							)
						)
					)
				)
				(pin input line
					(at 0 -50.8 0)
					(length 3.81)
					(name "DQ13_A"
						(effects
							(font
								(size 1.27 1.27)
							)
						)
					)
					(number "27"
						(effects
							(font
								(size 1.27 1.27)
							)
						)
					)
				)
				(pin input line
					(at 0 -53.34 0)
					(length 3.81)
					(name "DQ14_A"
						(effects
							(font
								(size 1.27 1.27)
							)
						)
					)
					(number "170"
						(effects
							(font
								(size 1.27 1.27)
							)
						)
					)
				)
				(pin input line
					(at 0 -55.88 0)
					(length 3.81)
					(name "DQ15_A"
						(effects
							(font
								(size 1.27 1.27)
							)
						)
					)
					(number "172"
						(effects
							(font
								(size 1.27 1.27)
							)
						)
					)
				)
				(pin input line
					(at 0 -58.42 0)
					(length 3.81)
					(name "DQS6_A_T"
						(effects
							(font
								(size 1.27 1.27)
							)
						)
					)
					(number "168"
						(effects
							(font
								(size 1.27 1.27)
							)
						)
					)
				)
				(pin input line
					(at 0 -60.96 0)
					(length 3.81)
					(name "DQS6_A_C"
						(effects
							(font
								(size 1.27 1.27)
							)
						)
					)
					(number "167"
						(effects
							(font
								(size 1.27 1.27)
							)
						)
					)
				)
				(pin input line
					(at 0 -66.04 0)
					(length 3.81)
					(name "DQ16_A"
						(effects
							(font
								(size 1.27 1.27)
							)
						)
					)
					(number "29"
						(effects
							(font
								(size 1.27 1.27)
							)
						)
					)
				)
				(pin input line
					(at 0 -68.58 0)
					(length 3.81)
					(name "DQ17_A"
						(effects
							(font
								(size 1.27 1.27)
							)
						)
					)
					(number "31"
						(effects
							(font
								(size 1.27 1.27)
							)
						)
					)
				)
				(pin input line
					(at 0 -71.12 0)
					(length 3.81)
					(name "DQ18_A"
						(effects
							(font
								(size 1.27 1.27)
							)
						)
					)
					(number "174"
						(effects
							(font
								(size 1.27 1.27)
							)
						)
					)
				)
				(pin input line
					(at 0 -73.66 0)
					(length 3.81)
					(name "DQ19_A"
						(effects
							(font
								(size 1.27 1.27)
							)
						)
					)
					(number "176"
						(effects
							(font
								(size 1.27 1.27)
							)
						)
					)
				)
				(pin input line
					(at 0 -76.2 0)
					(length 3.81)
					(name "DQS2_A_T"
						(effects
							(font
								(size 1.27 1.27)
							)
						)
					)
					(number "33"
						(effects
							(font
								(size 1.27 1.27)
							)
						)
					)
				)
				(pin input line
					(at 0 -78.74 0)
					(length 3.81)
					(name "DQS2_A_C"
						(effects
							(font
								(size 1.27 1.27)
							)
						)
					)
					(number "34"
						(effects
							(font
								(size 1.27 1.27)
							)
						)
					)
				)
				(pin input line
					(at 0 -81.28 0)
					(length 3.81)
					(name "DQ20_A"
						(effects
							(font
								(size 1.27 1.27)
							)
						)
					)
					(number "36"
						(effects
							(font
								(size 1.27 1.27)
							)
						)
					)
				)
				(pin input line
					(at 0 -83.82 0)
					(length 3.81)
					(name "DQ21_A"
						(effects
							(font
								(size 1.27 1.27)
							)
						)
					)
					(number "38"
						(effects
							(font
								(size 1.27 1.27)
							)
						)
					)
				)
				(pin input line
					(at 0 -86.36 0)
					(length 3.81)
					(name "DQ22_A"
						(effects
							(font
								(size 1.27 1.27)
							)
						)
					)
					(number "181"
						(effects
							(font
								(size 1.27 1.27)
							)
						)
					)
				)
				(pin input line
					(at 0 -88.9 0)
					(length 3.81)
					(name "DQ23_A"
						(effects
							(font
								(size 1.27 1.27)
							)
						)
					)
					(number "183"
						(effects
							(font
								(size 1.27 1.27)
							)
						)
					)
				)
				(pin input line
					(at 0 -91.44 0)
					(length 3.81)
					(name "DQS7_A_T"
						(effects
							(font
								(size 1.27 1.27)
							)
						)
					)
					(number "179"
						(effects
							(font
								(size 1.27 1.27)
							)
						)
					)
				)
				(pin input line
					(at 0 -93.98 0)
					(length 3.81)
					(name "DQS7_A_C"
						(effects
							(font
								(size 1.27 1.27)
							)
						)
					)
					(number "178"
						(effects
							(font
								(size 1.27 1.27)
							)
						)
					)
				)
				(pin input line
					(at 0 -99.06 0)
					(length 3.81)
					(name "DQ24_A"
						(effects
							(font
								(size 1.27 1.27)
							)
						)
					)
					(number "40"
						(effects
							(font
								(size 1.27 1.27)
							)
						)
					)
				)
				(pin input line
					(at 0 -101.6 0)
					(length 3.81)
					(name "DQ25_A"
						(effects
							(font
								(size 1.27 1.27)
							)
						)
					)
					(number "42"
						(effects
							(font
								(size 1.27 1.27)
							)
						)
					)
				)
				(pin input line
					(at 0 -104.14 0)
					(length 3.81)
					(name "DQ26_A"
						(effects
							(font
								(size 1.27 1.27)
							)
						)
					)
					(number "185"
						(effects
							(font
								(size 1.27 1.27)
							)
						)
					)
				)
				(pin input line
					(at 0 -106.68 0)
					(length 3.81)
					(name "DQ27_A"
						(effects
							(font
								(size 1.27 1.27)
							)
						)
					)
					(number "187"
						(effects
							(font
								(size 1.27 1.27)
							)
						)
					)
				)
				(pin input line
					(at 0 -109.22 0)
					(length 3.81)
					(name "DQS3_A_T"
						(effects
							(font
								(size 1.27 1.27)
							)
						)
					)
					(number "44"
						(effects
							(font
								(size 1.27 1.27)
							)
						)
					)
				)
				(pin input line
					(at 0 -111.76 0)
					(length 3.81)
					(name "DQS3_A_C"
						(effects
							(font
								(size 1.27 1.27)
							)
						)
					)
					(number "45"
						(effects
							(font
								(size 1.27 1.27)
							)
						)
					)
				)
				(pin input line
					(at 0 -114.3 0)
					(length 3.81)
					(name "DQ28_A"
						(effects
							(font
								(size 1.27 1.27)
							)
						)
					)
					(number "47"
						(effects
							(font
								(size 1.27 1.27)
							)
						)
					)
				)
				(pin input line
					(at 0 -116.84 0)
					(length 3.81)
					(name "DQ29_A"
						(effects
							(font
								(size 1.27 1.27)
							)
						)
					)
					(number "49"
						(effects
							(font
								(size 1.27 1.27)
							)
						)
					)
				)
				(pin input line
					(at 0 -119.38 0)
					(length 3.81)
					(name "DQ30_A"
						(effects
							(font
								(size 1.27 1.27)
							)
						)
					)
					(number "192"
						(effects
							(font
								(size 1.27 1.27)
							)
						)
					)
				)
				(pin input line
					(at 0 -121.92 0)
					(length 3.81)
					(name "DQ31_A"
						(effects
							(font
								(size 1.27 1.27)
							)
						)
					)
					(number "194"
						(effects
							(font
								(size 1.27 1.27)
							)
						)
					)
				)
				(pin input line
					(at 0 -124.46 0)
					(length 3.81)
					(name "DQS8_A_T"
						(effects
							(font
								(size 1.27 1.27)
							)
						)
					)
					(number "190"
						(effects
							(font
								(size 1.27 1.27)
							)
						)
					)
				)
				(pin input line
					(at 0 -127 0)
					(length 3.81)
					(name "DQS8_A_C"
						(effects
							(font
								(size 1.27 1.27)
							)
						)
					)
					(number "189"
						(effects
							(font
								(size 1.27 1.27)
							)
						)
					)
				)
				(pin input line
					(at 0 -132.08 0)
					(length 3.81)
					(name "CB0_A"
						(effects
							(font
								(size 1.27 1.27)
							)
						)
					)
					(number "51"
						(effects
							(font
								(size 1.27 1.27)
							)
						)
					)
				)
				(pin input line
					(at 0 -134.62 0)
					(length 3.81)
					(name "CB1_A"
						(effects
							(font
								(size 1.27 1.27)
							)
						)
					)
					(number "53"
						(effects
							(font
								(size 1.27 1.27)
							)
						)
					)
				)
				(pin input line
					(at 0 -137.16 0)
					(length 3.81)
					(name "CB2_A"
						(effects
							(font
								(size 1.27 1.27)
							)
						)
					)
					(number "196"
						(effects
							(font
								(size 1.27 1.27)
							)
						)
					)
				)
				(pin input line
					(at 0 -139.7 0)
					(length 3.81)
					(name "CB3_A"
						(effects
							(font
								(size 1.27 1.27)
							)
						)
					)
					(number "198"
						(effects
							(font
								(size 1.27 1.27)
							)
						)
					)
				)
				(pin input line
					(at 0 -142.24 0)
					(length 3.81)
					(name "DQS4_A_T"
						(effects
							(font
								(size 1.27 1.27)
							)
						)
					)
					(number "55"
						(effects
							(font
								(size 1.27 1.27)
							)
						)
					)
				)
				(pin input line
					(at 0 -144.78 0)
					(length 3.81)
					(name "DQS4_A_C"
						(effects
							(font
								(size 1.27 1.27)
							)
						)
					)
					(number "56"
						(effects
							(font
								(size 1.27 1.27)
							)
						)
					)
				)
				(pin input line
					(at 0 -147.32 0)
					(length 3.81)
					(name "CB4_A"
						(effects
							(font
								(size 1.27 1.27)
							)
						)
					)
					(number "58"
						(effects
							(font
								(size 1.27 1.27)
							)
						)
					)
				)
				(pin input line
					(at 0 -149.86 0)
					(length 3.81)
					(name "CB5_A"
						(effects
							(font
								(size 1.27 1.27)
							)
						)
					)
					(number "60"
						(effects
							(font
								(size 1.27 1.27)
							)
						)
					)
				)
				(pin input line
					(at 0 -152.4 0)
					(length 3.81)
					(name "CB6_A"
						(effects
							(font
								(size 1.27 1.27)
							)
						)
					)
					(number "203"
						(effects
							(font
								(size 1.27 1.27)
							)
						)
					)
				)
				(pin input line
					(at 0 -154.94 0)
					(length 3.81)
					(name "CB7_A"
						(effects
							(font
								(size 1.27 1.27)
							)
						)
					)
					(number "205"
						(effects
							(font
								(size 1.27 1.27)
							)
						)
					)
				)
				(pin input line
					(at 0 -157.48 0)
					(length 3.81)
					(name "DQS9_A_T"
						(effects
							(font
								(size 1.27 1.27)
							)
						)
					)
					(number "201"
						(effects
							(font
								(size 1.27 1.27)
							)
						)
					)
				)
				(pin input line
					(at 0 -160.02 0)
					(length 3.81)
					(name "DQS9_A_C"
						(effects
							(font
								(size 1.27 1.27)
							)
						)
					)
					(number "200"
						(effects
							(font
								(size 1.27 1.27)
							)
						)
					)
				)
				(pin input line
					(at 30.48 0 180)
					(length 3.81)
					(name "DQ0_B"
						(effects
							(font
								(size 1.27 1.27)
							)
						)
					)
					(number "100"
						(effects
							(font
								(size 1.27 1.27)
							)
						)
					)
				)
				(pin input line
					(at 30.48 -2.54 180)
					(length 3.81)
					(name "DQ1_B"
						(effects
							(font
								(size 1.27 1.27)
							)
						)
					)
					(number "102"
						(effects
							(font
								(size 1.27 1.27)
							)
						)
					)
				)
				(pin input line
					(at 30.48 -5.08 180)
					(length 3.81)
					(name "DQ2_B"
						(effects
							(font
								(size 1.27 1.27)
							)
						)
					)
					(number "245"
						(effects
							(font
								(size 1.27 1.27)
							)
						)
					)
				)
				(pin input line
					(at 30.48 -7.62 180)
					(length 3.81)
					(name "DQ3_B"
						(effects
							(font
								(size 1.27 1.27)
							)
						)
					)
					(number "247"
						(effects
							(font
								(size 1.27 1.27)
							)
						)
					)
				)
				(pin input line
					(at 30.48 -10.16 180)
					(length 3.81)
					(name "DQS0_B_T"
						(effects
							(font
								(size 1.27 1.27)
							)
						)
					)
					(number "104"
						(effects
							(font
								(size 1.27 1.27)
							)
						)
					)
				)
				(pin input line
					(at 30.48 -12.7 180)
					(length 3.81)
					(name "DQS0_B_C"
						(effects
							(font
								(size 1.27 1.27)
							)
						)
					)
					(number "105"
						(effects
							(font
								(size 1.27 1.27)
							)
						)
					)
				)
				(pin input line
					(at 30.48 -15.24 180)
					(length 3.81)
					(name "DQ4_B"
						(effects
							(font
								(size 1.27 1.27)
							)
						)
					)
					(number "107"
						(effects
							(font
								(size 1.27 1.27)
							)
						)
					)
				)
				(pin input line
					(at 30.48 -17.78 180)
					(length 3.81)
					(name "DQ5_B"
						(effects
							(font
								(size 1.27 1.27)
							)
						)
					)
					(number "109"
						(effects
							(font
								(size 1.27 1.27)
							)
						)
					)
				)
				(pin input line
					(at 30.48 -20.32 180)
					(length 3.81)
					(name "DQ6_B"
						(effects
							(font
								(size 1.27 1.27)
							)
						)
					)
					(number "252"
						(effects
							(font
								(size 1.27 1.27)
							)
						)
					)
				)
				(pin input line
					(at 30.48 -22.86 180)
					(length 3.81)
					(name "DQ7_B"
						(effects
							(font
								(size 1.27 1.27)
							)
						)
					)
					(number "254"
						(effects
							(font
								(size 1.27 1.27)
							)
						)
					)
				)
				(pin input line
					(at 30.48 -25.4 180)
					(length 3.81)
					(name "DQS5_B_T"
						(effects
							(font
								(size 1.27 1.27)
							)
						)
					)
					(number "250"
						(effects
							(font
								(size 1.27 1.27)
							)
						)
					)
				)
				(pin input line
					(at 30.48 -27.94 180)
					(length 3.81)
					(name "DQS5_B_C"
						(effects
							(font
								(size 1.27 1.27)
							)
						)
					)
					(number "249"
						(effects
							(font
								(size 1.27 1.27)
							)
						)
					)
				)
				(pin input line
					(at 30.48 -33.02 180)
					(length 3.81)
					(name "DQ8_B"
						(effects
							(font
								(size 1.27 1.27)
							)
						)
					)
					(number "111"
						(effects
							(font
								(size 1.27 1.27)
							)
						)
					)
				)
				(pin input line
					(at 30.48 -35.56 180)
					(length 3.81)
					(name "DQ9_B"
						(effects
							(font
								(size 1.27 1.27)
							)
						)
					)
					(number "113"
						(effects
							(font
								(size 1.27 1.27)
							)
						)
					)
				)
				(pin input line
					(at 30.48 -38.1 180)
					(length 3.81)
					(name "DQ10_B"
						(effects
							(font
								(size 1.27 1.27)
							)
						)
					)
					(number "256"
						(effects
							(font
								(size 1.27 1.27)
							)
						)
					)
				)
				(pin input line
					(at 30.48 -40.64 180)
					(length 3.81)
					(name "DQ11_B"
						(effects
							(font
								(size 1.27 1.27)
							)
						)
					)
					(number "258"
						(effects
							(font
								(size 1.27 1.27)
							)
						)
					)
				)
				(pin input line
					(at 30.48 -43.18 180)
					(length 3.81)
					(name "DQS1_B_T"
						(effects
							(font
								(size 1.27 1.27)
							)
						)
					)
					(number "115"
						(effects
							(font
								(size 1.27 1.27)
							)
						)
					)
				)
				(pin input line
					(at 30.48 -45.72 180)
					(length 3.81)
					(name "DQS1_B_C"
						(effects
							(font
								(size 1.27 1.27)
							)
						)
					)
					(number "116"
						(effects
							(font
								(size 1.27 1.27)
							)
						)
					)
				)
				(pin input line
					(at 30.48 -48.26 180)
					(length 3.81)
					(name "DQ12_B"
						(effects
							(font
								(size 1.27 1.27)
							)
						)
					)
					(number "118"
						(effects
							(font
								(size 1.27 1.27)
							)
						)
					)
				)
				(pin input line
					(at 30.48 -50.8 180)
					(length 3.81)
					(name "DQ13_B"
						(effects
							(font
								(size 1.27 1.27)
							)
						)
					)
					(number "120"
						(effects
							(font
								(size 1.27 1.27)
							)
						)
					)
				)
				(pin input line
					(at 30.48 -53.34 180)
					(length 3.81)
					(name "DQ14_B"
						(effects
							(font
								(size 1.27 1.27)
							)
						)
					)
					(number "263"
						(effects
							(font
								(size 1.27 1.27)
							)
						)
					)
				)
				(pin input line
					(at 30.48 -55.88 180)
					(length 3.81)
					(name "DQ15_B"
						(effects
							(font
								(size 1.27 1.27)
							)
						)
					)
					(number "265"
						(effects
							(font
								(size 1.27 1.27)
							)
						)
					)
				)
				(pin input line
					(at 30.48 -58.42 180)
					(length 3.81)
					(name "DQS6_B_T"
						(effects
							(font
								(size 1.27 1.27)
							)
						)
					)
					(number "261"
						(effects
							(font
								(size 1.27 1.27)
							)
						)
					)
				)
				(pin input line
					(at 30.48 -60.96 180)
					(length 3.81)
					(name "DQS6_B_C"
						(effects
							(font
								(size 1.27 1.27)
							)
						)
					)
					(number "260"
						(effects
							(font
								(size 1.27 1.27)
							)
						)
					)
				)
				(pin input line
					(at 30.48 -66.04 180)
					(length 3.81)
					(name "DQ16_B"
						(effects
							(font
								(size 1.27 1.27)
							)
						)
					)
					(number "122"
						(effects
							(font
								(size 1.27 1.27)
							)
						)
					)
				)
				(pin input line
					(at 30.48 -68.58 180)
					(length 3.81)
					(name "DQ17_B"
						(effects
							(font
								(size 1.27 1.27)
							)
						)
					)
					(number "124"
						(effects
							(font
								(size 1.27 1.27)
							)
						)
					)
				)
				(pin input line
					(at 30.48 -71.12 180)
					(length 3.81)
					(name "DQ18_B"
						(effects
							(font
								(size 1.27 1.27)
							)
						)
					)
					(number "267"
						(effects
							(font
								(size 1.27 1.27)
							)
						)
					)
				)
				(pin input line
					(at 30.48 -73.66 180)
					(length 3.81)
					(name "DQ19_B"
						(effects
							(font
								(size 1.27 1.27)
							)
						)
					)
					(number "269"
						(effects
							(font
								(size 1.27 1.27)
							)
						)
					)
				)
				(pin input line
					(at 30.48 -76.2 180)
					(length 3.81)
					(name "DQS2_B_T"
						(effects
							(font
								(size 1.27 1.27)
							)
						)
					)
					(number "126"
						(effects
							(font
								(size 1.27 1.27)
							)
						)
					)
				)
				(pin input line
					(at 30.48 -78.74 180)
					(length 3.81)
					(name "DQS2_B_C"
						(effects
							(font
								(size 1.27 1.27)
							)
						)
					)
					(number "127"
						(effects
							(font
								(size 1.27 1.27)
							)
						)
					)
				)
				(pin input line
					(at 30.48 -81.28 180)
					(length 3.81)
					(name "DQ20_B"
						(effects
							(font
								(size 1.27 1.27)
							)
						)
					)
					(number "129"
						(effects
							(font
								(size 1.27 1.27)
							)
						)
					)
				)
				(pin input line
					(at 30.48 -83.82 180)
					(length 3.81)
					(name "DQ21_B"
						(effects
							(font
								(size 1.27 1.27)
							)
						)
					)
					(number "131"
						(effects
							(font
								(size 1.27 1.27)
							)
						)
					)
				)
				(pin input line
					(at 30.48 -86.36 180)
					(length 3.81)
					(name "DQ22_B"
						(effects
							(font
								(size 1.27 1.27)
							)
						)
					)
					(number "274"
						(effects
							(font
								(size 1.27 1.27)
							)
						)
					)
				)
				(pin input line
					(at 30.48 -88.9 180)
					(length 3.81)
					(name "DQ23_B"
						(effects
							(font
								(size 1.27 1.27)
							)
						)
					)
					(number "276"
						(effects
							(font
								(size 1.27 1.27)
							)
						)
					)
				)
				(pin input line
					(at 30.48 -91.44 180)
					(length 3.81)
					(name "DQS7_B_T"
						(effects
							(font
								(size 1.27 1.27)
							)
						)
					)
					(number "272"
						(effects
							(font
								(size 1.27 1.27)
							)
						)
					)
				)
				(pin input line
					(at 30.48 -93.98 180)
					(length 3.81)
					(name "DQS7_B_C"
						(effects
							(font
								(size 1.27 1.27)
							)
						)
					)
					(number "271"
						(effects
							(font
								(size 1.27 1.27)
							)
						)
					)
				)
				(pin input line
					(at 30.48 -99.06 180)
					(length 3.81)
					(name "DQ24_B"
						(effects
							(font
								(size 1.27 1.27)
							)
						)
					)
					(number "133"
						(effects
							(font
								(size 1.27 1.27)
							)
						)
					)
				)
				(pin input line
					(at 30.48 -101.6 180)
					(length 3.81)
					(name "DQ25_B"
						(effects
							(font
								(size 1.27 1.27)
							)
						)
					)
					(number "135"
						(effects
							(font
								(size 1.27 1.27)
							)
						)
					)
				)
				(pin input line
					(at 30.48 -104.14 180)
					(length 3.81)
					(name "DQ26_B"
						(effects
							(font
								(size 1.27 1.27)
							)
						)
					)
					(number "278"
						(effects
							(font
								(size 1.27 1.27)
							)
						)
					)
				)
				(pin input line
					(at 30.48 -106.68 180)
					(length 3.81)
					(name "DQ27_B"
						(effects
							(font
								(size 1.27 1.27)
							)
						)
					)
					(number "280"
						(effects
							(font
								(size 1.27 1.27)
							)
						)
					)
				)
				(pin input line
					(at 30.48 -109.22 180)
					(length 3.81)
					(name "DQS3_B_T"
						(effects
							(font
								(size 1.27 1.27)
							)
						)
					)
					(number "137"
						(effects
							(font
								(size 1.27 1.27)
							)
						)
					)
				)
				(pin input line
					(at 30.48 -111.76 180)
					(length 3.81)
					(name "DQS3_B_C"
						(effects
							(font
								(size 1.27 1.27)
							)
						)
					)
					(number "138"
						(effects
							(font
								(size 1.27 1.27)
							)
						)
					)
				)
				(pin input line
					(at 30.48 -114.3 180)
					(length 3.81)
					(name "DQ28_B"
						(effects
							(font
								(size 1.27 1.27)
							)
						)
					)
					(number "140"
						(effects
							(font
								(size 1.27 1.27)
							)
						)
					)
				)
				(pin input line
					(at 30.48 -116.84 180)
					(length 3.81)
					(name "DQ29_B"
						(effects
							(font
								(size 1.27 1.27)
							)
						)
					)
					(number "142"
						(effects
							(font
								(size 1.27 1.27)
							)
						)
					)
				)
				(pin input line
					(at 30.48 -119.38 180)
					(length 3.81)
					(name "DQ30_B"
						(effects
							(font
								(size 1.27 1.27)
							)
						)
					)
					(number "285"
						(effects
							(font
								(size 1.27 1.27)
							)
						)
					)
				)
				(pin input line
					(at 30.48 -121.92 180)
					(length 3.81)
					(name "DQ31_B"
						(effects
							(font
								(size 1.27 1.27)
							)
						)
					)
					(number "287"
						(effects
							(font
								(size 1.27 1.27)
							)
						)
					)
				)
				(pin input line
					(at 30.48 -124.46 180)
					(length 3.81)
					(name "DQS8_B_T"
						(effects
							(font
								(size 1.27 1.27)
							)
						)
					)
					(number "283"
						(effects
							(font
								(size 1.27 1.27)
							)
						)
					)
				)
				(pin input line
					(at 30.48 -127 180)
					(length 3.81)
					(name "DQS8_B_C"
						(effects
							(font
								(size 1.27 1.27)
							)
						)
					)
					(number "282"
						(effects
							(font
								(size 1.27 1.27)
							)
						)
					)
				)
				(pin input line
					(at 30.48 -132.08 180)
					(length 3.81)
					(name "CB0_B"
						(effects
							(font
								(size 1.27 1.27)
							)
						)
					)
					(number "96"
						(effects
							(font
								(size 1.27 1.27)
							)
						)
					)
				)
				(pin input line
					(at 30.48 -134.62 180)
					(length 3.81)
					(name "CB1_B"
						(effects
							(font
								(size 1.27 1.27)
							)
						)
					)
					(number "98"
						(effects
							(font
								(size 1.27 1.27)
							)
						)
					)
				)
				(pin input line
					(at 30.48 -137.16 180)
					(length 3.81)
					(name "CB2_B"
						(effects
							(font
								(size 1.27 1.27)
							)
						)
					)
					(number "241"
						(effects
							(font
								(size 1.27 1.27)
							)
						)
					)
				)
				(pin input line
					(at 30.48 -139.7 180)
					(length 3.81)
					(name "CB3_B"
						(effects
							(font
								(size 1.27 1.27)
							)
						)
					)
					(number "243"
						(effects
							(font
								(size 1.27 1.27)
							)
						)
					)
				)
				(pin input line
					(at 30.48 -142.24 180)
					(length 3.81)
					(name "DQS4_B_T"
						(effects
							(font
								(size 1.27 1.27)
							)
						)
					)
					(number "239"
						(effects
							(font
								(size 1.27 1.27)
							)
						)
					)
				)
				(pin input line
					(at 30.48 -144.78 180)
					(length 3.81)
					(name "DQS4_B_C"
						(effects
							(font
								(size 1.27 1.27)
							)
						)
					)
					(number "238"
						(effects
							(font
								(size 1.27 1.27)
							)
						)
					)
				)
				(pin input line
					(at 30.48 -147.32 180)
					(length 3.81)
					(name "CB4_B"
						(effects
							(font
								(size 1.27 1.27)
							)
						)
					)
					(number "89"
						(effects
							(font
								(size 1.27 1.27)
							)
						)
					)
				)
				(pin input line
					(at 30.48 -149.86 180)
					(length 3.81)
					(name "CB5_B"
						(effects
							(font
								(size 1.27 1.27)
							)
						)
					)
					(number "91"
						(effects
							(font
								(size 1.27 1.27)
							)
						)
					)
				)
				(pin input line
					(at 30.48 -152.4 180)
					(length 3.81)
					(name "CB6_B"
						(effects
							(font
								(size 1.27 1.27)
							)
						)
					)
					(number "234"
						(effects
							(font
								(size 1.27 1.27)
							)
						)
					)
				)
				(pin input line
					(at 30.48 -154.94 180)
					(length 3.81)
					(name "CB7_B"
						(effects
							(font
								(size 1.27 1.27)
							)
						)
					)
					(number "236"
						(effects
							(font
								(size 1.27 1.27)
							)
						)
					)
				)
				(pin input line
					(at 30.48 -157.48 180)
					(length 3.81)
					(name "DQS9_B_T"
						(effects
							(font
								(size 1.27 1.27)
							)
						)
					)
					(number "93"
						(effects
							(font
								(size 1.27 1.27)
							)
						)
					)
				)
				(pin input line
					(at 30.48 -160.02 180)
					(length 3.81)
					(name "DQS9_B_C"
						(effects
							(font
								(size 1.27 1.27)
							)
						)
					)
					(number "94"
						(effects
							(font
								(size 1.27 1.27)
							)
						)
					)
				)
			)
			(symbol "Bus_DDR5_DDR504111002KQ_CUSTOM_1xDetectPin_2_1"
				(rectangle
					(start 3.81 2.54)
					(end 26.67 -63.5)
					(stroke
						(width 0.254)
						(type default)
					)
					(fill
						(type background)
					)
				)
				(pin power_in line
					(at 0 0 0)
					(length 3.81)
					(name "VIN_BULK"
						(effects
							(font
								(size 1.27 1.27)
							)
						)
					)
					(number "1"
						(effects
							(font
								(size 1.27 1.27)
							)
						)
					)
				)
				(pin passive line
					(at 0 0 0)
					(length 3.81)
					(hide yes)
					(name "VIN_BULK"
						(effects
							(font
								(size 1.27 1.27)
							)
						)
					)
					(number "145"
						(effects
							(font
								(size 1.27 1.27)
							)
						)
					)
				)
				(pin passive line
					(at 0 0 0)
					(length 3.81)
					(hide yes)
					(name "VIN_BULK"
						(effects
							(font
								(size 1.27 1.27)
							)
						)
					)
					(number "146"
						(effects
							(font
								(size 1.27 1.27)
							)
						)
					)
				)
				(pin power_in line
					(at 0 -2.54 0)
					(length 3.81)
					(name "VIN_MGMT"
						(effects
							(font
								(size 1.27 1.27)
							)
						)
					)
					(number "3"
						(effects
							(font
								(size 1.27 1.27)
							)
						)
					)
				)
				(pin input line
					(at 0 -5.08 0)
					(length 3.81)
					(name "PCAMP"
						(effects
							(font
								(size 1.27 1.27)
							)
						)
					)
					(number "147"
						(effects
							(font
								(size 1.27 1.27)
							)
						)
					)
				)
				(pin input line
					(at 0 -10.16 0)
					(length 3.81)
					(name "DLBDQ"
						(effects
							(font
								(size 1.27 1.27)
							)
						)
					)
					(number "86"
						(effects
							(font
								(size 1.27 1.27)
							)
						)
					)
				)
				(pin input line
					(at 0 -12.7 0)
					(length 3.81)
					(name "DLBDQS"
						(effects
							(font
								(size 1.27 1.27)
							)
						)
					)
					(number "87"
						(effects
							(font
								(size 1.27 1.27)
							)
						)
					)
				)
				(pin input line
					(at 0 -15.24 0)
					(length 3.81)
					(name "RESET_N"
						(effects
							(font
								(size 1.27 1.27)
							)
						)
					)
					(number "207"
						(effects
							(font
								(size 1.27 1.27)
							)
						)
					)
				)
				(pin input line
					(at 0 -20.32 0)
					(length 3.81)
					(name "CA0_A"
						(effects
							(font
								(size 1.27 1.27)
							)
						)
					)
					(number "66"
						(effects
							(font
								(size 1.27 1.27)
							)
						)
					)
				)
				(pin input line
					(at 0 -22.86 0)
					(length 3.81)
					(name "CA1_A"
						(effects
							(font
								(size 1.27 1.27)
							)
						)
					)
					(number "211"
						(effects
							(font
								(size 1.27 1.27)
							)
						)
					)
				)
				(pin input line
					(at 0 -25.4 0)
					(length 3.81)
					(name "CA2_A"
						(effects
							(font
								(size 1.27 1.27)
							)
						)
					)
					(number "68"
						(effects
							(font
								(size 1.27 1.27)
							)
						)
					)
				)
				(pin input line
					(at 0 -27.94 0)
					(length 3.81)
					(name "CA3_A"
						(effects
							(font
								(size 1.27 1.27)
							)
						)
					)
					(number "213"
						(effects
							(font
								(size 1.27 1.27)
							)
						)
					)
				)
				(pin input line
					(at 0 -30.48 0)
					(length 3.81)
					(name "CA4_A"
						(effects
							(font
								(size 1.27 1.27)
							)
						)
					)
					(number "70"
						(effects
							(font
								(size 1.27 1.27)
							)
						)
					)
				)
				(pin input line
					(at 0 -33.02 0)
					(length 3.81)
					(name "CA5_A"
						(effects
							(font
								(size 1.27 1.27)
							)
						)
					)
					(number "215"
						(effects
							(font
								(size 1.27 1.27)
							)
						)
					)
				)
				(pin input line
					(at 0 -35.56 0)
					(length 3.81)
					(name "CA6_A"
						(effects
							(font
								(size 1.27 1.27)
							)
						)
					)
					(number "72"
						(effects
							(font
								(size 1.27 1.27)
							)
						)
					)
				)
				(pin input line
					(at 0 -38.1 0)
					(length 3.81)
					(name "PAR_A"
						(effects
							(font
								(size 1.27 1.27)
							)
						)
					)
					(number "74"
						(effects
							(font
								(size 1.27 1.27)
							)
						)
					)
				)
				(pin input line
					(at 0 -40.64 0)
					(length 3.81)
					(name "CS0_A_N"
						(effects
							(font
								(size 1.27 1.27)
							)
						)
					)
					(number "64"
						(effects
							(font
								(size 1.27 1.27)
							)
						)
					)
				)
				(pin input line
					(at 0 -43.18 0)
					(length 3.81)
					(name "CS1_A_N"
						(effects
							(font
								(size 1.27 1.27)
							)
						)
					)
					(number "209"
						(effects
							(font
								(size 1.27 1.27)
							)
						)
					)
				)
				(pin passive line
					(at 0 -53.34 0)
					(length 3.81)
					(name "VSS_DET"
						(effects
							(font
								(size 1.27 1.27)
							)
						)
					)
					(number "75"
						(effects
							(font
								(size 1.27 1.27)
							)
						)
					)
				)
				(pin power_in line
					(at 0 -55.88 0)
					(length 3.81)
					(name "VSS"
						(effects
							(font
								(size 1.27 1.27)
							)
						)
					)
					(number "10"
						(effects
							(font
								(size 1.27 1.27)
							)
						)
					)
				)
				(pin passive line
					(at 0 -55.88 0)
					(length 3.81)
					(hide yes)
					(name "VSS"
						(effects
							(font
								(size 1.27 1.27)
							)
						)
					)
					(number "101"
						(effects
							(font
								(size 1.27 1.27)
							)
						)
					)
				)
				(pin passive line
					(at 0 -55.88 0)
					(length 3.81)
					(hide yes)
					(name "VSS"
						(effects
							(font
								(size 1.27 1.27)
							)
						)
					)
					(number "103"
						(effects
							(font
								(size 1.27 1.27)
							)
						)
					)
				)
				(pin passive line
					(at 0 -55.88 0)
					(length 3.81)
					(hide yes)
					(name "VSS"
						(effects
							(font
								(size 1.27 1.27)
							)
						)
					)
					(number "106"
						(effects
							(font
								(size 1.27 1.27)
							)
						)
					)
				)
				(pin passive line
					(at 0 -55.88 0)
					(length 3.81)
					(hide yes)
					(name "VSS"
						(effects
							(font
								(size 1.27 1.27)
							)
						)
					)
					(number "108"
						(effects
							(font
								(size 1.27 1.27)
							)
						)
					)
				)
				(pin passive line
					(at 0 -55.88 0)
					(length 3.81)
					(hide yes)
					(name "VSS"
						(effects
							(font
								(size 1.27 1.27)
							)
						)
					)
					(number "110"
						(effects
							(font
								(size 1.27 1.27)
							)
						)
					)
				)
				(pin passive line
					(at 0 -55.88 0)
					(length 3.81)
					(hide yes)
					(name "VSS"
						(effects
							(font
								(size 1.27 1.27)
							)
						)
					)
					(number "112"
						(effects
							(font
								(size 1.27 1.27)
							)
						)
					)
				)
				(pin passive line
					(at 0 -55.88 0)
					(length 3.81)
					(hide yes)
					(name "VSS"
						(effects
							(font
								(size 1.27 1.27)
							)
						)
					)
					(number "114"
						(effects
							(font
								(size 1.27 1.27)
							)
						)
					)
				)
				(pin passive line
					(at 0 -55.88 0)
					(length 3.81)
					(hide yes)
					(name "VSS"
						(effects
							(font
								(size 1.27 1.27)
							)
						)
					)
					(number "117"
						(effects
							(font
								(size 1.27 1.27)
							)
						)
					)
				)
				(pin passive line
					(at 0 -55.88 0)
					(length 3.81)
					(hide yes)
					(name "VSS"
						(effects
							(font
								(size 1.27 1.27)
							)
						)
					)
					(number "119"
						(effects
							(font
								(size 1.27 1.27)
							)
						)
					)
				)
				(pin passive line
					(at 0 -55.88 0)
					(length 3.81)
					(hide yes)
					(name "VSS"
						(effects
							(font
								(size 1.27 1.27)
							)
						)
					)
					(number "121"
						(effects
							(font
								(size 1.27 1.27)
							)
						)
					)
				)
				(pin passive line
					(at 0 -55.88 0)
					(length 3.81)
					(hide yes)
					(name "VSS"
						(effects
							(font
								(size 1.27 1.27)
							)
						)
					)
					(number "123"
						(effects
							(font
								(size 1.27 1.27)
							)
						)
					)
				)
				(pin passive line
					(at 0 -55.88 0)
					(length 3.81)
					(hide yes)
					(name "VSS"
						(effects
							(font
								(size 1.27 1.27)
							)
						)
					)
					(number "125"
						(effects
							(font
								(size 1.27 1.27)
							)
						)
					)
				)
				(pin passive line
					(at 0 -55.88 0)
					(length 3.81)
					(hide yes)
					(name "VSS"
						(effects
							(font
								(size 1.27 1.27)
							)
						)
					)
					(number "128"
						(effects
							(font
								(size 1.27 1.27)
							)
						)
					)
				)
				(pin passive line
					(at 0 -55.88 0)
					(length 3.81)
					(hide yes)
					(name "VSS"
						(effects
							(font
								(size 1.27 1.27)
							)
						)
					)
					(number "13"
						(effects
							(font
								(size 1.27 1.27)
							)
						)
					)
				)
				(pin passive line
					(at 0 -55.88 0)
					(length 3.81)
					(hide yes)
					(name "VSS"
						(effects
							(font
								(size 1.27 1.27)
							)
						)
					)
					(number "130"
						(effects
							(font
								(size 1.27 1.27)
							)
						)
					)
				)
				(pin passive line
					(at 0 -55.88 0)
					(length 3.81)
					(hide yes)
					(name "VSS"
						(effects
							(font
								(size 1.27 1.27)
							)
						)
					)
					(number "132"
						(effects
							(font
								(size 1.27 1.27)
							)
						)
					)
				)
				(pin passive line
					(at 0 -55.88 0)
					(length 3.81)
					(hide yes)
					(name "VSS"
						(effects
							(font
								(size 1.27 1.27)
							)
						)
					)
					(number "134"
						(effects
							(font
								(size 1.27 1.27)
							)
						)
					)
				)
				(pin passive line
					(at 0 -55.88 0)
					(length 3.81)
					(hide yes)
					(name "VSS"
						(effects
							(font
								(size 1.27 1.27)
							)
						)
					)
					(number "136"
						(effects
							(font
								(size 1.27 1.27)
							)
						)
					)
				)
				(pin passive line
					(at 0 -55.88 0)
					(length 3.81)
					(hide yes)
					(name "VSS"
						(effects
							(font
								(size 1.27 1.27)
							)
						)
					)
					(number "139"
						(effects
							(font
								(size 1.27 1.27)
							)
						)
					)
				)
				(pin passive line
					(at 0 -55.88 0)
					(length 3.81)
					(hide yes)
					(name "VSS"
						(effects
							(font
								(size 1.27 1.27)
							)
						)
					)
					(number "141"
						(effects
							(font
								(size 1.27 1.27)
							)
						)
					)
				)
				(pin passive line
					(at 0 -55.88 0)
					(length 3.81)
					(hide yes)
					(name "VSS"
						(effects
							(font
								(size 1.27 1.27)
							)
						)
					)
					(number "143"
						(effects
							(font
								(size 1.27 1.27)
							)
						)
					)
				)
				(pin passive line
					(at 0 -55.88 0)
					(length 3.81)
					(hide yes)
					(name "VSS"
						(effects
							(font
								(size 1.27 1.27)
							)
						)
					)
					(number "15"
						(effects
							(font
								(size 1.27 1.27)
							)
						)
					)
				)
				(pin passive line
					(at 0 -55.88 0)
					(length 3.81)
					(hide yes)
					(name "VSS"
						(effects
							(font
								(size 1.27 1.27)
							)
						)
					)
					(number "151"
						(effects
							(font
								(size 1.27 1.27)
							)
						)
					)
				)
				(pin passive line
					(at 0 -55.88 0)
					(length 3.81)
					(hide yes)
					(name "VSS"
						(effects
							(font
								(size 1.27 1.27)
							)
						)
					)
					(number "153"
						(effects
							(font
								(size 1.27 1.27)
							)
						)
					)
				)
				(pin passive line
					(at 0 -55.88 0)
					(length 3.81)
					(hide yes)
					(name "VSS"
						(effects
							(font
								(size 1.27 1.27)
							)
						)
					)
					(number "155"
						(effects
							(font
								(size 1.27 1.27)
							)
						)
					)
				)
				(pin passive line
					(at 0 -55.88 0)
					(length 3.81)
					(hide yes)
					(name "VSS"
						(effects
							(font
								(size 1.27 1.27)
							)
						)
					)
					(number "158"
						(effects
							(font
								(size 1.27 1.27)
							)
						)
					)
				)
				(pin passive line
					(at 0 -55.88 0)
					(length 3.81)
					(hide yes)
					(name "VSS"
						(effects
							(font
								(size 1.27 1.27)
							)
						)
					)
					(number "160"
						(effects
							(font
								(size 1.27 1.27)
							)
						)
					)
				)
				(pin passive line
					(at 0 -55.88 0)
					(length 3.81)
					(hide yes)
					(name "VSS"
						(effects
							(font
								(size 1.27 1.27)
							)
						)
					)
					(number "162"
						(effects
							(font
								(size 1.27 1.27)
							)
						)
					)
				)
				(pin passive line
					(at 0 -55.88 0)
					(length 3.81)
					(hide yes)
					(name "VSS"
						(effects
							(font
								(size 1.27 1.27)
							)
						)
					)
					(number "164"
						(effects
							(font
								(size 1.27 1.27)
							)
						)
					)
				)
				(pin passive line
					(at 0 -55.88 0)
					(length 3.81)
					(hide yes)
					(name "VSS"
						(effects
							(font
								(size 1.27 1.27)
							)
						)
					)
					(number "166"
						(effects
							(font
								(size 1.27 1.27)
							)
						)
					)
				)
				(pin passive line
					(at 0 -55.88 0)
					(length 3.81)
					(hide yes)
					(name "VSS"
						(effects
							(font
								(size 1.27 1.27)
							)
						)
					)
					(number "169"
						(effects
							(font
								(size 1.27 1.27)
							)
						)
					)
				)
				(pin passive line
					(at 0 -55.88 0)
					(length 3.81)
					(hide yes)
					(name "VSS"
						(effects
							(font
								(size 1.27 1.27)
							)
						)
					)
					(number "17"
						(effects
							(font
								(size 1.27 1.27)
							)
						)
					)
				)
				(pin passive line
					(at 0 -55.88 0)
					(length 3.81)
					(hide yes)
					(name "VSS"
						(effects
							(font
								(size 1.27 1.27)
							)
						)
					)
					(number "171"
						(effects
							(font
								(size 1.27 1.27)
							)
						)
					)
				)
				(pin passive line
					(at 0 -55.88 0)
					(length 3.81)
					(hide yes)
					(name "VSS"
						(effects
							(font
								(size 1.27 1.27)
							)
						)
					)
					(number "173"
						(effects
							(font
								(size 1.27 1.27)
							)
						)
					)
				)
				(pin passive line
					(at 0 -55.88 0)
					(length 3.81)
					(hide yes)
					(name "VSS"
						(effects
							(font
								(size 1.27 1.27)
							)
						)
					)
					(number "175"
						(effects
							(font
								(size 1.27 1.27)
							)
						)
					)
				)
				(pin passive line
					(at 0 -55.88 0)
					(length 3.81)
					(hide yes)
					(name "VSS"
						(effects
							(font
								(size 1.27 1.27)
							)
						)
					)
					(number "177"
						(effects
							(font
								(size 1.27 1.27)
							)
						)
					)
				)
				(pin passive line
					(at 0 -55.88 0)
					(length 3.81)
					(hide yes)
					(name "VSS"
						(effects
							(font
								(size 1.27 1.27)
							)
						)
					)
					(number "180"
						(effects
							(font
								(size 1.27 1.27)
							)
						)
					)
				)
				(pin passive line
					(at 0 -55.88 0)
					(length 3.81)
					(hide yes)
					(name "VSS"
						(effects
							(font
								(size 1.27 1.27)
							)
						)
					)
					(number "182"
						(effects
							(font
								(size 1.27 1.27)
							)
						)
					)
				)
				(pin passive line
					(at 0 -55.88 0)
					(length 3.81)
					(hide yes)
					(name "VSS"
						(effects
							(font
								(size 1.27 1.27)
							)
						)
					)
					(number "184"
						(effects
							(font
								(size 1.27 1.27)
							)
						)
					)
				)
				(pin passive line
					(at 0 -55.88 0)
					(length 3.81)
					(hide yes)
					(name "VSS"
						(effects
							(font
								(size 1.27 1.27)
							)
						)
					)
					(number "186"
						(effects
							(font
								(size 1.27 1.27)
							)
						)
					)
				)
				(pin passive line
					(at 0 -55.88 0)
					(length 3.81)
					(hide yes)
					(name "VSS"
						(effects
							(font
								(size 1.27 1.27)
							)
						)
					)
					(number "188"
						(effects
							(font
								(size 1.27 1.27)
							)
						)
					)
				)
				(pin passive line
					(at 0 -55.88 0)
					(length 3.81)
					(hide yes)
					(name "VSS"
						(effects
							(font
								(size 1.27 1.27)
							)
						)
					)
					(number "19"
						(effects
							(font
								(size 1.27 1.27)
							)
						)
					)
				)
				(pin passive line
					(at 0 -55.88 0)
					(length 3.81)
					(hide yes)
					(name "VSS"
						(effects
							(font
								(size 1.27 1.27)
							)
						)
					)
					(number "191"
						(effects
							(font
								(size 1.27 1.27)
							)
						)
					)
				)
				(pin passive line
					(at 0 -55.88 0)
					(length 3.81)
					(hide yes)
					(name "VSS"
						(effects
							(font
								(size 1.27 1.27)
							)
						)
					)
					(number "193"
						(effects
							(font
								(size 1.27 1.27)
							)
						)
					)
				)
				(pin passive line
					(at 0 -55.88 0)
					(length 3.81)
					(hide yes)
					(name "VSS"
						(effects
							(font
								(size 1.27 1.27)
							)
						)
					)
					(number "195"
						(effects
							(font
								(size 1.27 1.27)
							)
						)
					)
				)
				(pin passive line
					(at 0 -55.88 0)
					(length 3.81)
					(hide yes)
					(name "VSS"
						(effects
							(font
								(size 1.27 1.27)
							)
						)
					)
					(number "197"
						(effects
							(font
								(size 1.27 1.27)
							)
						)
					)
				)
				(pin passive line
					(at 0 -55.88 0)
					(length 3.81)
					(hide yes)
					(name "VSS"
						(effects
							(font
								(size 1.27 1.27)
							)
						)
					)
					(number "199"
						(effects
							(font
								(size 1.27 1.27)
							)
						)
					)
				)
				(pin passive line
					(at 0 -55.88 0)
					(length 3.81)
					(hide yes)
					(name "VSS"
						(effects
							(font
								(size 1.27 1.27)
							)
						)
					)
					(number "202"
						(effects
							(font
								(size 1.27 1.27)
							)
						)
					)
				)
				(pin passive line
					(at 0 -55.88 0)
					(length 3.81)
					(hide yes)
					(name "VSS"
						(effects
							(font
								(size 1.27 1.27)
							)
						)
					)
					(number "204"
						(effects
							(font
								(size 1.27 1.27)
							)
						)
					)
				)
				(pin passive line
					(at 0 -55.88 0)
					(length 3.81)
					(hide yes)
					(name "VSS"
						(effects
							(font
								(size 1.27 1.27)
							)
						)
					)
					(number "206"
						(effects
							(font
								(size 1.27 1.27)
							)
						)
					)
				)
				(pin passive line
					(at 0 -55.88 0)
					(length 3.81)
					(hide yes)
					(name "VSS"
						(effects
							(font
								(size 1.27 1.27)
							)
						)
					)
					(number "208"
						(effects
							(font
								(size 1.27 1.27)
							)
						)
					)
				)
				(pin passive line
					(at 0 -55.88 0)
					(length 3.81)
					(hide yes)
					(name "VSS"
						(effects
							(font
								(size 1.27 1.27)
							)
						)
					)
					(number "21"
						(effects
							(font
								(size 1.27 1.27)
							)
						)
					)
				)
				(pin passive line
					(at 0 -55.88 0)
					(length 3.81)
					(hide yes)
					(name "VSS"
						(effects
							(font
								(size 1.27 1.27)
							)
						)
					)
					(number "210"
						(effects
							(font
								(size 1.27 1.27)
							)
						)
					)
				)
				(pin passive line
					(at 0 -55.88 0)
					(length 3.81)
					(hide yes)
					(name "VSS"
						(effects
							(font
								(size 1.27 1.27)
							)
						)
					)
					(number "212"
						(effects
							(font
								(size 1.27 1.27)
							)
						)
					)
				)
				(pin passive line
					(at 0 -55.88 0)
					(length 3.81)
					(hide yes)
					(name "VSS"
						(effects
							(font
								(size 1.27 1.27)
							)
						)
					)
					(number "214"
						(effects
							(font
								(size 1.27 1.27)
							)
						)
					)
				)
				(pin passive line
					(at 0 -55.88 0)
					(length 3.81)
					(hide yes)
					(name "VSS"
						(effects
							(font
								(size 1.27 1.27)
							)
						)
					)
					(number "216"
						(effects
							(font
								(size 1.27 1.27)
							)
						)
					)
				)
				(pin passive line
					(at 0 -55.88 0)
					(length 3.81)
					(hide yes)
					(name "VSS"
						(effects
							(font
								(size 1.27 1.27)
							)
						)
					)
					(number "219"
						(effects
							(font
								(size 1.27 1.27)
							)
						)
					)
				)
				(pin passive line
					(at 0 -55.88 0)
					(length 3.81)
					(hide yes)
					(name "VSS"
						(effects
							(font
								(size 1.27 1.27)
							)
						)
					)
					(number "222"
						(effects
							(font
								(size 1.27 1.27)
							)
						)
					)
				)
				(pin passive line
					(at 0 -55.88 0)
					(length 3.81)
					(hide yes)
					(name "VSS"
						(effects
							(font
								(size 1.27 1.27)
							)
						)
					)
					(number "224"
						(effects
							(font
								(size 1.27 1.27)
							)
						)
					)
				)
				(pin passive line
					(at 0 -55.88 0)
					(length 3.81)
					(hide yes)
					(name "VSS"
						(effects
							(font
								(size 1.27 1.27)
							)
						)
					)
					(number "226"
						(effects
							(font
								(size 1.27 1.27)
							)
						)
					)
				)
				(pin passive line
					(at 0 -55.88 0)
					(length 3.81)
					(hide yes)
					(name "VSS"
						(effects
							(font
								(size 1.27 1.27)
							)
						)
					)
					(number "228"
						(effects
							(font
								(size 1.27 1.27)
							)
						)
					)
				)
				(pin passive line
					(at 0 -55.88 0)
					(length 3.81)
					(hide yes)
					(name "VSS"
						(effects
							(font
								(size 1.27 1.27)
							)
						)
					)
					(number "230"
						(effects
							(font
								(size 1.27 1.27)
							)
						)
					)
				)
				(pin passive line
					(at 0 -55.88 0)
					(length 3.81)
					(hide yes)
					(name "VSS"
						(effects
							(font
								(size 1.27 1.27)
							)
						)
					)
					(number "233"
						(effects
							(font
								(size 1.27 1.27)
							)
						)
					)
				)
				(pin passive line
					(at 0 -55.88 0)
					(length 3.81)
					(hide yes)
					(name "VSS"
						(effects
							(font
								(size 1.27 1.27)
							)
						)
					)
					(number "235"
						(effects
							(font
								(size 1.27 1.27)
							)
						)
					)
				)
				(pin passive line
					(at 0 -55.88 0)
					(length 3.81)
					(hide yes)
					(name "VSS"
						(effects
							(font
								(size 1.27 1.27)
							)
						)
					)
					(number "237"
						(effects
							(font
								(size 1.27 1.27)
							)
						)
					)
				)
				(pin passive line
					(at 0 -55.88 0)
					(length 3.81)
					(hide yes)
					(name "VSS"
						(effects
							(font
								(size 1.27 1.27)
							)
						)
					)
					(number "24"
						(effects
							(font
								(size 1.27 1.27)
							)
						)
					)
				)
				(pin passive line
					(at 0 -55.88 0)
					(length 3.81)
					(hide yes)
					(name "VSS"
						(effects
							(font
								(size 1.27 1.27)
							)
						)
					)
					(number "240"
						(effects
							(font
								(size 1.27 1.27)
							)
						)
					)
				)
				(pin passive line
					(at 0 -55.88 0)
					(length 3.81)
					(hide yes)
					(name "VSS"
						(effects
							(font
								(size 1.27 1.27)
							)
						)
					)
					(number "242"
						(effects
							(font
								(size 1.27 1.27)
							)
						)
					)
				)
				(pin passive line
					(at 0 -55.88 0)
					(length 3.81)
					(hide yes)
					(name "VSS"
						(effects
							(font
								(size 1.27 1.27)
							)
						)
					)
					(number "244"
						(effects
							(font
								(size 1.27 1.27)
							)
						)
					)
				)
				(pin passive line
					(at 0 -55.88 0)
					(length 3.81)
					(hide yes)
					(name "VSS"
						(effects
							(font
								(size 1.27 1.27)
							)
						)
					)
					(number "246"
						(effects
							(font
								(size 1.27 1.27)
							)
						)
					)
				)
				(pin passive line
					(at 0 -55.88 0)
					(length 3.81)
					(hide yes)
					(name "VSS"
						(effects
							(font
								(size 1.27 1.27)
							)
						)
					)
					(number "248"
						(effects
							(font
								(size 1.27 1.27)
							)
						)
					)
				)
				(pin passive line
					(at 0 -55.88 0)
					(length 3.81)
					(hide yes)
					(name "VSS"
						(effects
							(font
								(size 1.27 1.27)
							)
						)
					)
					(number "251"
						(effects
							(font
								(size 1.27 1.27)
							)
						)
					)
				)
				(pin passive line
					(at 0 -55.88 0)
					(length 3.81)
					(hide yes)
					(name "VSS"
						(effects
							(font
								(size 1.27 1.27)
							)
						)
					)
					(number "253"
						(effects
							(font
								(size 1.27 1.27)
							)
						)
					)
				)
				(pin passive line
					(at 0 -55.88 0)
					(length 3.81)
					(hide yes)
					(name "VSS"
						(effects
							(font
								(size 1.27 1.27)
							)
						)
					)
					(number "255"
						(effects
							(font
								(size 1.27 1.27)
							)
						)
					)
				)
				(pin passive line
					(at 0 -55.88 0)
					(length 3.81)
					(hide yes)
					(name "VSS"
						(effects
							(font
								(size 1.27 1.27)
							)
						)
					)
					(number "257"
						(effects
							(font
								(size 1.27 1.27)
							)
						)
					)
				)
				(pin passive line
					(at 0 -55.88 0)
					(length 3.81)
					(hide yes)
					(name "VSS"
						(effects
							(font
								(size 1.27 1.27)
							)
						)
					)
					(number "259"
						(effects
							(font
								(size 1.27 1.27)
							)
						)
					)
				)
				(pin passive line
					(at 0 -55.88 0)
					(length 3.81)
					(hide yes)
					(name "VSS"
						(effects
							(font
								(size 1.27 1.27)
							)
						)
					)
					(number "26"
						(effects
							(font
								(size 1.27 1.27)
							)
						)
					)
				)
				(pin passive line
					(at 0 -55.88 0)
					(length 3.81)
					(hide yes)
					(name "VSS"
						(effects
							(font
								(size 1.27 1.27)
							)
						)
					)
					(number "262"
						(effects
							(font
								(size 1.27 1.27)
							)
						)
					)
				)
				(pin passive line
					(at 0 -55.88 0)
					(length 3.81)
					(hide yes)
					(name "VSS"
						(effects
							(font
								(size 1.27 1.27)
							)
						)
					)
					(number "264"
						(effects
							(font
								(size 1.27 1.27)
							)
						)
					)
				)
				(pin passive line
					(at 0 -55.88 0)
					(length 3.81)
					(hide yes)
					(name "VSS"
						(effects
							(font
								(size 1.27 1.27)
							)
						)
					)
					(number "266"
						(effects
							(font
								(size 1.27 1.27)
							)
						)
					)
				)
				(pin passive line
					(at 0 -55.88 0)
					(length 3.81)
					(hide yes)
					(name "VSS"
						(effects
							(font
								(size 1.27 1.27)
							)
						)
					)
					(number "268"
						(effects
							(font
								(size 1.27 1.27)
							)
						)
					)
				)
				(pin passive line
					(at 0 -55.88 0)
					(length 3.81)
					(hide yes)
					(name "VSS"
						(effects
							(font
								(size 1.27 1.27)
							)
						)
					)
					(number "270"
						(effects
							(font
								(size 1.27 1.27)
							)
						)
					)
				)
				(pin passive line
					(at 0 -55.88 0)
					(length 3.81)
					(hide yes)
					(name "VSS"
						(effects
							(font
								(size 1.27 1.27)
							)
						)
					)
					(number "273"
						(effects
							(font
								(size 1.27 1.27)
							)
						)
					)
				)
				(pin passive line
					(at 0 -55.88 0)
					(length 3.81)
					(hide yes)
					(name "VSS"
						(effects
							(font
								(size 1.27 1.27)
							)
						)
					)
					(number "275"
						(effects
							(font
								(size 1.27 1.27)
							)
						)
					)
				)
				(pin passive line
					(at 0 -55.88 0)
					(length 3.81)
					(hide yes)
					(name "VSS"
						(effects
							(font
								(size 1.27 1.27)
							)
						)
					)
					(number "277"
						(effects
							(font
								(size 1.27 1.27)
							)
						)
					)
				)
				(pin passive line
					(at 0 -55.88 0)
					(length 3.81)
					(hide yes)
					(name "VSS"
						(effects
							(font
								(size 1.27 1.27)
							)
						)
					)
					(number "279"
						(effects
							(font
								(size 1.27 1.27)
							)
						)
					)
				)
				(pin passive line
					(at 0 -55.88 0)
					(length 3.81)
					(hide yes)
					(name "VSS"
						(effects
							(font
								(size 1.27 1.27)
							)
						)
					)
					(number "28"
						(effects
							(font
								(size 1.27 1.27)
							)
						)
					)
				)
				(pin passive line
					(at 0 -55.88 0)
					(length 3.81)
					(hide yes)
					(name "VSS"
						(effects
							(font
								(size 1.27 1.27)
							)
						)
					)
					(number "281"
						(effects
							(font
								(size 1.27 1.27)
							)
						)
					)
				)
				(pin passive line
					(at 0 -55.88 0)
					(length 3.81)
					(hide yes)
					(name "VSS"
						(effects
							(font
								(size 1.27 1.27)
							)
						)
					)
					(number "284"
						(effects
							(font
								(size 1.27 1.27)
							)
						)
					)
				)
				(pin passive line
					(at 0 -55.88 0)
					(length 3.81)
					(hide yes)
					(name "VSS"
						(effects
							(font
								(size 1.27 1.27)
							)
						)
					)
					(number "286"
						(effects
							(font
								(size 1.27 1.27)
							)
						)
					)
				)
				(pin passive line
					(at 0 -55.88 0)
					(length 3.81)
					(hide yes)
					(name "VSS"
						(effects
							(font
								(size 1.27 1.27)
							)
						)
					)
					(number "288"
						(effects
							(font
								(size 1.27 1.27)
							)
						)
					)
				)
				(pin passive line
					(at 0 -55.88 0)
					(length 3.81)
					(hide yes)
					(name "VSS"
						(effects
							(font
								(size 1.27 1.27)
							)
						)
					)
					(number "30"
						(effects
							(font
								(size 1.27 1.27)
							)
						)
					)
				)
				(pin passive line
					(at 0 -55.88 0)
					(length 3.81)
					(hide yes)
					(name "VSS"
						(effects
							(font
								(size 1.27 1.27)
							)
						)
					)
					(number "32"
						(effects
							(font
								(size 1.27 1.27)
							)
						)
					)
				)
				(pin passive line
					(at 0 -55.88 0)
					(length 3.81)
					(hide yes)
					(name "VSS"
						(effects
							(font
								(size 1.27 1.27)
							)
						)
					)
					(number "35"
						(effects
							(font
								(size 1.27 1.27)
							)
						)
					)
				)
				(pin passive line
					(at 0 -55.88 0)
					(length 3.81)
					(hide yes)
					(name "VSS"
						(effects
							(font
								(size 1.27 1.27)
							)
						)
					)
					(number "37"
						(effects
							(font
								(size 1.27 1.27)
							)
						)
					)
				)
				(pin passive line
					(at 0 -55.88 0)
					(length 3.81)
					(hide yes)
					(name "VSS"
						(effects
							(font
								(size 1.27 1.27)
							)
						)
					)
					(number "39"
						(effects
							(font
								(size 1.27 1.27)
							)
						)
					)
				)
				(pin passive line
					(at 0 -55.88 0)
					(length 3.81)
					(hide yes)
					(name "VSS"
						(effects
							(font
								(size 1.27 1.27)
							)
						)
					)
					(number "41"
						(effects
							(font
								(size 1.27 1.27)
							)
						)
					)
				)
				(pin passive line
					(at 0 -55.88 0)
					(length 3.81)
					(hide yes)
					(name "VSS"
						(effects
							(font
								(size 1.27 1.27)
							)
						)
					)
					(number "43"
						(effects
							(font
								(size 1.27 1.27)
							)
						)
					)
				)
				(pin passive line
					(at 0 -55.88 0)
					(length 3.81)
					(hide yes)
					(name "VSS"
						(effects
							(font
								(size 1.27 1.27)
							)
						)
					)
					(number "46"
						(effects
							(font
								(size 1.27 1.27)
							)
						)
					)
				)
				(pin passive line
					(at 0 -55.88 0)
					(length 3.81)
					(hide yes)
					(name "VSS"
						(effects
							(font
								(size 1.27 1.27)
							)
						)
					)
					(number "48"
						(effects
							(font
								(size 1.27 1.27)
							)
						)
					)
				)
				(pin passive line
					(at 0 -55.88 0)
					(length 3.81)
					(hide yes)
					(name "VSS"
						(effects
							(font
								(size 1.27 1.27)
							)
						)
					)
					(number "50"
						(effects
							(font
								(size 1.27 1.27)
							)
						)
					)
				)
				(pin passive line
					(at 0 -55.88 0)
					(length 3.81)
					(hide yes)
					(name "VSS"
						(effects
							(font
								(size 1.27 1.27)
							)
						)
					)
					(number "52"
						(effects
							(font
								(size 1.27 1.27)
							)
						)
					)
				)
				(pin passive line
					(at 0 -55.88 0)
					(length 3.81)
					(hide yes)
					(name "VSS"
						(effects
							(font
								(size 1.27 1.27)
							)
						)
					)
					(number "54"
						(effects
							(font
								(size 1.27 1.27)
							)
						)
					)
				)
				(pin passive line
					(at 0 -55.88 0)
					(length 3.81)
					(hide yes)
					(name "VSS"
						(effects
							(font
								(size 1.27 1.27)
							)
						)
					)
					(number "57"
						(effects
							(font
								(size 1.27 1.27)
							)
						)
					)
				)
				(pin passive line
					(at 0 -55.88 0)
					(length 3.81)
					(hide yes)
					(name "VSS"
						(effects
							(font
								(size 1.27 1.27)
							)
						)
					)
					(number "59"
						(effects
							(font
								(size 1.27 1.27)
							)
						)
					)
				)
				(pin passive line
					(at 0 -55.88 0)
					(length 3.81)
					(hide yes)
					(name "VSS"
						(effects
							(font
								(size 1.27 1.27)
							)
						)
					)
					(number "6"
						(effects
							(font
								(size 1.27 1.27)
							)
						)
					)
				)
				(pin passive line
					(at 0 -55.88 0)
					(length 3.81)
					(hide yes)
					(name "VSS"
						(effects
							(font
								(size 1.27 1.27)
							)
						)
					)
					(number "61"
						(effects
							(font
								(size 1.27 1.27)
							)
						)
					)
				)
				(pin passive line
					(at 0 -55.88 0)
					(length 3.81)
					(hide yes)
					(name "VSS"
						(effects
							(font
								(size 1.27 1.27)
							)
						)
					)
					(number "63"
						(effects
							(font
								(size 1.27 1.27)
							)
						)
					)
				)
				(pin passive line
					(at 0 -55.88 0)
					(length 3.81)
					(hide yes)
					(name "VSS"
						(effects
							(font
								(size 1.27 1.27)
							)
						)
					)
					(number "65"
						(effects
							(font
								(size 1.27 1.27)
							)
						)
					)
				)
				(pin passive line
					(at 0 -55.88 0)
					(length 3.81)
					(hide yes)
					(name "VSS"
						(effects
							(font
								(size 1.27 1.27)
							)
						)
					)
					(number "67"
						(effects
							(font
								(size 1.27 1.27)
							)
						)
					)
				)
				(pin passive line
					(at 0 -55.88 0)
					(length 3.81)
					(hide yes)
					(name "VSS"
						(effects
							(font
								(size 1.27 1.27)
							)
						)
					)
					(number "69"
						(effects
							(font
								(size 1.27 1.27)
							)
						)
					)
				)
				(pin passive line
					(at 0 -55.88 0)
					(length 3.81)
					(hide yes)
					(name "VSS"
						(effects
							(font
								(size 1.27 1.27)
							)
						)
					)
					(number "71"
						(effects
							(font
								(size 1.27 1.27)
							)
						)
					)
				)
				(pin passive line
					(at 0 -55.88 0)
					(length 3.81)
					(hide yes)
					(name "VSS"
						(effects
							(font
								(size 1.27 1.27)
							)
						)
					)
					(number "73"
						(effects
							(font
								(size 1.27 1.27)
							)
						)
					)
				)
				(pin passive line
					(at 0 -55.88 0)
					(length 3.81)
					(hide yes)
					(name "VSS"
						(effects
							(font
								(size 1.27 1.27)
							)
						)
					)
					(number "77"
						(effects
							(font
								(size 1.27 1.27)
							)
						)
					)
				)
				(pin passive line
					(at 0 -55.88 0)
					(length 3.81)
					(hide yes)
					(name "VSS"
						(effects
							(font
								(size 1.27 1.27)
							)
						)
					)
					(number "79"
						(effects
							(font
								(size 1.27 1.27)
							)
						)
					)
				)
				(pin passive line
					(at 0 -55.88 0)
					(length 3.81)
					(hide yes)
					(name "VSS"
						(effects
							(font
								(size 1.27 1.27)
							)
						)
					)
					(number "8"
						(effects
							(font
								(size 1.27 1.27)
							)
						)
					)
				)
				(pin passive line
					(at 0 -55.88 0)
					(length 3.81)
					(hide yes)
					(name "VSS"
						(effects
							(font
								(size 1.27 1.27)
							)
						)
					)
					(number "81"
						(effects
							(font
								(size 1.27 1.27)
							)
						)
					)
				)
				(pin passive line
					(at 0 -55.88 0)
					(length 3.81)
					(hide yes)
					(name "VSS"
						(effects
							(font
								(size 1.27 1.27)
							)
						)
					)
					(number "83"
						(effects
							(font
								(size 1.27 1.27)
							)
						)
					)
				)
				(pin passive line
					(at 0 -55.88 0)
					(length 3.81)
					(hide yes)
					(name "VSS"
						(effects
							(font
								(size 1.27 1.27)
							)
						)
					)
					(number "85"
						(effects
							(font
								(size 1.27 1.27)
							)
						)
					)
				)
				(pin passive line
					(at 0 -55.88 0)
					(length 3.81)
					(hide yes)
					(name "VSS"
						(effects
							(font
								(size 1.27 1.27)
							)
						)
					)
					(number "88"
						(effects
							(font
								(size 1.27 1.27)
							)
						)
					)
				)
				(pin passive line
					(at 0 -55.88 0)
					(length 3.81)
					(hide yes)
					(name "VSS"
						(effects
							(font
								(size 1.27 1.27)
							)
						)
					)
					(number "90"
						(effects
							(font
								(size 1.27 1.27)
							)
						)
					)
				)
				(pin passive line
					(at 0 -55.88 0)
					(length 3.81)
					(hide yes)
					(name "VSS"
						(effects
							(font
								(size 1.27 1.27)
							)
						)
					)
					(number "92"
						(effects
							(font
								(size 1.27 1.27)
							)
						)
					)
				)
				(pin passive line
					(at 0 -55.88 0)
					(length 3.81)
					(hide yes)
					(name "VSS"
						(effects
							(font
								(size 1.27 1.27)
							)
						)
					)
					(number "95"
						(effects
							(font
								(size 1.27 1.27)
							)
						)
					)
				)
				(pin passive line
					(at 0 -55.88 0)
					(length 3.81)
					(hide yes)
					(name "VSS"
						(effects
							(font
								(size 1.27 1.27)
							)
						)
					)
					(number "97"
						(effects
							(font
								(size 1.27 1.27)
							)
						)
					)
				)
				(pin passive line
					(at 0 -55.88 0)
					(length 3.81)
					(hide yes)
					(name "VSS"
						(effects
							(font
								(size 1.27 1.27)
							)
						)
					)
					(number "99"
						(effects
							(font
								(size 1.27 1.27)
							)
						)
					)
				)
				(pin no_connect line
					(at 3.81 -45.72 0)
					(length 3.81)
					(hide yes)
					(name "RFU"
						(effects
							(font
								(size 1.27 1.27)
							)
						)
					)
					(number "150"
						(effects
							(font
								(size 1.27 1.27)
							)
						)
					)
				)
				(pin no_connect line
					(at 3.81 -48.26 0)
					(length 3.81)
					(hide yes)
					(name "RFU"
						(effects
							(font
								(size 1.27 1.27)
							)
						)
					)
					(number "2"
						(effects
							(font
								(size 1.27 1.27)
							)
						)
					)
				)
				(pin no_connect line
					(at 3.81 -50.8 0)
					(length 3.81)
					(hide yes)
					(name "RFU"
						(effects
							(font
								(size 1.27 1.27)
							)
						)
					)
					(number "144"
						(effects
							(font
								(size 1.27 1.27)
							)
						)
					)
				)
				(pin no_connect line
					(at 26.67 -45.72 180)
					(length 3.81)
					(hide yes)
					(name "RFU"
						(effects
							(font
								(size 1.27 1.27)
							)
						)
					)
					(number "149"
						(effects
							(font
								(size 1.27 1.27)
							)
						)
					)
				)
				(pin no_connect line
					(at 26.67 -48.26 180)
					(length 3.81)
					(hide yes)
					(name "RFU"
						(effects
							(font
								(size 1.27 1.27)
							)
						)
					)
					(number "232"
						(effects
							(font
								(size 1.27 1.27)
							)
						)
					)
				)
				(pin no_connect line
					(at 26.67 -50.8 180)
					(length 3.81)
					(hide yes)
					(name "RFU"
						(effects
							(font
								(size 1.27 1.27)
							)
						)
					)
					(number "220"
						(effects
							(font
								(size 1.27 1.27)
							)
						)
					)
				)
				(pin no_connect line
					(at 26.67 -53.34 180)
					(length 3.81)
					(hide yes)
					(name "RFU"
						(effects
							(font
								(size 1.27 1.27)
							)
						)
					)
					(number "231"
						(effects
							(font
								(size 1.27 1.27)
							)
						)
					)
				)
				(pin input line
					(at 30.48 0 180)
					(length 3.81)
					(name "HSA"
						(effects
							(font
								(size 1.27 1.27)
							)
						)
					)
					(number "148"
						(effects
							(font
								(size 1.27 1.27)
							)
						)
					)
				)
				(pin input line
					(at 30.48 -2.54 180)
					(length 3.81)
					(name "HSDA"
						(effects
							(font
								(size 1.27 1.27)
							)
						)
					)
					(number "5"
						(effects
							(font
								(size 1.27 1.27)
							)
						)
					)
				)
				(pin input line
					(at 30.48 -5.08 180)
					(length 3.81)
					(name "HSCL"
						(effects
							(font
								(size 1.27 1.27)
							)
						)
					)
					(number "4"
						(effects
							(font
								(size 1.27 1.27)
							)
						)
					)
				)
				(pin input line
					(at 30.48 -10.16 180)
					(length 3.81)
					(name "ALERT_N"
						(effects
							(font
								(size 1.27 1.27)
							)
						)
					)
					(number "62"
						(effects
							(font
								(size 1.27 1.27)
							)
						)
					)
				)
				(pin input line
					(at 30.48 -12.7 180)
					(length 3.81)
					(name "CK_T"
						(effects
							(font
								(size 1.27 1.27)
							)
						)
					)
					(number "217"
						(effects
							(font
								(size 1.27 1.27)
							)
						)
					)
				)
				(pin input line
					(at 30.48 -15.24 180)
					(length 3.81)
					(name "CK_C"
						(effects
							(font
								(size 1.27 1.27)
							)
						)
					)
					(number "218"
						(effects
							(font
								(size 1.27 1.27)
							)
						)
					)
				)
				(pin input line
					(at 30.48 -20.32 180)
					(length 3.81)
					(name "CA0_B"
						(effects
							(font
								(size 1.27 1.27)
							)
						)
					)
					(number "76"
						(effects
							(font
								(size 1.27 1.27)
							)
						)
					)
				)
				(pin input line
					(at 30.48 -22.86 180)
					(length 3.81)
					(name "CA1_B"
						(effects
							(font
								(size 1.27 1.27)
							)
						)
					)
					(number "221"
						(effects
							(font
								(size 1.27 1.27)
							)
						)
					)
				)
				(pin input line
					(at 30.48 -25.4 180)
					(length 3.81)
					(name "CA2_B"
						(effects
							(font
								(size 1.27 1.27)
							)
						)
					)
					(number "78"
						(effects
							(font
								(size 1.27 1.27)
							)
						)
					)
				)
				(pin input line
					(at 30.48 -27.94 180)
					(length 3.81)
					(name "CA3_B"
						(effects
							(font
								(size 1.27 1.27)
							)
						)
					)
					(number "223"
						(effects
							(font
								(size 1.27 1.27)
							)
						)
					)
				)
				(pin input line
					(at 30.48 -30.48 180)
					(length 3.81)
					(name "CA4_B"
						(effects
							(font
								(size 1.27 1.27)
							)
						)
					)
					(number "80"
						(effects
							(font
								(size 1.27 1.27)
							)
						)
					)
				)
				(pin input line
					(at 30.48 -33.02 180)
					(length 3.81)
					(name "CA5_B"
						(effects
							(font
								(size 1.27 1.27)
							)
						)
					)
					(number "225"
						(effects
							(font
								(size 1.27 1.27)
							)
						)
					)
				)
				(pin input line
					(at 30.48 -35.56 180)
					(length 3.81)
					(name "CA6_B"
						(effects
							(font
								(size 1.27 1.27)
							)
						)
					)
					(number "82"
						(effects
							(font
								(size 1.27 1.27)
							)
						)
					)
				)
				(pin input line
					(at 30.48 -38.1 180)
					(length 3.81)
					(name "PAR_B"
						(effects
							(font
								(size 1.27 1.27)
							)
						)
					)
					(number "227"
						(effects
							(font
								(size 1.27 1.27)
							)
						)
					)
				)
				(pin input line
					(at 30.48 -40.64 180)
					(length 3.81)
					(name "CS0_B_N"
						(effects
							(font
								(size 1.27 1.27)
							)
						)
					)
					(number "84"
						(effects
							(font
								(size 1.27 1.27)
							)
						)
					)
				)
				(pin input line
					(at 30.48 -43.18 180)
					(length 3.81)
					(name "CS1_B_N"
						(effects
							(font
								(size 1.27 1.27)
							)
						)
					)
					(number "229"
						(effects
							(font
								(size 1.27 1.27)
							)
						)
					)
				)
				(pin passive line
					(at 30.48 -55.88 180)
					(length 3.81)
					(name "SH"
						(effects
							(font
								(size 1.27 1.27)
							)
						)
					)
					(number "S1"
						(effects
							(font
								(size 1.27 1.27)
							)
						)
					)
				)
				(pin passive line
					(at 30.48 -58.42 180)
					(length 3.81)
					(name "SH"
						(effects
							(font
								(size 1.27 1.27)
							)
						)
					)
					(number "S2"
						(effects
							(font
								(size 1.27 1.27)
							)
						)
					)
				)
				(pin passive line
					(at 30.48 -60.96 180)
					(length 3.81)
					(name "SH"
						(effects
							(font
								(size 1.27 1.27)
							)
						)
					)
					(number "S3"
						(effects
							(font
								(size 1.27 1.27)
							)
						)
					)
				)
			)
		)
	(symbol "antmicroMemoryConnectorsPCCardSockets:MicroSD_693071020811"
			(exclude_from_sim no)
			(in_bom yes)
			(on_board yes)
			(property "Reference" "J"
				(at 55.88 -2.54 0)
				(effects
					(font
						(size 1.27 1.27)
						(thickness 0.15)
					)
					(justify left bottom)
				)
			)
			(property "Value" "MicroSD_693071020811"
				(at 55.88 -5.08 0)
				(effects
					(font
						(size 1.27 1.27)
						(thickness 0.15)
					)
					(justify left bottom)
					(hide yes)
				)
			)
			(property "Footprint" "antmicro-footprints:MicroSD_Wurth_693071020811"
				(at 55.88 -7.62 0)
				(effects
					(font
						(size 1.27 1.27)
						(thickness 0.15)
					)
					(justify left bottom)
					(hide yes)
				)
			)
			(property "Datasheet" "https://www.we-online.com/catalog/datasheet/693071020811.pdf"
				(at 55.88 -10.16 0)
				(effects
					(font
						(size 1.27 1.27)
						(thickness 0.15)
					)
					(justify left bottom)
					(hide yes)
				)
			)
			(property "Description" "Memory Card Connector, MicroSD, Push-Push, 8 Contacts, Copper Alloy, Gold Plated Contacts, WR-CRD"
				(at 0 0 0)
				(effects
					(font
						(size 1.27 1.27)
					)
					(hide yes)
				)
			)
			(property "Manufacturer" "Würth Elektronik"
				(at 55.88 -12.7 0)
				(effects
					(font
						(size 1.27 1.27)
						(thickness 0.15)
					)
					(justify left bottom)
					(hide yes)
				)
			)
			(property "MPN" "693071020811"
				(at 55.88 -15.24 0)
				(effects
					(font
						(size 1.27 1.27)
						(thickness 0.15)
					)
					(justify left bottom)
				)
			)
			(property "Author" "Antmicro"
				(at 55.88 -17.78 0)
				(effects
					(font
						(size 1.27 1.27)
						(thickness 0.15)
					)
					(justify left bottom)
					(hide yes)
				)
			)
			(property "License" "Apache-2.0"
				(at 55.88 -20.32 0)
				(effects
					(font
						(size 1.27 1.27)
						(thickness 0.15)
					)
					(justify left bottom)
					(hide yes)
				)
			)
			(property "ki_keywords" "HORIZONTAL, SMT, MEMORY, CONNECTOR"
				(at 0 0 0)
				(effects
					(font
						(size 1.27 1.27)
					)
					(hide yes)
				)
			)
			(symbol "MicroSD_693071020811_1_1"
				(polyline
					(pts
						(xy 12.7 -21.59) (xy 12.7 -1.27) (xy 20.32 -1.27) (xy 24.13 2.54) (xy 25.4 2.54) (xy 25.4 1.27)
						(xy 27.94 1.27) (xy 29.21 2.54) (xy 41.91 2.54) (xy 41.91 -21.59) (xy 12.7 -21.59)
					)
					(stroke
						(width 0.254)
						(type default)
					)
					(fill
						(type background)
					)
				)
				(rectangle
					(start 13.97 -1.905)
					(end 16.51 -3.175)
					(stroke
						(width 0.254)
						(type default)
					)
					(fill
						(type outline)
					)
				)
				(rectangle
					(start 13.97 -4.445)
					(end 16.51 -5.715)
					(stroke
						(width 0.254)
						(type default)
					)
					(fill
						(type outline)
					)
				)
				(rectangle
					(start 13.97 -6.985)
					(end 16.51 -8.255)
					(stroke
						(width 0.254)
						(type default)
					)
					(fill
						(type outline)
					)
				)
				(rectangle
					(start 13.97 -9.525)
					(end 16.51 -10.795)
					(stroke
						(width 0.254)
						(type default)
					)
					(fill
						(type outline)
					)
				)
				(rectangle
					(start 13.97 -12.065)
					(end 16.51 -13.335)
					(stroke
						(width 0.254)
						(type default)
					)
					(fill
						(type outline)
					)
				)
				(rectangle
					(start 13.97 -14.605)
					(end 16.51 -15.875)
					(stroke
						(width 0.254)
						(type default)
					)
					(fill
						(type outline)
					)
				)
				(rectangle
					(start 13.97 -17.145)
					(end 16.51 -18.415)
					(stroke
						(width 0.254)
						(type default)
					)
					(fill
						(type outline)
					)
				)
				(rectangle
					(start 13.97 -19.685)
					(end 16.51 -20.955)
					(stroke
						(width 0.254)
						(type default)
					)
					(fill
						(type outline)
					)
				)
				(polyline
					(pts
						(xy 38.1 2.54) (xy 38.1 3.81) (xy 2.54 3.81) (xy 2.54 -29.21) (xy 38.1 -29.21) (xy 38.1 -21.59)
					)
					(stroke
						(width 0.254)
						(type default)
					)
					(fill
						(type background)
					)
				)
				(pin power_in line
					(at 0 0 0)
					(length 2.54)
					(name "VDD"
						(effects
							(font
								(size 1.27 1.27)
							)
						)
					)
					(number "4"
						(effects
							(font
								(size 1.27 1.27)
							)
						)
					)
				)
				(pin bidirectional line
					(at 0 -5.08 0)
					(length 2.54)
					(name "DAT2"
						(effects
							(font
								(size 1.27 1.27)
							)
						)
					)
					(number "1"
						(effects
							(font
								(size 1.27 1.27)
							)
						)
					)
				)
				(pin bidirectional line
					(at 0 -7.62 0)
					(length 2.54)
					(name "DAT3/CD"
						(effects
							(font
								(size 1.27 1.27)
							)
						)
					)
					(number "2"
						(effects
							(font
								(size 1.27 1.27)
							)
						)
					)
				)
				(pin input line
					(at 0 -10.16 0)
					(length 2.54)
					(name "CMD"
						(effects
							(font
								(size 1.27 1.27)
							)
						)
					)
					(number "3"
						(effects
							(font
								(size 1.27 1.27)
							)
						)
					)
				)
				(pin input line
					(at 0 -12.7 0)
					(length 2.54)
					(name "CLK"
						(effects
							(font
								(size 1.27 1.27)
							)
						)
					)
					(number "5"
						(effects
							(font
								(size 1.27 1.27)
							)
						)
					)
				)
				(pin input line
					(at 0 -15.24 0)
					(length 2.54)
					(name "DAT0"
						(effects
							(font
								(size 1.27 1.27)
							)
						)
					)
					(number "7"
						(effects
							(font
								(size 1.27 1.27)
							)
						)
					)
				)
				(pin input line
					(at 0 -17.78 0)
					(length 2.54)
					(name "DAT1"
						(effects
							(font
								(size 1.27 1.27)
							)
						)
					)
					(number "8"
						(effects
							(font
								(size 1.27 1.27)
							)
						)
					)
				)
				(pin passive line
					(at 0 -20.32 0)
					(length 2.54)
					(name "CD_SW1"
						(effects
							(font
								(size 1.27 1.27)
							)
						)
					)
					(number "9"
						(effects
							(font
								(size 1.27 1.27)
							)
						)
					)
				)
				(pin passive line
					(at 0 -26.67 0)
					(length 2.54)
					(name "VSS"
						(effects
							(font
								(size 1.27 1.27)
							)
						)
					)
					(number "6"
						(effects
							(font
								(size 1.27 1.27)
							)
						)
					)
				)
				(pin passive line
					(at 40.64 -26.67 180)
					(length 2.54)
					(name "SH"
						(effects
							(font
								(size 1.27 1.27)
							)
						)
					)
					(number "SH"
						(effects
							(font
								(size 1.27 1.27)
							)
						)
					)
				)
			)
		)
	(symbol "antmicroModularConnectorsJacks:RJ45_Abracon_ARJM11B1-502-AB-EW2"
			(exclude_from_sim no)
			(in_bom yes)
			(on_board yes)
			(property "Reference" "J"
				(at 35.56 -2.54 0)
				(effects
					(font
						(size 1.27 1.27)
						(thickness 0.15)
					)
					(justify left bottom)
				)
			)
			(property "Value" "RJ45_Abracon_ARJM11B1-502-AB-EW2"
				(at 35.56 -7.62 0)
				(effects
					(font
						(size 1.27 1.27)
						(thickness 0.15)
					)
					(justify left bottom)
					(hide yes)
				)
			)
			(property "Footprint" "antmicro-footprints:RJ45_ARJM11B1-502-AB-EW2_Horizontal"
				(at 35.56 -10.16 0)
				(effects
					(font
						(size 1.27 1.27)
						(thickness 0.15)
					)
					(justify left bottom)
					(hide yes)
				)
			)
			(property "Datasheet" "https://www.mouser.com/datasheet/3/184/1/ARJM11.pdf"
				(at 35.56 -12.7 0)
				(effects
					(font
						(size 1.27 1.27)
						(thickness 0.15)
					)
					(justify left bottom)
					(hide yes)
				)
			)
			(property "Description" "Modular Connectors / Ethernet Connectors RJ45 JACK W/MAG 1X1 1000BASE-T"
				(at 35.56 -22.606 0)
				(effects
					(font
						(size 1.27 1.27)
					)
					(justify left bottom)
					(hide yes)
				)
			)
			(property "MPN" "ARJM11B1-502-AB-EW2"
				(at 35.56 -5.08 0)
				(effects
					(font
						(size 1.27 1.27)
						(thickness 0.15)
					)
					(justify left bottom)
				)
			)
			(property "Manufacturer" "Abracon"
				(at 35.56 -15.24 0)
				(effects
					(font
						(size 1.27 1.27)
						(thickness 0.15)
					)
					(justify left bottom)
					(hide yes)
				)
			)
			(property "Author" "Antmicro"
				(at 35.56 -17.526 0)
				(effects
					(font
						(size 1.27 1.27)
						(thickness 0.15)
					)
					(justify left bottom)
					(hide yes)
				)
			)
			(property "License" "Apache-2.0"
				(at 35.56 -20.066 0)
				(effects
					(font
						(size 1.27 1.27)
						(thickness 0.15)
					)
					(justify left bottom)
					(hide yes)
				)
			)
			(property "ki_keywords" "CONNECTOR, RJ45, THT, ETHERNET, HORIZONTAL"
				(at 0 0 0)
				(effects
					(font
						(size 1.27 1.27)
					)
					(hide yes)
				)
			)
			(symbol "RJ45_Abracon_ARJM11B1-502-AB-EW2_1_1"
				(rectangle
					(start 2.54 2.54)
					(end 20.32 -30.48)
					(stroke
						(width 0.254)
						(type default)
					)
					(fill
						(type background)
					)
				)
				(rectangle
					(start 6.35 -4.445)
					(end 17.78 -18.415)
					(stroke
						(width 0.254)
						(type default)
					)
					(fill
						(type background)
					)
				)
				(polyline
					(pts
						(xy 7.62 -5.715) (xy 13.97 -5.715)
					)
					(stroke
						(width 0.254)
						(type default)
					)
					(fill
						(type background)
					)
				)
				(polyline
					(pts
						(xy 7.62 -17.145) (xy 7.62 -5.715)
					)
					(stroke
						(width 0.254)
						(type default)
					)
					(fill
						(type background)
					)
				)
				(polyline
					(pts
						(xy 13.97 -5.715) (xy 13.97 -6.985)
					)
					(stroke
						(width 0.254)
						(type default)
					)
					(fill
						(type background)
					)
				)
				(polyline
					(pts
						(xy 13.97 -6.985) (xy 15.24 -6.985)
					)
					(stroke
						(width 0.254)
						(type default)
					)
					(fill
						(type background)
					)
				)
				(polyline
					(pts
						(xy 13.97 -15.875) (xy 15.24 -15.875)
					)
					(stroke
						(width 0.254)
						(type default)
					)
					(fill
						(type background)
					)
				)
				(polyline
					(pts
						(xy 13.97 -17.145) (xy 7.62 -17.145)
					)
					(stroke
						(width 0.254)
						(type default)
					)
					(fill
						(type background)
					)
				)
				(polyline
					(pts
						(xy 13.97 -17.145) (xy 13.97 -15.875)
					)
					(stroke
						(width 0.254)
						(type default)
					)
					(fill
						(type background)
					)
				)
				(polyline
					(pts
						(xy 15.24 -6.985) (xy 15.24 -8.255)
					)
					(stroke
						(width 0.254)
						(type default)
					)
					(fill
						(type background)
					)
				)
				(polyline
					(pts
						(xy 15.24 -8.255) (xy 16.51 -8.255)
					)
					(stroke
						(width 0.254)
						(type default)
					)
					(fill
						(type background)
					)
				)
				(polyline
					(pts
						(xy 15.24 -14.605) (xy 16.51 -14.605)
					)
					(stroke
						(width 0.254)
						(type default)
					)
					(fill
						(type background)
					)
				)
				(polyline
					(pts
						(xy 15.24 -15.875) (xy 15.24 -14.605)
					)
					(stroke
						(width 0.254)
						(type default)
					)
					(fill
						(type background)
					)
				)
				(polyline
					(pts
						(xy 16.51 -8.255) (xy 16.51 -14.605)
					)
					(stroke
						(width 0.254)
						(type default)
					)
					(fill
						(type background)
					)
				)
				(pin bidirectional line
					(at 0 0 0)
					(length 2.54)
					(name "1"
						(effects
							(font
								(size 1.27 1.27)
							)
						)
					)
					(number "1"
						(effects
							(font
								(size 1.27 1.27)
							)
						)
					)
				)
				(pin bidirectional line
					(at 0 -2.54 0)
					(length 2.54)
					(name "2"
						(effects
							(font
								(size 1.27 1.27)
							)
						)
					)
					(number "2"
						(effects
							(font
								(size 1.27 1.27)
							)
						)
					)
				)
				(pin bidirectional line
					(at 0 -5.08 0)
					(length 2.54)
					(name "3"
						(effects
							(font
								(size 1.27 1.27)
							)
						)
					)
					(number "3"
						(effects
							(font
								(size 1.27 1.27)
							)
						)
					)
				)
				(pin bidirectional line
					(at 0 -7.62 0)
					(length 2.54)
					(name "4"
						(effects
							(font
								(size 1.27 1.27)
							)
						)
					)
					(number "4"
						(effects
							(font
								(size 1.27 1.27)
							)
						)
					)
				)
				(pin bidirectional line
					(at 0 -10.16 0)
					(length 2.54)
					(name "7"
						(effects
							(font
								(size 1.27 1.27)
							)
						)
					)
					(number "7"
						(effects
							(font
								(size 1.27 1.27)
							)
						)
					)
				)
				(pin bidirectional line
					(at 0 -12.7 0)
					(length 2.54)
					(name "8"
						(effects
							(font
								(size 1.27 1.27)
							)
						)
					)
					(number "8"
						(effects
							(font
								(size 1.27 1.27)
							)
						)
					)
				)
				(pin bidirectional line
					(at 0 -15.24 0)
					(length 2.54)
					(name "9"
						(effects
							(font
								(size 1.27 1.27)
							)
						)
					)
					(number "9"
						(effects
							(font
								(size 1.27 1.27)
							)
						)
					)
				)
				(pin bidirectional line
					(at 0 -17.78 0)
					(length 2.54)
					(name "10"
						(effects
							(font
								(size 1.27 1.27)
							)
						)
					)
					(number "10"
						(effects
							(font
								(size 1.27 1.27)
							)
						)
					)
				)
				(pin passive line
					(at 0 -21.59 0)
					(length 2.54)
					(name "5"
						(effects
							(font
								(size 1.27 1.27)
							)
						)
					)
					(number "5"
						(effects
							(font
								(size 1.27 1.27)
							)
						)
					)
				)
				(pin passive line
					(at 0 -24.13 0)
					(length 2.54)
					(name "6"
						(effects
							(font
								(size 1.27 1.27)
							)
						)
					)
					(number "6"
						(effects
							(font
								(size 1.27 1.27)
							)
						)
					)
				)
				(pin passive line
					(at 0 -27.94 0)
					(length 2.54)
					(name "SH"
						(effects
							(font
								(size 1.27 1.27)
							)
						)
					)
					(number "SH"
						(effects
							(font
								(size 1.27 1.27)
							)
						)
					)
				)
				(pin passive line
					(at 22.86 0 180)
					(length 2.54)
					(name "LED_Y+"
						(effects
							(font
								(size 1.27 1.27)
							)
						)
					)
					(number "13"
						(effects
							(font
								(size 1.27 1.27)
							)
						)
					)
				)
				(pin passive line
					(at 22.86 -2.54 180)
					(length 2.54)
					(name "LED_Y-"
						(effects
							(font
								(size 1.27 1.27)
							)
						)
					)
					(number "14"
						(effects
							(font
								(size 1.27 1.27)
							)
						)
					)
				)
				(pin passive line
					(at 22.86 -25.4 180)
					(length 2.54)
					(name "LED_G+"
						(effects
							(font
								(size 1.27 1.27)
							)
						)
					)
					(number "11"
						(effects
							(font
								(size 1.27 1.27)
							)
						)
					)
				)
				(pin passive line
					(at 22.86 -27.94 180)
					(length 2.54)
					(name "LED_G-"
						(effects
							(font
								(size 1.27 1.27)
							)
						)
					)
					(number "12"
						(effects
							(font
								(size 1.27 1.27)
							)
						)
					)
				)
			)
		)
	(symbol "antmicroOscillators:Oscillator_100MHz_SG3225VAN"
			(exclude_from_sim no)
			(in_bom yes)
			(on_board yes)
			(property "Reference" "Y"
				(at 20.32 -10.16 0)
				(effects
					(font
						(size 1.27 1.27)
						(thickness 0.15)
					)
					(justify left bottom)
				)
			)
			(property "Value" "Oscillator_100MHz_SG3225VAN"
				(at 20.32 -20.32 0)
				(effects
					(font
						(size 1.27 1.27)
						(thickness 0.15)
					)
					(justify left bottom)
					(hide yes)
				)
			)
			(property "Footprint" "antmicro-footprints:Oscillator_SMD_Epson_SG3225EEN_3.2x2.5x1.2mm"
				(at 20.32 -22.86 0)
				(effects
					(font
						(size 1.27 1.27)
						(thickness 0.15)
					)
					(justify left bottom)
					(hide yes)
				)
			)
			(property "Datasheet" "https://support.epson.biz/td/api/doc_check.php?dl=brief_SG5032VAN&lang=en"
				(at 20.32 -25.4 0)
				(effects
					(font
						(size 1.27 1.27)
						(thickness 0.15)
					)
					(justify left bottom)
					(hide yes)
				)
			)
			(property "Description" "100 MHz XO (Standard) LVPECL Oscillator 3.3V Enable/Disable 6-SMD, No Lead"
				(at 0 0 0)
				(effects
					(font
						(size 1.27 1.27)
					)
					(hide yes)
				)
			)
			(property "Manufacturer" "Epson"
				(at 20.32 -12.7 0)
				(effects
					(font
						(size 1.27 1.27)
						(thickness 0.15)
					)
					(justify left bottom)
					(hide yes)
				)
			)
			(property "MPN" "SG3225VAN_100.000000M-KEGA3"
				(at 20.32 -15.24 0)
				(effects
					(font
						(size 1.27 1.27)
						(thickness 0.15)
					)
					(justify left bottom)
				)
			)
			(property "Val" "100MHz"
				(at 20.32 -17.78 0)
				(effects
					(font
						(size 1.27 1.27)
						(thickness 0.15)
					)
					(justify left bottom)
				)
			)
			(property "Author" "Antmicro"
				(at 20.32 -27.94 0)
				(effects
					(font
						(size 1.27 1.27)
						(thickness 0.15)
					)
					(justify left bottom)
					(hide yes)
				)
			)
			(property "License" "Apache-2.0"
				(at 20.32 -30.48 0)
				(effects
					(font
						(size 1.27 1.27)
						(thickness 0.15)
					)
					(justify left bottom)
					(hide yes)
				)
			)
			(property "ki_keywords" "OSCILLATOR, LVDS"
				(at 0 0 0)
				(effects
					(font
						(size 1.27 1.27)
					)
					(hide yes)
				)
			)
			(symbol "Oscillator_100MHz_SG3225VAN_1_1"
				(rectangle
					(start 2.54 2.54)
					(end 16.51 -7.62)
					(stroke
						(width 0.254)
						(type default)
					)
					(fill
						(type background)
					)
				)
				(polyline
					(pts
						(xy 7.62 -1.27) (xy 8.255 -1.27) (xy 8.255 0) (xy 8.89 0) (xy 8.89 -1.27) (xy 9.525 -1.27) (xy 9.525 0)
						(xy 10.16 0) (xy 10.16 -1.27)
					)
					(stroke
						(width 0.254)
						(type default)
					)
					(fill
						(type background)
					)
				)
				(pin power_in line
					(at 0 0 0)
					(length 2.54)
					(name "VCC"
						(effects
							(font
								(size 1.27 1.27)
							)
						)
					)
					(number "6"
						(effects
							(font
								(size 1.27 1.27)
							)
						)
					)
				)
				(pin input line
					(at 0 -2.54 0)
					(length 2.54)
					(name "EN"
						(effects
							(font
								(size 1.27 1.27)
							)
						)
					)
					(number "1"
						(effects
							(font
								(size 1.27 1.27)
							)
						)
					)
				)
				(pin power_in line
					(at 0 -5.08 0)
					(length 2.54)
					(name "GND"
						(effects
							(font
								(size 1.27 1.27)
							)
						)
					)
					(number "3"
						(effects
							(font
								(size 1.27 1.27)
							)
						)
					)
				)
				(pin no_connect line
					(at 16.51 -5.08 180)
					(length 2.54)
					(hide yes)
					(name "NC"
						(effects
							(font
								(size 1.27 1.27)
							)
						)
					)
					(number "2"
						(effects
							(font
								(size 1.27 1.27)
							)
						)
					)
				)
				(pin output line
					(at 19.05 0 180)
					(length 2.54)
					(name "OUT+"
						(effects
							(font
								(size 1.27 1.27)
							)
						)
					)
					(number "4"
						(effects
							(font
								(size 1.27 1.27)
							)
						)
					)
				)
				(pin output line
					(at 19.05 -2.54 180)
					(length 2.54)
					(name "OUT-"
						(effects
							(font
								(size 1.27 1.27)
							)
						)
					)
					(number "5"
						(effects
							(font
								(size 1.27 1.27)
							)
						)
					)
				)
			)
		)
	(symbol "antmicroPMICORControllersIdealDiodes:LTC4412IS6"
			(exclude_from_sim no)
			(in_bom yes)
			(on_board yes)
			(property "Reference" "U"
				(at 31.75 -2.54 0)
				(effects
					(font
						(size 1.27 1.27)
						(thickness 0.15)
					)
					(justify left bottom)
				)
			)
			(property "Value" "LTC4412IS6"
				(at 31.75 -5.08 0)
				(effects
					(font
						(size 1.27 1.27)
						(thickness 0.15)
					)
					(justify left bottom)
				)
			)
			(property "Footprint" "antmicro-footprints:SOT-23-6"
				(at 31.75 -7.62 0)
				(effects
					(font
						(size 1.27 1.27)
						(thickness 0.15)
					)
					(justify left bottom)
					(hide yes)
				)
			)
			(property "Datasheet" "https://www.mouser.com/datasheet/2/308/NCV8187_D-1813214.pdf"
				(at 31.75 -10.16 0)
				(effects
					(font
						(size 1.27 1.27)
						(thickness 0.15)
					)
					(justify left bottom)
					(hide yes)
				)
			)
			(property "Description" "Ideal diode controller"
				(at 0 0 0)
				(effects
					(font
						(size 1.27 1.27)
					)
					(hide yes)
				)
			)
			(property "MPN" "LTC4412IS6#TRMPBF"
				(at 31.75 -12.7 0)
				(effects
					(font
						(size 1.27 1.27)
						(thickness 0.15)
					)
					(justify left bottom)
					(hide yes)
				)
			)
			(property "Manufacturer" "Analog Devices"
				(at 31.75 -15.24 0)
				(effects
					(font
						(size 1.27 1.27)
						(thickness 0.15)
					)
					(justify left bottom)
					(hide yes)
				)
			)
			(property "Author" "Antmicro"
				(at 31.75 -17.78 0)
				(effects
					(font
						(size 1.27 1.27)
						(thickness 0.15)
					)
					(justify left bottom)
					(hide yes)
				)
			)
			(property "License" "Apache-2.0"
				(at 31.75 -20.32 0)
				(effects
					(font
						(size 1.27 1.27)
						(thickness 0.15)
					)
					(justify left bottom)
					(hide yes)
				)
			)
			(property "ki_keywords" "SMT, CONTROLLER, IC, DIODE"
				(at 0 0 0)
				(effects
					(font
						(size 1.27 1.27)
					)
					(hide yes)
				)
			)
			(symbol "LTC4412IS6_1_1"
				(rectangle
					(start 2.54 2.54)
					(end 15.24 -7.62)
					(stroke
						(width 0.254)
						(type default)
					)
					(fill
						(type background)
					)
				)
				(pin power_in line
					(at 0 0 0)
					(length 2.54)
					(name "IN"
						(effects
							(font
								(size 1.27 1.27)
							)
						)
					)
					(number "1"
						(effects
							(font
								(size 1.27 1.27)
							)
						)
					)
				)
				(pin input line
					(at 0 -2.54 0)
					(length 2.54)
					(name "CTL"
						(effects
							(font
								(size 1.27 1.27)
							)
						)
					)
					(number "3"
						(effects
							(font
								(size 1.27 1.27)
							)
						)
					)
				)
				(pin power_in line
					(at 0 -5.08 0)
					(length 2.54)
					(name "GND"
						(effects
							(font
								(size 1.27 1.27)
							)
						)
					)
					(number "2"
						(effects
							(font
								(size 1.27 1.27)
							)
						)
					)
				)
				(pin input line
					(at 17.78 0 180)
					(length 2.54)
					(name "SENSE"
						(effects
							(font
								(size 1.27 1.27)
							)
						)
					)
					(number "6"
						(effects
							(font
								(size 1.27 1.27)
							)
						)
					)
				)
				(pin output line
					(at 17.78 -2.54 180)
					(length 2.54)
					(name "GATE"
						(effects
							(font
								(size 1.27 1.27)
							)
						)
					)
					(number "5"
						(effects
							(font
								(size 1.27 1.27)
							)
						)
					)
				)
				(pin output line
					(at 17.78 -5.08 180)
					(length 2.54)
					(name "STAT"
						(effects
							(font
								(size 1.27 1.27)
							)
						)
					)
					(number "4"
						(effects
							(font
								(size 1.27 1.27)
							)
						)
					)
				)
			)
		)
	(symbol "antmicroPMICPowerDistributionSwitchesLoadDrivers:TPS2116DRLR"
			(exclude_from_sim no)
			(in_bom yes)
			(on_board yes)
			(property "Reference" "U"
				(at 34.29 0 0)
				(effects
					(font
						(size 1.27 1.27)
						(thickness 0.15)
					)
					(justify left bottom)
				)
			)
			(property "Value" "TPS2116DRLR"
				(at 34.29 -2.54 0)
				(effects
					(font
						(size 1.27 1.27)
						(thickness 0.15)
					)
					(justify left bottom)
					(hide yes)
				)
			)
			(property "Footprint" "antmicro-footprints:SOT-583"
				(at 34.29 -5.08 0)
				(effects
					(font
						(size 1.27 1.27)
						(thickness 0.15)
					)
					(justify left bottom)
					(hide yes)
				)
			)
			(property "Datasheet" "https://www.ti.com/lit/ds/symlink/tps2116.pdf?ts=1647438832100&ref_url=https%253A%252F%252Fwww.ti.com%252Fproduct%252FTPS2116"
				(at 34.29 -7.62 0)
				(effects
					(font
						(size 1.27 1.27)
						(thickness 0.15)
					)
					(justify left bottom)
					(hide yes)
				)
			)
			(property "Description" "Power switch"
				(at 0 0 0)
				(effects
					(font
						(size 1.27 1.27)
					)
					(hide yes)
				)
			)
			(property "Manufacturer" "Texas Instruments"
				(at 34.29 -10.16 0)
				(effects
					(font
						(size 1.27 1.27)
						(thickness 0.15)
					)
					(justify left bottom)
					(hide yes)
				)
			)
			(property "MPN" "TPS2116DRLR"
				(at 34.29 -12.7 0)
				(effects
					(font
						(size 1.27 1.27)
						(thickness 0.15)
					)
					(justify left bottom)
				)
			)
			(property "Author" "Antmicro"
				(at 34.29 -15.24 0)
				(effects
					(font
						(size 1.27 1.27)
						(thickness 0.15)
					)
					(justify left bottom)
					(hide yes)
				)
			)
			(property "License" "Apache-2.0"
				(at 34.29 -17.78 0)
				(effects
					(font
						(size 1.27 1.27)
						(thickness 0.15)
					)
					(justify left bottom)
					(hide yes)
				)
			)
			(property "ki_keywords" "SMT, SWITCH, IC, POWER, DRIVER"
				(at 0 0 0)
				(effects
					(font
						(size 1.27 1.27)
					)
					(hide yes)
				)
			)
			(property "ki_fp_filters" "DRL0008A-MFG"
				(at 0 0 0)
				(effects
					(font
						(size 1.27 1.27)
					)
					(hide yes)
				)
			)
			(symbol "TPS2116DRLR_1_1"
				(rectangle
					(start 2.54 2.54)
					(end 15.24 -10.16)
					(stroke
						(width 0.254)
						(type default)
					)
					(fill
						(type background)
					)
				)
				(pin power_in line
					(at 0 0 0)
					(length 2.54)
					(name "VIN1"
						(effects
							(font
								(size 1.27 1.27)
							)
						)
					)
					(number "3"
						(effects
							(font
								(size 1.27 1.27)
							)
						)
					)
				)
				(pin input line
					(at 0 -2.54 0)
					(length 2.54)
					(name "MODE"
						(effects
							(font
								(size 1.27 1.27)
							)
						)
					)
					(number "5"
						(effects
							(font
								(size 1.27 1.27)
							)
						)
					)
				)
				(pin input line
					(at 0 -5.08 0)
					(length 2.54)
					(name "PR1"
						(effects
							(font
								(size 1.27 1.27)
							)
						)
					)
					(number "4"
						(effects
							(font
								(size 1.27 1.27)
							)
						)
					)
				)
				(pin power_in line
					(at 0 -7.62 0)
					(length 2.54)
					(name "VIN2"
						(effects
							(font
								(size 1.27 1.27)
							)
						)
					)
					(number "6"
						(effects
							(font
								(size 1.27 1.27)
							)
						)
					)
				)
				(pin power_out line
					(at 17.78 0 180)
					(length 2.54)
					(name "VOUT"
						(effects
							(font
								(size 1.27 1.27)
							)
						)
					)
					(number "2"
						(effects
							(font
								(size 1.27 1.27)
							)
						)
					)
				)
				(pin passive line
					(at 17.78 0 180)
					(length 2.54)
					(hide yes)
					(name "VOUT"
						(effects
							(font
								(size 1.27 1.27)
							)
						)
					)
					(number "7"
						(effects
							(font
								(size 1.27 1.27)
							)
						)
					)
				)
				(pin output line
					(at 17.78 -2.54 180)
					(length 2.54)
					(name "ST"
						(effects
							(font
								(size 1.27 1.27)
							)
						)
					)
					(number "8"
						(effects
							(font
								(size 1.27 1.27)
							)
						)
					)
				)
				(pin power_in line
					(at 17.78 -7.62 180)
					(length 2.54)
					(name "GND"
						(effects
							(font
								(size 1.27 1.27)
							)
						)
					)
					(number "1"
						(effects
							(font
								(size 1.27 1.27)
							)
						)
					)
				)
			)
		)
	(symbol "antmicroPMICPowerSequencers:LM3880"
			(exclude_from_sim no)
			(in_bom yes)
			(on_board yes)
			(property "Reference" "U"
				(at 25.4 -5.08 0)
				(effects
					(font
						(size 1.27 1.27)
						(thickness 0.15)
					)
					(justify left bottom)
				)
			)
			(property "Value" "LM3880"
				(at 25.4 -7.62 0)
				(effects
					(font
						(size 1.27 1.27)
						(thickness 0.15)
					)
					(justify left bottom)
				)
			)
			(property "Footprint" "antmicro-footprints:SOT-23-6"
				(at 25.4 -10.16 0)
				(effects
					(font
						(size 1.27 1.27)
						(thickness 0.15)
					)
					(justify left bottom)
					(hide yes)
				)
			)
			(property "Datasheet" "http://www.ti.com/lit/ds/symlink/lm3880.pdf"
				(at 25.4 -12.7 0)
				(effects
					(font
						(size 1.27 1.27)
						(thickness 0.15)
					)
					(justify left bottom)
					(hide yes)
				)
			)
			(property "Description" "Power sequencer"
				(at 0 0 0)
				(effects
					(font
						(size 1.27 1.27)
					)
					(hide yes)
				)
			)
			(property "Manufacturer" "Texas Instruments"
				(at 25.4 -15.24 0)
				(effects
					(font
						(size 1.27 1.27)
						(thickness 0.15)
					)
					(justify left bottom)
					(hide yes)
				)
			)
			(property "MPN" "LM3880MFX-1AA/NOPB"
				(at 25.4 -17.78 0)
				(effects
					(font
						(size 1.27 1.27)
						(thickness 0.15)
					)
					(justify left bottom)
					(hide yes)
				)
			)
			(property "Author" "Antmicro"
				(at 25.4 -20.32 0)
				(effects
					(font
						(size 1.27 1.27)
						(thickness 0.15)
					)
					(justify left bottom)
					(hide yes)
				)
			)
			(property "License" "Apache-2.0"
				(at 25.4 -22.86 0)
				(effects
					(font
						(size 1.27 1.27)
						(thickness 0.15)
					)
					(justify left bottom)
					(hide yes)
				)
			)
			(property "ki_keywords" "SMT, PMIC, IC, POWER, SEQUENCER"
				(at 0 0 0)
				(effects
					(font
						(size 1.27 1.27)
					)
					(hide yes)
				)
			)
			(property "ki_fp_filters" "SOT?23*"
				(at 0 0 0)
				(effects
					(font
						(size 1.27 1.27)
					)
					(hide yes)
				)
			)
			(symbol "LM3880_1_1"
				(rectangle
					(start -7.62 -2.54)
					(end 7.62 -12.7)
					(stroke
						(width 0.254)
						(type default)
					)
					(fill
						(type background)
					)
				)
				(pin input line
					(at -10.16 -7.62 0)
					(length 2.54)
					(name "EN"
						(effects
							(font
								(size 1.27 1.27)
							)
						)
					)
					(number "3"
						(effects
							(font
								(size 1.27 1.27)
							)
						)
					)
				)
				(pin power_in line
					(at 0 0 270)
					(length 2.54)
					(name "VCC"
						(effects
							(font
								(size 1.27 1.27)
							)
						)
					)
					(number "1"
						(effects
							(font
								(size 1.27 1.27)
							)
						)
					)
				)
				(pin power_in line
					(at 0 -15.24 90)
					(length 2.54)
					(name "GND"
						(effects
							(font
								(size 1.27 1.27)
							)
						)
					)
					(number "2"
						(effects
							(font
								(size 1.27 1.27)
							)
						)
					)
				)
				(pin open_collector line
					(at 10.16 -5.08 180)
					(length 2.54)
					(name "FLAG1"
						(effects
							(font
								(size 1.27 1.27)
							)
						)
					)
					(number "6"
						(effects
							(font
								(size 1.27 1.27)
							)
						)
					)
				)
				(pin open_collector line
					(at 10.16 -7.62 180)
					(length 2.54)
					(name "FLAG2"
						(effects
							(font
								(size 1.27 1.27)
							)
						)
					)
					(number "5"
						(effects
							(font
								(size 1.27 1.27)
							)
						)
					)
				)
				(pin open_collector line
					(at 10.16 -10.16 180)
					(length 2.54)
					(name "FLAG3"
						(effects
							(font
								(size 1.27 1.27)
							)
						)
					)
					(number "4"
						(effects
							(font
								(size 1.27 1.27)
							)
						)
					)
				)
			)
		)
	(symbol "antmicroPMICPowerSequencers:MAX812REUS+T"
			(exclude_from_sim no)
			(in_bom yes)
			(on_board yes)
			(property "Reference" "U"
				(at 30.48 -2.54 0)
				(effects
					(font
						(size 1.27 1.27)
						(thickness 0.15)
					)
					(justify left bottom)
				)
			)
			(property "Value" "MAX812REUS+T"
				(at 30.48 -5.08 0)
				(effects
					(font
						(size 1.27 1.27)
						(thickness 0.15)
					)
					(justify left bottom)
				)
			)
			(property "Footprint" "antmicro-footprints:SOT-143-4"
				(at 30.48 -7.62 0)
				(effects
					(font
						(size 1.27 1.27)
						(thickness 0.15)
					)
					(justify left bottom)
					(hide yes)
				)
			)
			(property "Datasheet" "https://datasheets.maximintegrated.com/en/ds/MAX811-MAX812T.pdf"
				(at 30.48 -10.16 0)
				(effects
					(font
						(size 1.27 1.27)
						(thickness 0.15)
					)
					(justify left bottom)
					(hide yes)
				)
			)
			(property "Description" "Voltage monitor"
				(at 0 0 0)
				(effects
					(font
						(size 1.27 1.27)
					)
					(hide yes)
				)
			)
			(property "Manufacturer" "Maxim Integrated Products"
				(at 30.48 -12.7 0)
				(effects
					(font
						(size 1.27 1.27)
						(thickness 0.15)
					)
					(justify left bottom)
					(hide yes)
				)
			)
			(property "MPN" "MAX812REUS+T"
				(at 30.48 -15.24 0)
				(effects
					(font
						(size 1.27 1.27)
						(thickness 0.15)
					)
					(justify left bottom)
					(hide yes)
				)
			)
			(property "License" "Apache-2.0"
				(at 30.48 -17.78 0)
				(effects
					(font
						(size 1.27 1.27)
						(thickness 0.15)
					)
					(justify left bottom)
					(hide yes)
				)
			)
			(property "Author" "Antmicro"
				(at 30.48 -20.32 0)
				(effects
					(font
						(size 1.27 1.27)
						(thickness 0.15)
					)
					(justify left bottom)
					(hide yes)
				)
			)
			(property "ki_keywords" "SMT, PMIC, IC, VOLTAGE, MONITOR"
				(at 0 0 0)
				(effects
					(font
						(size 1.27 1.27)
					)
					(hide yes)
				)
			)
			(symbol "MAX812REUS+T_1_1"
				(rectangle
					(start 2.54 2.54)
					(end 12.7 -7.62)
					(stroke
						(width 0.254)
						(type default)
					)
					(fill
						(type background)
					)
				)
				(pin power_in line
					(at 0 0 0)
					(length 2.54)
					(name "VCC"
						(effects
							(font
								(size 1.27 1.27)
							)
						)
					)
					(number "4"
						(effects
							(font
								(size 1.27 1.27)
							)
						)
					)
				)
				(pin input line
					(at 0 -2.54 0)
					(length 2.54)
					(name "~{MR}"
						(effects
							(font
								(size 1.27 1.27)
							)
						)
					)
					(number "3"
						(effects
							(font
								(size 1.27 1.27)
							)
						)
					)
				)
				(pin power_in line
					(at 0 -5.08 0)
					(length 2.54)
					(name "GND"
						(effects
							(font
								(size 1.27 1.27)
							)
						)
					)
					(number "1"
						(effects
							(font
								(size 1.27 1.27)
							)
						)
					)
				)
				(pin output line
					(at 15.24 -2.54 180)
					(length 2.54)
					(name "~{RST}"
						(effects
							(font
								(size 1.27 1.27)
							)
						)
					)
					(number "2"
						(effects
							(font
								(size 1.27 1.27)
							)
						)
					)
				)
			)
		)
	(symbol "antmicroPMICVoltageRegulatorsDCDCSwitchingRegulators:MPM54304GMN"
			(exclude_from_sim no)
			(in_bom yes)
			(on_board yes)
			(property "Reference" "U"
				(at 46.99 -2.54 0)
				(effects
					(font
						(size 1.27 1.27)
						(thickness 0.15)
					)
					(justify left bottom)
				)
			)
			(property "Value" "MPM54304GMN"
				(at 46.99 -5.08 0)
				(effects
					(font
						(size 1.27 1.27)
						(thickness 0.15)
					)
					(justify left bottom)
					(hide yes)
				)
			)
			(property "Footprint" "antmicro-footprints:LGA-33_7x7mm_P0.65mm"
				(at 46.99 -7.62 0)
				(effects
					(font
						(size 1.27 1.27)
						(thickness 0.15)
					)
					(justify left bottom)
					(hide yes)
				)
			)
			(property "Datasheet" "https://www.monolithicpower.com/en/documentview/productdocument/index/version/2/document_type/Datasheet/lang/en/sku/MPM54304/document_id/4982/"
				(at 46.99 -10.16 0)
				(effects
					(font
						(size 1.27 1.27)
						(thickness 0.15)
					)
					(justify left bottom)
					(hide yes)
				)
			)
			(property "Description" "DC-DC Switching Synchronous Step-Down Regulator, Multi Output, 4-16V in, 1V/3.3V, 4.2/3A out, LGA33"
				(at 0 0 0)
				(effects
					(font
						(size 1.27 1.27)
					)
					(hide yes)
				)
			)
			(property "MPN" "MPM54304GMN-0000"
				(at 46.99 -12.7 0)
				(effects
					(font
						(size 1.27 1.27)
						(thickness 0.15)
					)
					(justify left bottom)
				)
			)
			(property "Manufacturer" "Monolithic Power Systems"
				(at 46.99 -15.24 0)
				(effects
					(font
						(size 1.27 1.27)
						(thickness 0.15)
					)
					(justify left bottom)
					(hide yes)
				)
			)
			(property "Author" "Antmicro"
				(at 46.99 -17.78 0)
				(effects
					(font
						(size 1.27 1.27)
						(thickness 0.15)
					)
					(justify left bottom)
					(hide yes)
				)
			)
			(property "License" "Apache-2.0"
				(at 46.99 -20.32 0)
				(effects
					(font
						(size 1.27 1.27)
						(thickness 0.15)
					)
					(justify left bottom)
					(hide yes)
				)
			)
			(property "ki_keywords" "SMT, PMIC, IC, VOLTAGE, REGULATOR, SWITCHING, DC-DC"
				(at 0 0 0)
				(effects
					(font
						(size 1.27 1.27)
					)
					(hide yes)
				)
			)
			(property "ki_fp_filters" "CP_48_13_ADI CP_48_13_ADI-M CP_48_13_ADI-L"
				(at 0 0 0)
				(effects
					(font
						(size 1.27 1.27)
					)
					(hide yes)
				)
			)
			(symbol "MPM54304GMN_1_1"
				(rectangle
					(start 2.54 3.81)
					(end 2.54 3.81)
					(stroke
						(width 0.254)
						(type default)
					)
					(fill
						(type background)
					)
				)
				(rectangle
					(start 2.54 2.54)
					(end 25.4 -38.1)
					(stroke
						(width 0.254)
						(type default)
					)
					(fill
						(type background)
					)
				)
				(polyline
					(pts
						(xy 25.4 1.27) (xy 17.78 1.27) (xy 17.78 -8.89) (xy 25.4 -8.89)
					)
					(stroke
						(width 0.254)
						(type default)
					)
					(fill
						(type background)
					)
				)
				(polyline
					(pts
						(xy 25.4 -11.43) (xy 17.78 -11.43) (xy 17.78 -19.05) (xy 25.4 -19.05)
					)
					(stroke
						(width 0.254)
						(type default)
					)
					(fill
						(type background)
					)
				)
				(polyline
					(pts
						(xy 25.4 -21.59) (xy 17.78 -21.59) (xy 17.78 -29.21) (xy 25.4 -29.21)
					)
					(stroke
						(width 0.254)
						(type default)
					)
					(fill
						(type background)
					)
				)
				(polyline
					(pts
						(xy 25.4 -31.75) (xy 17.78 -31.75) (xy 17.78 -36.83) (xy 25.4 -36.83)
					)
					(stroke
						(width 0.254)
						(type default)
					)
					(fill
						(type background)
					)
				)
				(pin input line
					(at 0 0 0)
					(length 2.54)
					(name "VIN"
						(effects
							(font
								(size 1.27 1.27)
							)
						)
					)
					(number "28"
						(effects
							(font
								(size 1.27 1.27)
							)
						)
					)
				)
				(pin passive line
					(at 0 0 0)
					(length 2.54)
					(hide yes)
					(name "VIN"
						(effects
							(font
								(size 1.27 1.27)
							)
						)
					)
					(number "29"
						(effects
							(font
								(size 1.27 1.27)
							)
						)
					)
				)
				(pin input line
					(at 0 -2.54 0)
					(length 2.54)
					(name "VCC"
						(effects
							(font
								(size 1.27 1.27)
							)
						)
					)
					(number "25"
						(effects
							(font
								(size 1.27 1.27)
							)
						)
					)
				)
				(pin input line
					(at 0 -10.16 0)
					(length 2.54)
					(name "EN/SYNCI"
						(effects
							(font
								(size 1.27 1.27)
							)
						)
					)
					(number "19"
						(effects
							(font
								(size 1.27 1.27)
							)
						)
					)
				)
				(pin bidirectional line
					(at 0 -19.05 0)
					(length 2.54)
					(name "SDA"
						(effects
							(font
								(size 1.27 1.27)
							)
						)
					)
					(number "3"
						(effects
							(font
								(size 1.27 1.27)
							)
						)
					)
				)
				(pin input line
					(at 0 -21.59 0)
					(length 2.54)
					(name "SCL"
						(effects
							(font
								(size 1.27 1.27)
							)
						)
					)
					(number "4"
						(effects
							(font
								(size 1.27 1.27)
							)
						)
					)
				)
				(pin input line
					(at 0 -30.48 0)
					(length 2.54)
					(name "GPIO"
						(effects
							(font
								(size 1.27 1.27)
							)
						)
					)
					(number "26"
						(effects
							(font
								(size 1.27 1.27)
							)
						)
					)
				)
				(pin passive line
					(at 0 -35.56 0)
					(length 2.54)
					(name "GND"
						(effects
							(font
								(size 1.27 1.27)
							)
						)
					)
					(number "10"
						(effects
							(font
								(size 1.27 1.27)
							)
						)
					)
				)
				(pin passive line
					(at 0 -35.56 0)
					(length 2.54)
					(hide yes)
					(name "GND"
						(effects
							(font
								(size 1.27 1.27)
							)
						)
					)
					(number "13"
						(effects
							(font
								(size 1.27 1.27)
							)
						)
					)
				)
				(pin passive line
					(at 0 -35.56 0)
					(length 2.54)
					(hide yes)
					(name "GND"
						(effects
							(font
								(size 1.27 1.27)
							)
						)
					)
					(number "16"
						(effects
							(font
								(size 1.27 1.27)
							)
						)
					)
				)
				(pin passive line
					(at 0 -35.56 0)
					(length 2.54)
					(hide yes)
					(name "GND"
						(effects
							(font
								(size 1.27 1.27)
							)
						)
					)
					(number "2"
						(effects
							(font
								(size 1.27 1.27)
							)
						)
					)
				)
				(pin passive line
					(at 0 -35.56 0)
					(length 2.54)
					(hide yes)
					(name "GND"
						(effects
							(font
								(size 1.27 1.27)
							)
						)
					)
					(number "20"
						(effects
							(font
								(size 1.27 1.27)
							)
						)
					)
				)
				(pin passive line
					(at 0 -35.56 0)
					(length 2.54)
					(hide yes)
					(name "GND"
						(effects
							(font
								(size 1.27 1.27)
							)
						)
					)
					(number "21"
						(effects
							(font
								(size 1.27 1.27)
							)
						)
					)
				)
				(pin passive line
					(at 0 -35.56 0)
					(length 2.54)
					(hide yes)
					(name "GND"
						(effects
							(font
								(size 1.27 1.27)
							)
						)
					)
					(number "27"
						(effects
							(font
								(size 1.27 1.27)
							)
						)
					)
				)
				(pin passive line
					(at 0 -35.56 0)
					(length 2.54)
					(hide yes)
					(name "GND"
						(effects
							(font
								(size 1.27 1.27)
							)
						)
					)
					(number "33"
						(effects
							(font
								(size 1.27 1.27)
							)
						)
					)
				)
				(pin passive line
					(at 0 -35.56 0)
					(length 2.54)
					(hide yes)
					(name "GND"
						(effects
							(font
								(size 1.27 1.27)
							)
						)
					)
					(number "5"
						(effects
							(font
								(size 1.27 1.27)
							)
						)
					)
				)
				(pin passive line
					(at 0 -35.56 0)
					(length 2.54)
					(hide yes)
					(name "GND"
						(effects
							(font
								(size 1.27 1.27)
							)
						)
					)
					(number "7"
						(effects
							(font
								(size 1.27 1.27)
							)
						)
					)
				)
				(pin power_out line
					(at 27.94 0 180)
					(length 2.54)
					(name "VOUT1"
						(effects
							(font
								(size 1.27 1.27)
							)
						)
					)
					(number "14"
						(effects
							(font
								(size 1.27 1.27)
							)
						)
					)
				)
				(pin passive line
					(at 27.94 0 180)
					(length 2.54)
					(hide yes)
					(name "VOUT1"
						(effects
							(font
								(size 1.27 1.27)
							)
						)
					)
					(number "15"
						(effects
							(font
								(size 1.27 1.27)
							)
						)
					)
				)
				(pin power_out line
					(at 27.94 -2.54 180)
					(length 2.54)
					(name "SW1"
						(effects
							(font
								(size 1.27 1.27)
							)
						)
					)
					(number "12"
						(effects
							(font
								(size 1.27 1.27)
							)
						)
					)
				)
				(pin input line
					(at 27.94 -5.08 180)
					(length 2.54)
					(name "FB1"
						(effects
							(font
								(size 1.27 1.27)
							)
						)
					)
					(number "18"
						(effects
							(font
								(size 1.27 1.27)
							)
						)
					)
				)
				(pin power_out line
					(at 27.94 -7.62 180)
					(length 2.54)
					(name "SGND1"
						(effects
							(font
								(size 1.27 1.27)
							)
						)
					)
					(number "17"
						(effects
							(font
								(size 1.27 1.27)
							)
						)
					)
				)
				(pin power_out line
					(at 27.94 -12.7 180)
					(length 2.54)
					(name "VOUT2"
						(effects
							(font
								(size 1.27 1.27)
							)
						)
					)
					(number "8"
						(effects
							(font
								(size 1.27 1.27)
							)
						)
					)
				)
				(pin passive line
					(at 27.94 -12.7 180)
					(length 2.54)
					(hide yes)
					(name "VOUT2"
						(effects
							(font
								(size 1.27 1.27)
							)
						)
					)
					(number "9"
						(effects
							(font
								(size 1.27 1.27)
							)
						)
					)
				)
				(pin power_out line
					(at 27.94 -15.24 180)
					(length 2.54)
					(name "SW2"
						(effects
							(font
								(size 1.27 1.27)
							)
						)
					)
					(number "11"
						(effects
							(font
								(size 1.27 1.27)
							)
						)
					)
				)
				(pin input line
					(at 27.94 -17.78 180)
					(length 2.54)
					(name "FB2"
						(effects
							(font
								(size 1.27 1.27)
							)
						)
					)
					(number "6"
						(effects
							(font
								(size 1.27 1.27)
							)
						)
					)
				)
				(pin power_out line
					(at 27.94 -22.86 180)
					(length 2.54)
					(name "VOUT3"
						(effects
							(font
								(size 1.27 1.27)
							)
						)
					)
					(number "1"
						(effects
							(font
								(size 1.27 1.27)
							)
						)
					)
				)
				(pin passive line
					(at 27.94 -22.86 180)
					(length 2.54)
					(hide yes)
					(name "VOUT3"
						(effects
							(font
								(size 1.27 1.27)
							)
						)
					)
					(number "32"
						(effects
							(font
								(size 1.27 1.27)
							)
						)
					)
				)
				(pin input line
					(at 27.94 -25.4 180)
					(length 2.54)
					(name "FB3"
						(effects
							(font
								(size 1.27 1.27)
							)
						)
					)
					(number "31"
						(effects
							(font
								(size 1.27 1.27)
							)
						)
					)
				)
				(pin power_out line
					(at 27.94 -27.94 180)
					(length 2.54)
					(name "SGND2"
						(effects
							(font
								(size 1.27 1.27)
							)
						)
					)
					(number "30"
						(effects
							(font
								(size 1.27 1.27)
							)
						)
					)
				)
				(pin power_out line
					(at 27.94 -33.02 180)
					(length 2.54)
					(name "VOUT4"
						(effects
							(font
								(size 1.27 1.27)
							)
						)
					)
					(number "22"
						(effects
							(font
								(size 1.27 1.27)
							)
						)
					)
				)
				(pin passive line
					(at 27.94 -33.02 180)
					(length 2.54)
					(hide yes)
					(name "VOUT4"
						(effects
							(font
								(size 1.27 1.27)
							)
						)
					)
					(number "23"
						(effects
							(font
								(size 1.27 1.27)
							)
						)
					)
				)
				(pin input line
					(at 27.94 -35.56 180)
					(length 2.54)
					(name "FB4"
						(effects
							(font
								(size 1.27 1.27)
							)
						)
					)
					(number "24"
						(effects
							(font
								(size 1.27 1.27)
							)
						)
					)
				)
			)
		)
	(symbol "antmicroPMICVoltageRegulatorsLinear:NCP718BSN330T1G"
			(exclude_from_sim no)
			(in_bom yes)
			(on_board yes)
			(property "Reference" "U"
				(at 35.56 -3.81 0)
				(effects
					(font
						(size 1.27 1.27)
						(thickness 0.15)
					)
					(justify left bottom)
				)
			)
			(property "Value" "NCP718BSN330T1G"
				(at 35.56 -6.35 0)
				(effects
					(font
						(size 1.27 1.27)
						(thickness 0.15)
					)
					(justify left bottom)
					(hide yes)
				)
			)
			(property "Footprint" "antmicro-footprints:SOT-23-5"
				(at 35.56 -8.89 0)
				(effects
					(font
						(size 1.27 1.27)
						(thickness 0.15)
					)
					(justify left bottom)
					(hide yes)
				)
			)
			(property "Datasheet" "https://www.mouser.com/datasheet/2/308/NCP718_D-1224359.pdf"
				(at 35.56 -11.43 0)
				(effects
					(font
						(size 1.27 1.27)
						(thickness 0.15)
					)
					(justify left bottom)
					(hide yes)
				)
			)
			(property "Description" "Linear Voltage Regulator IC Positive Fixed 1 Output 300mA TSOT-23-5"
				(at 0 0 0)
				(effects
					(font
						(size 1.27 1.27)
					)
					(hide yes)
				)
			)
			(property "MPN" "NCP718BSN330T1G"
				(at 35.56 -13.97 0)
				(effects
					(font
						(size 1.27 1.27)
						(thickness 0.15)
					)
					(justify left bottom)
				)
			)
			(property "Manufacturer" "ON Semiconductor"
				(at 35.56 -16.51 0)
				(effects
					(font
						(size 1.27 1.27)
						(thickness 0.15)
					)
					(justify left bottom)
					(hide yes)
				)
			)
			(property "Author" "Antmicro"
				(at 35.56 -19.05 0)
				(effects
					(font
						(size 1.27 1.27)
						(thickness 0.15)
					)
					(justify left bottom)
					(hide yes)
				)
			)
			(property "License" "Apache-2.0"
				(at 35.56 -21.59 0)
				(effects
					(font
						(size 1.27 1.27)
						(thickness 0.15)
					)
					(justify left bottom)
					(hide yes)
				)
			)
			(property "ki_keywords" "SMT, PMIC, IC, LDO, VOLTAGE, REGULATOR"
				(at 0 0 0)
				(effects
					(font
						(size 1.27 1.27)
					)
					(hide yes)
				)
			)
			(symbol "NCP718BSN330T1G_1_1"
				(rectangle
					(start 2.54 2.54)
					(end 17.78 -5.08)
					(stroke
						(width 0.254)
						(type default)
					)
					(fill
						(type background)
					)
				)
				(pin passive line
					(at 0 0 0)
					(length 2.54)
					(name "VIN"
						(effects
							(font
								(size 1.27 1.27)
							)
						)
					)
					(number "1"
						(effects
							(font
								(size 1.27 1.27)
							)
						)
					)
				)
				(pin passive line
					(at 0 -2.54 0)
					(length 2.54)
					(name "EN"
						(effects
							(font
								(size 1.27 1.27)
							)
						)
					)
					(number "3"
						(effects
							(font
								(size 1.27 1.27)
							)
						)
					)
				)
				(pin no_connect line
					(at 10.16 -5.08 90)
					(length 2.54)
					(hide yes)
					(name "NC"
						(effects
							(font
								(size 1.27 1.27)
							)
						)
					)
					(number "4"
						(effects
							(font
								(size 1.27 1.27)
							)
						)
					)
				)
				(pin passive line
					(at 20.32 0 180)
					(length 2.54)
					(name "VOUT"
						(effects
							(font
								(size 1.27 1.27)
							)
						)
					)
					(number "5"
						(effects
							(font
								(size 1.27 1.27)
							)
						)
					)
				)
				(pin passive line
					(at 20.32 -2.54 180)
					(length 2.54)
					(name "GND"
						(effects
							(font
								(size 1.27 1.27)
							)
						)
					)
					(number "2"
						(effects
							(font
								(size 1.27 1.27)
							)
						)
					)
				)
			)
		)
	(symbol "antmicroPowerMeasurement:PAC1720-1-AIA-TR"
			(exclude_from_sim no)
			(in_bom yes)
			(on_board yes)
			(property "Reference" "U"
				(at 38.1 -2.54 0)
				(effects
					(font
						(size 1.27 1.27)
						(thickness 0.15)
					)
					(justify left bottom)
				)
			)
			(property "Value" "PAC1720-1"
				(at 38.1 -7.62 0)
				(effects
					(font
						(size 1.27 1.27)
						(thickness 0.15)
					)
					(justify left bottom)
					(hide yes)
				)
			)
			(property "Footprint" "antmicro-footprints:DFN-10-1EP_3x3mm"
				(at 38.1 -10.16 0)
				(effects
					(font
						(size 1.27 1.27)
						(thickness 0.15)
					)
					(justify left bottom)
					(hide yes)
				)
			)
			(property "Datasheet" "https://ww1.microchip.com/downloads/aemDocuments/documents/MSLD/ProductDocuments/DataSheets/PAC1710-PAC1720-Data-Sheet-DS20005386.pdf"
				(at 38.1 -12.7 0)
				(effects
					(font
						(size 1.27 1.27)
						(thickness 0.15)
					)
					(justify left bottom)
					(hide yes)
				)
			)
			(property "Description" "Current/Voltage Monitor Regulator High-Side VDFN-10 (3x3)"
				(at 0 0 0)
				(effects
					(font
						(size 1.27 1.27)
					)
					(hide yes)
				)
			)
			(property "MPN" "PAC1720-1-AIA-TR"
				(at 38.1 -5.08 0)
				(effects
					(font
						(size 1.27 1.27)
						(thickness 0.15)
					)
					(justify left bottom)
				)
			)
			(property "Manufacturer" "Microchip Technology"
				(at 38.1 -15.24 0)
				(effects
					(font
						(size 1.27 1.27)
						(thickness 0.15)
					)
					(justify left bottom)
					(hide yes)
				)
			)
			(property "Author" "Antmicro"
				(at 38.1 -17.78 0)
				(effects
					(font
						(size 1.27 1.27)
						(thickness 0.15)
					)
					(justify left bottom)
					(hide yes)
				)
			)
			(property "License" "Apache-2.0"
				(at 38.1 -20.32 0)
				(effects
					(font
						(size 1.27 1.27)
						(thickness 0.15)
					)
					(justify left bottom)
					(hide yes)
				)
			)
			(property "ki_keywords" "MONITOR, VOLTAGE, IC, SMT"
				(at 0 0 0)
				(effects
					(font
						(size 1.27 1.27)
					)
					(hide yes)
				)
			)
			(property "ki_fp_filters" "UQFN*1EP*4x4mm*P0.65mm*"
				(at 0 0 0)
				(effects
					(font
						(size 1.27 1.27)
					)
					(hide yes)
				)
			)
			(symbol "PAC1720-1-AIA-TR_1_1"
				(rectangle
					(start 2.54 2.54)
					(end 22.86 -25.4)
					(stroke
						(width 0.254)
						(type default)
					)
					(fill
						(type background)
					)
				)
				(pin power_in line
					(at 0 0 0)
					(length 2.54)
					(name "VDD"
						(effects
							(font
								(size 1.27 1.27)
							)
						)
					)
					(number "10"
						(effects
							(font
								(size 1.27 1.27)
							)
						)
					)
				)
				(pin input line
					(at 0 -3.81 0)
					(length 2.54)
					(name "SCL"
						(effects
							(font
								(size 1.27 1.27)
							)
						)
					)
					(number "9"
						(effects
							(font
								(size 1.27 1.27)
							)
						)
					)
				)
				(pin bidirectional line
					(at 0 -6.35 0)
					(length 2.54)
					(name "SDA"
						(effects
							(font
								(size 1.27 1.27)
							)
						)
					)
					(number "8"
						(effects
							(font
								(size 1.27 1.27)
							)
						)
					)
				)
				(pin bidirectional line
					(at 0 -8.89 0)
					(length 2.54)
					(name "~{ALERT}"
						(effects
							(font
								(size 1.27 1.27)
							)
						)
					)
					(number "7"
						(effects
							(font
								(size 1.27 1.27)
							)
						)
					)
				)
				(pin bidirectional line
					(at 0 -16.51 0)
					(length 2.54)
					(name "ADDRSEL"
						(effects
							(font
								(size 1.27 1.27)
							)
						)
					)
					(number "6"
						(effects
							(font
								(size 1.27 1.27)
							)
						)
					)
				)
				(pin passive line
					(at 0 -20.32 0)
					(length 2.54)
					(name "EP"
						(effects
							(font
								(size 1.27 1.27)
							)
						)
					)
					(number "11"
						(effects
							(font
								(size 1.27 1.27)
							)
						)
					)
				)
				(pin power_in line
					(at 0 -22.86 0)
					(length 2.54)
					(name "GND"
						(effects
							(font
								(size 1.27 1.27)
							)
						)
					)
					(number "5"
						(effects
							(font
								(size 1.27 1.27)
							)
						)
					)
				)
				(pin input line
					(at 25.4 0 180)
					(length 2.54)
					(name "IN1+"
						(effects
							(font
								(size 1.27 1.27)
							)
						)
					)
					(number "1"
						(effects
							(font
								(size 1.27 1.27)
							)
						)
					)
				)
				(pin input line
					(at 25.4 -2.54 180)
					(length 2.54)
					(name "IN1-"
						(effects
							(font
								(size 1.27 1.27)
							)
						)
					)
					(number "2"
						(effects
							(font
								(size 1.27 1.27)
							)
						)
					)
				)
				(pin input line
					(at 25.4 -6.35 180)
					(length 2.54)
					(name "IN2+"
						(effects
							(font
								(size 1.27 1.27)
							)
						)
					)
					(number "3"
						(effects
							(font
								(size 1.27 1.27)
							)
						)
					)
				)
				(pin input line
					(at 25.4 -8.89 180)
					(length 2.54)
					(name "IN2-"
						(effects
							(font
								(size 1.27 1.27)
							)
						)
					)
					(number "4"
						(effects
							(font
								(size 1.27 1.27)
							)
						)
					)
				)
			)
		)
	(symbol "antmicroPowerMeasurement:PAC1944T-E"
			(exclude_from_sim no)
			(in_bom yes)
			(on_board yes)
			(property "Reference" "U"
				(at 38.1 -2.54 0)
				(effects
					(font
						(size 1.27 1.27)
						(thickness 0.15)
					)
					(justify left bottom)
				)
			)
			(property "Value" "PAC1944T-E"
				(at 38.1 -7.62 0)
				(effects
					(font
						(size 1.27 1.27)
						(thickness 0.15)
					)
					(justify left bottom)
					(hide yes)
				)
			)
			(property "Footprint" "antmicro-footprints:VQFN-16-1EP_3x3mm_P0.5mm_EP1.1x1.1mm"
				(at 38.1 -10.16 0)
				(effects
					(font
						(size 1.27 1.27)
						(thickness 0.15)
					)
					(justify left bottom)
					(hide yes)
				)
			)
			(property "Datasheet" "https://ww1.microchip.com/downloads/aemDocuments/documents/MSLD/ProductDocuments/DataSheets/PAC194X-Family-Data-Sheet-DS20006543.pdf"
				(at 38.1 -12.7 0)
				(effects
					(font
						(size 1.27 1.27)
						(thickness 0.15)
					)
					(justify left bottom)
					(hide yes)
				)
			)
			(property "Description" "Current/Voltage Monitor Regulator High-Side 16-VQFN (3x3)"
				(at 0 0 0)
				(effects
					(font
						(size 1.27 1.27)
					)
					(hide yes)
				)
			)
			(property "MPN" "PAC1944T-E/4MX"
				(at 38.1 -5.08 0)
				(effects
					(font
						(size 1.27 1.27)
						(thickness 0.15)
					)
					(justify left bottom)
				)
			)
			(property "Manufacturer" "Microchip Technology"
				(at 38.1 -15.24 0)
				(effects
					(font
						(size 1.27 1.27)
						(thickness 0.15)
					)
					(justify left bottom)
					(hide yes)
				)
			)
			(property "Author" "Antmicro"
				(at 38.1 -17.78 0)
				(effects
					(font
						(size 1.27 1.27)
						(thickness 0.15)
					)
					(justify left bottom)
					(hide yes)
				)
			)
			(property "License" "Apache-2.0"
				(at 38.1 -20.32 0)
				(effects
					(font
						(size 1.27 1.27)
						(thickness 0.15)
					)
					(justify left bottom)
					(hide yes)
				)
			)
			(property "ki_keywords" "MONITOR, VOLTAGE, IC, SMT"
				(at 0 0 0)
				(effects
					(font
						(size 1.27 1.27)
					)
					(hide yes)
				)
			)
			(property "ki_fp_filters" "UQFN*1EP*4x4mm*P0.65mm*"
				(at 0 0 0)
				(effects
					(font
						(size 1.27 1.27)
					)
					(hide yes)
				)
			)
			(symbol "PAC1944T-E_1_1"
				(rectangle
					(start 2.54 2.54)
					(end 22.86 -25.4)
					(stroke
						(width 0.254)
						(type default)
					)
					(fill
						(type background)
					)
				)
				(pin power_in line
					(at 0 0 0)
					(length 2.54)
					(name "VDD"
						(effects
							(font
								(size 1.27 1.27)
							)
						)
					)
					(number "2"
						(effects
							(font
								(size 1.27 1.27)
							)
						)
					)
				)
				(pin input line
					(at 0 -3.81 0)
					(length 2.54)
					(name "SCL"
						(effects
							(font
								(size 1.27 1.27)
							)
						)
					)
					(number "4"
						(effects
							(font
								(size 1.27 1.27)
							)
						)
					)
				)
				(pin bidirectional line
					(at 0 -6.35 0)
					(length 2.54)
					(name "SDA"
						(effects
							(font
								(size 1.27 1.27)
							)
						)
					)
					(number "5"
						(effects
							(font
								(size 1.27 1.27)
							)
						)
					)
				)
				(pin bidirectional line
					(at 0 -8.89 0)
					(length 2.54)
					(name "SLOW/~{ALERT1}"
						(effects
							(font
								(size 1.27 1.27)
							)
						)
					)
					(number "1"
						(effects
							(font
								(size 1.27 1.27)
							)
						)
					)
				)
				(pin bidirectional line
					(at 0 -11.43 0)
					(length 2.54)
					(name "GPIO/~{ALERT2}"
						(effects
							(font
								(size 1.27 1.27)
							)
						)
					)
					(number "15"
						(effects
							(font
								(size 1.27 1.27)
							)
						)
					)
				)
				(pin input line
					(at 0 -13.97 0)
					(length 2.54)
					(name "~{PWRDN}"
						(effects
							(font
								(size 1.27 1.27)
							)
						)
					)
					(number "16"
						(effects
							(font
								(size 1.27 1.27)
							)
						)
					)
				)
				(pin bidirectional line
					(at 0 -16.51 0)
					(length 2.54)
					(name "ADDRSEL"
						(effects
							(font
								(size 1.27 1.27)
							)
						)
					)
					(number "6"
						(effects
							(font
								(size 1.27 1.27)
							)
						)
					)
				)
				(pin passive line
					(at 0 -20.32 0)
					(length 2.54)
					(name "EP"
						(effects
							(font
								(size 1.27 1.27)
							)
						)
					)
					(number "17"
						(effects
							(font
								(size 1.27 1.27)
							)
						)
					)
				)
				(pin power_in line
					(at 0 -22.86 0)
					(length 2.54)
					(name "GND"
						(effects
							(font
								(size 1.27 1.27)
							)
						)
					)
					(number "3"
						(effects
							(font
								(size 1.27 1.27)
							)
						)
					)
				)
				(pin input line
					(at 25.4 0 180)
					(length 2.54)
					(name "IN1+"
						(effects
							(font
								(size 1.27 1.27)
							)
						)
					)
					(number "11"
						(effects
							(font
								(size 1.27 1.27)
							)
						)
					)
				)
				(pin input line
					(at 25.4 -2.54 180)
					(length 2.54)
					(name "IN1-"
						(effects
							(font
								(size 1.27 1.27)
							)
						)
					)
					(number "12"
						(effects
							(font
								(size 1.27 1.27)
							)
						)
					)
				)
				(pin input line
					(at 25.4 -6.35 180)
					(length 2.54)
					(name "IN2+"
						(effects
							(font
								(size 1.27 1.27)
							)
						)
					)
					(number "13"
						(effects
							(font
								(size 1.27 1.27)
							)
						)
					)
				)
				(pin input line
					(at 25.4 -8.89 180)
					(length 2.54)
					(name "IN2-"
						(effects
							(font
								(size 1.27 1.27)
							)
						)
					)
					(number "14"
						(effects
							(font
								(size 1.27 1.27)
							)
						)
					)
				)
				(pin input line
					(at 25.4 -12.7 180)
					(length 2.54)
					(name "IN3+"
						(effects
							(font
								(size 1.27 1.27)
							)
						)
					)
					(number "8"
						(effects
							(font
								(size 1.27 1.27)
							)
						)
					)
				)
				(pin input line
					(at 25.4 -15.24 180)
					(length 2.54)
					(name "IN3-"
						(effects
							(font
								(size 1.27 1.27)
							)
						)
					)
					(number "7"
						(effects
							(font
								(size 1.27 1.27)
							)
						)
					)
				)
				(pin input line
					(at 25.4 -19.05 180)
					(length 2.54)
					(name "IN4+"
						(effects
							(font
								(size 1.27 1.27)
							)
						)
					)
					(number "10"
						(effects
							(font
								(size 1.27 1.27)
							)
						)
					)
				)
				(pin input line
					(at 25.4 -21.59 180)
					(length 2.54)
					(name "IN4-"
						(effects
							(font
								(size 1.27 1.27)
							)
						)
					)
					(number "9"
						(effects
							(font
								(size 1.27 1.27)
							)
						)
					)
				)
			)
		)
	(symbol "antmicroPushbuttonSwitches:SW_KMR211NGLFS_SMD"
			(pin_names
				(hide yes)
			)
			(exclude_from_sim no)
			(in_bom yes)
			(on_board yes)
			(property "Reference" "SW"
				(at 25.4 -2.54 0)
				(effects
					(font
						(size 1.27 1.27)
						(thickness 0.15)
					)
					(justify left bottom)
				)
			)
			(property "Value" "SW_KMR211NGLFS_SMD"
				(at 25.4 -7.62 0)
				(effects
					(font
						(size 1.27 1.27)
						(thickness 0.15)
					)
					(justify left bottom)
					(hide yes)
				)
			)
			(property "Footprint" "antmicro-footprints:SW_KMR211NGLFS_SMD"
				(at 25.4 -10.16 0)
				(effects
					(font
						(size 1.27 1.27)
						(thickness 0.15)
					)
					(justify left bottom)
					(hide yes)
				)
			)
			(property "Datasheet" "http://www.farnell.com/datasheets/2631211.pdf"
				(at 25.4 -12.7 0)
				(effects
					(font
						(size 1.27 1.27)
						(thickness 0.15)
					)
					(justify left bottom)
					(hide yes)
				)
			)
			(property "Description" "Tactile Switch, KMR 2 Series, Top Actuated, Surface Mount, Oval Button, 120 gf, 50mA at 32VDC"
				(at 0 0 0)
				(effects
					(font
						(size 1.27 1.27)
					)
					(hide yes)
				)
			)
			(property "MPN" "KMR211NGLFS"
				(at 25.4 -5.08 0)
				(effects
					(font
						(size 1.27 1.27)
						(thickness 0.15)
					)
					(justify left bottom)
				)
			)
			(property "Manufacturer" "C&K"
				(at 25.4 -15.24 0)
				(effects
					(font
						(size 1.27 1.27)
						(thickness 0.15)
					)
					(justify left bottom)
					(hide yes)
				)
			)
			(property "Author" "Antmicro"
				(at 25.4 -17.78 0)
				(effects
					(font
						(size 1.27 1.27)
						(thickness 0.15)
					)
					(justify left bottom)
					(hide yes)
				)
			)
			(property "License" "Apache-2.0"
				(at 25.4 -20.32 0)
				(effects
					(font
						(size 1.27 1.27)
						(thickness 0.15)
					)
					(justify left bottom)
					(hide yes)
				)
			)
			(property "ki_keywords" "VERTICAL, SMT, SWITCH, MECHANICAL, TACTILE"
				(at 0 0 0)
				(effects
					(font
						(size 1.27 1.27)
					)
					(hide yes)
				)
			)
			(symbol "SW_KMR211NGLFS_SMD_1_1"
				(polyline
					(pts
						(xy 2.54 0) (xy 3.302 0)
					)
					(stroke
						(width 0.254)
						(type default)
					)
					(fill
						(type none)
					)
				)
				(polyline
					(pts
						(xy 2.54 -2.54) (xy 3.302 -2.54)
					)
					(stroke
						(width 0.254)
						(type default)
					)
					(fill
						(type none)
					)
				)
				(polyline
					(pts
						(xy 3.302 1.27) (xy 6.858 1.27)
					)
					(stroke
						(width 0.254)
						(type default)
					)
					(fill
						(type none)
					)
				)
				(circle
					(center 3.556 0)
					(radius 0.254)
					(stroke
						(width 0.254)
						(type default)
					)
					(fill
						(type none)
					)
				)
				(polyline
					(pts
						(xy 3.556 -0.3048) (xy 3.556 -2.1844)
					)
					(stroke
						(width 0.254)
						(type default)
					)
					(fill
						(type none)
					)
				)
				(circle
					(center 3.556 -2.54)
					(radius 0.254)
					(stroke
						(width 0.254)
						(type default)
					)
					(fill
						(type none)
					)
				)
				(polyline
					(pts
						(xy 4.064 2.794) (xy 6.096 2.794)
					)
					(stroke
						(width 0.254)
						(type default)
					)
					(fill
						(type none)
					)
				)
				(polyline
					(pts
						(xy 5.08 1.27) (xy 5.08 2.794)
					)
					(stroke
						(width 0.254)
						(type default)
					)
					(fill
						(type none)
					)
				)
				(circle
					(center 6.604 0)
					(radius 0.254)
					(stroke
						(width 0.254)
						(type default)
					)
					(fill
						(type none)
					)
				)
				(polyline
					(pts
						(xy 6.604 -0.254) (xy 6.604 -2.1844)
					)
					(stroke
						(width 0.254)
						(type default)
					)
					(fill
						(type none)
					)
				)
				(circle
					(center 6.604 -2.54)
					(radius 0.254)
					(stroke
						(width 0.254)
						(type default)
					)
					(fill
						(type none)
					)
				)
				(polyline
					(pts
						(xy 7.62 0) (xy 6.858 0)
					)
					(stroke
						(width 0.254)
						(type default)
					)
					(fill
						(type none)
					)
				)
				(polyline
					(pts
						(xy 7.62 -2.54) (xy 6.858 -2.54)
					)
					(stroke
						(width 0.254)
						(type default)
					)
					(fill
						(type none)
					)
				)
				(pin passive line
					(at 0 0 0)
					(length 2.54)
					(name "1"
						(effects
							(font
								(size 1.27 1.27)
							)
						)
					)
					(number "1"
						(effects
							(font
								(size 1.27 1.27)
							)
						)
					)
				)
				(pin passive line
					(at 0 -2.54 0)
					(length 2.54)
					(name "2"
						(effects
							(font
								(size 1.27 1.27)
							)
						)
					)
					(number "2"
						(effects
							(font
								(size 1.27 1.27)
							)
						)
					)
				)
				(pin passive line
					(at 10.16 0 180)
					(length 2.54)
					(name "3"
						(effects
							(font
								(size 1.27 1.27)
							)
						)
					)
					(number "3"
						(effects
							(font
								(size 1.27 1.27)
							)
						)
					)
				)
				(pin passive line
					(at 10.16 -2.54 180)
					(length 2.54)
					(name "4"
						(effects
							(font
								(size 1.27 1.27)
							)
						)
					)
					(number "4"
						(effects
							(font
								(size 1.27 1.27)
							)
						)
					)
				)
			)
		)
	(symbol "antmicroResistors0402:R_0R_0402"
			(pin_numbers
				(hide yes)
			)
			(pin_names
				(hide yes)
			)
			(exclude_from_sim no)
			(in_bom yes)
			(on_board yes)
			(property "Reference" "R"
				(at 20.32 -5.08 0)
				(effects
					(font
						(size 1.27 1.27)
						(thickness 0.15)
					)
					(justify left bottom)
				)
			)
			(property "Value" "R_0R_0402"
				(at 20.32 -12.7 0)
				(effects
					(font
						(size 1.27 1.27)
						(thickness 0.15)
					)
					(justify left bottom)
					(hide yes)
				)
			)
			(property "Footprint" "antmicro-footprints:R_0402_1005Metric"
				(at 20.32 -15.24 0)
				(effects
					(font
						(size 1.27 1.27)
						(thickness 0.15)
					)
					(justify left bottom)
					(hide yes)
				)
			)
			(property "Datasheet" "https://industrial.panasonic.com/cdbs/www-data/pdf/RDA0000/AOA0000C301.pdf"
				(at 20.32 -17.78 0)
				(effects
					(font
						(size 1.27 1.27)
						(thickness 0.15)
					)
					(justify left bottom)
					(hide yes)
				)
			)
			(property "Description" "SMD Chip Resistor, Jumper, 0 ohm, 100 mW, 0402 [1005 Metric], Thick Film, General Purpose"
				(at 0 0 0)
				(effects
					(font
						(size 1.27 1.27)
					)
					(hide yes)
				)
			)
			(property "MPN" "ERJ2GE0R00X"
				(at 20.32 -20.32 0)
				(effects
					(font
						(size 1.27 1.27)
						(thickness 0.15)
					)
					(justify left bottom)
					(hide yes)
				)
			)
			(property "Manufacturer" "Panasonic"
				(at 20.32 -22.86 0)
				(effects
					(font
						(size 1.27 1.27)
						(thickness 0.15)
					)
					(justify left bottom)
					(hide yes)
				)
			)
			(property "License" "Apache-2.0"
				(at 20.32 -25.4 0)
				(effects
					(font
						(size 1.27 1.27)
						(thickness 0.15)
					)
					(justify left bottom)
					(hide yes)
				)
			)
			(property "Author" "Antmicro"
				(at 20.32 -27.94 0)
				(effects
					(font
						(size 1.27 1.27)
						(thickness 0.15)
					)
					(justify left bottom)
					(hide yes)
				)
			)
			(property "Val" "0R"
				(at 20.32 -7.62 0)
				(effects
					(font
						(size 1.27 1.27)
						(thickness 0.15)
					)
					(justify left bottom)
				)
			)
			(property "Tolerance" "~"
				(at 20.32 -10.16 0)
				(effects
					(font
						(size 1.27 1.27)
					)
					(justify left bottom)
					(hide yes)
				)
			)
			(property "Current" "1A"
				(at 20.32 -30.48 0)
				(effects
					(font
						(size 1.27 1.27)
						(thickness 0.15)
					)
					(justify left bottom)
					(hide yes)
				)
			)
			(property "ki_keywords" "0402, SMT, RESISTOR, PASSIVE"
				(at 0 0 0)
				(effects
					(font
						(size 1.27 1.27)
					)
					(hide yes)
				)
			)
			(symbol "R_0R_0402_0_1"
				(rectangle
					(start 0.635 0.889)
					(end 4.445 -0.889)
					(stroke
						(width 0.254)
						(type default)
					)
					(fill
						(type none)
					)
				)
			)
			(symbol "R_0R_0402_1_1"
				(pin passive line
					(at 0 0 0)
					(length 0.635)
					(name "~"
						(effects
							(font
								(size 1.27 1.27)
							)
						)
					)
					(number "1"
						(effects
							(font
								(size 1.27 1.27)
							)
						)
					)
				)
				(pin passive line
					(at 5.08 0 180)
					(length 0.635)
					(name "~"
						(effects
							(font
								(size 1.27 1.27)
							)
						)
					)
					(number "2"
						(effects
							(font
								(size 1.27 1.27)
							)
						)
					)
				)
			)
		)
	(symbol "antmicroResistors0402:R_100R_0402"
			(pin_numbers
				(hide yes)
			)
			(pin_names
				(hide yes)
			)
			(exclude_from_sim no)
			(in_bom yes)
			(on_board yes)
			(property "Reference" "R"
				(at 20.32 -5.08 0)
				(effects
					(font
						(size 1.27 1.27)
						(thickness 0.15)
					)
					(justify left bottom)
				)
			)
			(property "Value" "R_100R_0402"
				(at 20.32 -12.7 0)
				(effects
					(font
						(size 1.27 1.27)
						(thickness 0.15)
					)
					(justify left bottom)
					(hide yes)
				)
			)
			(property "Footprint" "antmicro-footprints:R_0402_1005Metric"
				(at 20.32 -15.24 0)
				(effects
					(font
						(size 1.27 1.27)
						(thickness 0.15)
					)
					(justify left bottom)
					(hide yes)
				)
			)
			(property "Datasheet" "https://www.bourns.com/docs/product-datasheets/cr.pdf"
				(at 20.32 -17.78 0)
				(effects
					(font
						(size 1.27 1.27)
						(thickness 0.15)
					)
					(justify left bottom)
					(hide yes)
				)
			)
			(property "Description" "SMD Chip Resistor, 100 ohm, ± 1%, 62.5 mW, 0402 [1005 Metric], Thick Film, General Purpose"
				(at 0 0 0)
				(effects
					(font
						(size 1.27 1.27)
					)
					(hide yes)
				)
			)
			(property "MPN" "CR0402-FX-1000GLF"
				(at 20.32 -20.32 0)
				(effects
					(font
						(size 1.27 1.27)
						(thickness 0.15)
					)
					(justify left bottom)
					(hide yes)
				)
			)
			(property "Manufacturer" "Bourns"
				(at 20.32 -22.86 0)
				(effects
					(font
						(size 1.27 1.27)
						(thickness 0.15)
					)
					(justify left bottom)
					(hide yes)
				)
			)
			(property "License" "Apache-2.0"
				(at 20.32 -25.4 0)
				(effects
					(font
						(size 1.27 1.27)
						(thickness 0.15)
					)
					(justify left bottom)
					(hide yes)
				)
			)
			(property "Author" "Antmicro"
				(at 20.32 -27.94 0)
				(effects
					(font
						(size 1.27 1.27)
						(thickness 0.15)
					)
					(justify left bottom)
					(hide yes)
				)
			)
			(property "Val" "100R"
				(at 20.32 -7.62 0)
				(effects
					(font
						(size 1.27 1.27)
						(thickness 0.15)
					)
					(justify left bottom)
				)
			)
			(property "Tolerance" "1%"
				(at 20.32 -10.16 0)
				(effects
					(font
						(size 1.27 1.27)
					)
					(justify left bottom)
					(hide yes)
				)
			)
			(property "ki_keywords" "0402, SMT, RESISTOR, PASSIVE"
				(at 0 0 0)
				(effects
					(font
						(size 1.27 1.27)
					)
					(hide yes)
				)
			)
			(symbol "R_100R_0402_0_1"
				(rectangle
					(start 0.635 0.889)
					(end 4.445 -0.889)
					(stroke
						(width 0.254)
						(type default)
					)
					(fill
						(type none)
					)
				)
			)
			(symbol "R_100R_0402_1_1"
				(pin passive line
					(at 0 0 0)
					(length 0.635)
					(name "~"
						(effects
							(font
								(size 1.27 1.27)
							)
						)
					)
					(number "1"
						(effects
							(font
								(size 1.27 1.27)
							)
						)
					)
				)
				(pin passive line
					(at 5.08 0 180)
					(length 0.635)
					(name "~"
						(effects
							(font
								(size 1.27 1.27)
							)
						)
					)
					(number "2"
						(effects
							(font
								(size 1.27 1.27)
							)
						)
					)
				)
			)
		)
	(symbol "antmicroResistors0402:R_100k_0402"
			(pin_numbers
				(hide yes)
			)
			(pin_names
				(hide yes)
			)
			(exclude_from_sim no)
			(in_bom yes)
			(on_board yes)
			(property "Reference" "R"
				(at 20.32 -5.08 0)
				(effects
					(font
						(size 1.27 1.27)
						(thickness 0.15)
					)
					(justify left bottom)
				)
			)
			(property "Value" "R_100k_0402"
				(at 20.32 -12.7 0)
				(effects
					(font
						(size 1.27 1.27)
						(thickness 0.15)
					)
					(justify left bottom)
					(hide yes)
				)
			)
			(property "Footprint" "antmicro-footprints:R_0402_1005Metric"
				(at 20.32 -15.24 0)
				(effects
					(font
						(size 1.27 1.27)
						(thickness 0.15)
					)
					(justify left bottom)
					(hide yes)
				)
			)
			(property "Datasheet" "https://www.bourns.com/docs/product-datasheets/cr.pdf"
				(at 20.32 -17.78 0)
				(effects
					(font
						(size 1.27 1.27)
						(thickness 0.15)
					)
					(justify left bottom)
					(hide yes)
				)
			)
			(property "Description" "SMD Chip Resistor, 100 kohm, ± 1%, 62.5 mW, 0402 [1005 Metric], Thick Film, General Purpose"
				(at 0 0 0)
				(effects
					(font
						(size 1.27 1.27)
					)
					(hide yes)
				)
			)
			(property "MPN" "CR0402-FX-1003GLF"
				(at 20.32 -20.32 0)
				(effects
					(font
						(size 1.27 1.27)
						(thickness 0.15)
					)
					(justify left bottom)
					(hide yes)
				)
			)
			(property "Manufacturer" "Bourns"
				(at 20.32 -22.86 0)
				(effects
					(font
						(size 1.27 1.27)
						(thickness 0.15)
					)
					(justify left bottom)
					(hide yes)
				)
			)
			(property "License" "Apache-2.0"
				(at 20.32 -25.4 0)
				(effects
					(font
						(size 1.27 1.27)
						(thickness 0.15)
					)
					(justify left bottom)
					(hide yes)
				)
			)
			(property "Author" "Antmicro"
				(at 20.32 -27.94 0)
				(effects
					(font
						(size 1.27 1.27)
						(thickness 0.15)
					)
					(justify left bottom)
					(hide yes)
				)
			)
			(property "Val" "100k"
				(at 20.32 -7.62 0)
				(effects
					(font
						(size 1.27 1.27)
						(thickness 0.15)
					)
					(justify left bottom)
				)
			)
			(property "Tolerance" "1%"
				(at 20.32 -10.16 0)
				(effects
					(font
						(size 1.27 1.27)
					)
					(justify left bottom)
					(hide yes)
				)
			)
			(property "ki_keywords" "0402, SMT, RESISTOR, PASSIVE"
				(at 0 0 0)
				(effects
					(font
						(size 1.27 1.27)
					)
					(hide yes)
				)
			)
			(symbol "R_100k_0402_0_1"
				(rectangle
					(start 0.635 0.889)
					(end 4.445 -0.889)
					(stroke
						(width 0.254)
						(type default)
					)
					(fill
						(type none)
					)
				)
			)
			(symbol "R_100k_0402_1_1"
				(pin passive line
					(at 0 0 0)
					(length 0.635)
					(name "~"
						(effects
							(font
								(size 1.27 1.27)
							)
						)
					)
					(number "1"
						(effects
							(font
								(size 1.27 1.27)
							)
						)
					)
				)
				(pin passive line
					(at 5.08 0 180)
					(length 0.635)
					(name "~"
						(effects
							(font
								(size 1.27 1.27)
							)
						)
					)
					(number "2"
						(effects
							(font
								(size 1.27 1.27)
							)
						)
					)
				)
			)
		)
	(symbol "antmicroResistors0402:R_10R_0402"
			(pin_numbers
				(hide yes)
			)
			(pin_names
				(hide yes)
			)
			(exclude_from_sim no)
			(in_bom yes)
			(on_board yes)
			(property "Reference" "R"
				(at 20.32 -5.08 0)
				(effects
					(font
						(size 1.27 1.27)
						(thickness 0.15)
					)
					(justify left bottom)
				)
			)
			(property "Value" "R_10R_0402"
				(at 20.32 -12.7 0)
				(effects
					(font
						(size 1.27 1.27)
						(thickness 0.15)
					)
					(justify left bottom)
					(hide yes)
				)
			)
			(property "Footprint" "antmicro-footprints:R_0402_1005Metric"
				(at 20.32 -15.24 0)
				(effects
					(font
						(size 1.27 1.27)
						(thickness 0.15)
					)
					(justify left bottom)
					(hide yes)
				)
			)
			(property "Datasheet" "https://www.bourns.com/docs/product-datasheets/cr.pdf"
				(at 20.32 -17.78 0)
				(effects
					(font
						(size 1.27 1.27)
						(thickness 0.15)
					)
					(justify left bottom)
					(hide yes)
				)
			)
			(property "Description" "SMD Chip Resistor, 10 ohm, ± 1%, 62.5 mW, 0402 [1005 Metric], Thick Film, General Purpose"
				(at 0 0 0)
				(effects
					(font
						(size 1.27 1.27)
					)
					(hide yes)
				)
			)
			(property "MPN" "CR0402-FX-10R0GLF"
				(at 20.32 -20.32 0)
				(effects
					(font
						(size 1.27 1.27)
						(thickness 0.15)
					)
					(justify left bottom)
					(hide yes)
				)
			)
			(property "Manufacturer" "Bourns"
				(at 20.32 -22.86 0)
				(effects
					(font
						(size 1.27 1.27)
						(thickness 0.15)
					)
					(justify left bottom)
					(hide yes)
				)
			)
			(property "License" "Apache-2.0"
				(at 20.32 -25.4 0)
				(effects
					(font
						(size 1.27 1.27)
						(thickness 0.15)
					)
					(justify left bottom)
					(hide yes)
				)
			)
			(property "Author" "Antmicro"
				(at 20.32 -27.94 0)
				(effects
					(font
						(size 1.27 1.27)
						(thickness 0.15)
					)
					(justify left bottom)
					(hide yes)
				)
			)
			(property "Val" "10R"
				(at 20.32 -7.62 0)
				(effects
					(font
						(size 1.27 1.27)
						(thickness 0.15)
					)
					(justify left bottom)
				)
			)
			(property "Tolerance" "1%"
				(at 20.32 -10.16 0)
				(effects
					(font
						(size 1.27 1.27)
					)
					(justify left bottom)
					(hide yes)
				)
			)
			(property "ki_keywords" "0402, SMT, RESISTOR, PASSIVE"
				(at 0 0 0)
				(effects
					(font
						(size 1.27 1.27)
					)
					(hide yes)
				)
			)
			(symbol "R_10R_0402_0_1"
				(rectangle
					(start 0.635 0.889)
					(end 4.445 -0.889)
					(stroke
						(width 0.254)
						(type default)
					)
					(fill
						(type none)
					)
				)
			)
			(symbol "R_10R_0402_1_1"
				(pin passive line
					(at 0 0 0)
					(length 0.635)
					(name "~"
						(effects
							(font
								(size 1.27 1.27)
							)
						)
					)
					(number "1"
						(effects
							(font
								(size 1.27 1.27)
							)
						)
					)
				)
				(pin passive line
					(at 5.08 0 180)
					(length 0.635)
					(name "~"
						(effects
							(font
								(size 1.27 1.27)
							)
						)
					)
					(number "2"
						(effects
							(font
								(size 1.27 1.27)
							)
						)
					)
				)
			)
		)
	(symbol "antmicroResistors0402:R_10k_0402"
			(pin_numbers
				(hide yes)
			)
			(pin_names
				(hide yes)
			)
			(exclude_from_sim no)
			(in_bom yes)
			(on_board yes)
			(property "Reference" "R"
				(at 20.32 -5.08 0)
				(effects
					(font
						(size 1.27 1.27)
						(thickness 0.15)
					)
					(justify left bottom)
				)
			)
			(property "Value" "R_10k_0402"
				(at 20.32 -12.7 0)
				(effects
					(font
						(size 1.27 1.27)
						(thickness 0.15)
					)
					(justify left bottom)
					(hide yes)
				)
			)
			(property "Footprint" "antmicro-footprints:R_0402_1005Metric"
				(at 20.32 -15.24 0)
				(effects
					(font
						(size 1.27 1.27)
						(thickness 0.15)
					)
					(justify left bottom)
					(hide yes)
				)
			)
			(property "Datasheet" "https://www.bourns.com/docs/product-datasheets/cr.pdf"
				(at 20.32 -17.78 0)
				(effects
					(font
						(size 1.27 1.27)
						(thickness 0.15)
					)
					(justify left bottom)
					(hide yes)
				)
			)
			(property "Description" "SMD Chip Resistor, 10 kohm, ± 1%, 62.5 mW, 0402 [1005 Metric], Thick Film, General Purpose"
				(at 0 0 0)
				(effects
					(font
						(size 1.27 1.27)
					)
					(hide yes)
				)
			)
			(property "MPN" "CR0402-FX-1002GLF"
				(at 20.32 -20.32 0)
				(effects
					(font
						(size 1.27 1.27)
						(thickness 0.15)
					)
					(justify left bottom)
					(hide yes)
				)
			)
			(property "Manufacturer" "Bourns"
				(at 20.32 -22.86 0)
				(effects
					(font
						(size 1.27 1.27)
						(thickness 0.15)
					)
					(justify left bottom)
					(hide yes)
				)
			)
			(property "License" "Apache-2.0"
				(at 20.32 -25.4 0)
				(effects
					(font
						(size 1.27 1.27)
						(thickness 0.15)
					)
					(justify left bottom)
					(hide yes)
				)
			)
			(property "Author" "Antmicro"
				(at 20.32 -27.94 0)
				(effects
					(font
						(size 1.27 1.27)
						(thickness 0.15)
					)
					(justify left bottom)
					(hide yes)
				)
			)
			(property "Val" "10k"
				(at 20.32 -7.62 0)
				(effects
					(font
						(size 1.27 1.27)
						(thickness 0.15)
					)
					(justify left bottom)
				)
			)
			(property "Tolerance" "1%"
				(at 20.32 -10.16 0)
				(effects
					(font
						(size 1.27 1.27)
					)
					(justify left bottom)
					(hide yes)
				)
			)
			(property "ki_keywords" "0402, SMT, RESISTOR, PASSIVE"
				(at 0 0 0)
				(effects
					(font
						(size 1.27 1.27)
					)
					(hide yes)
				)
			)
			(symbol "R_10k_0402_0_1"
				(rectangle
					(start 0.635 0.889)
					(end 4.445 -0.889)
					(stroke
						(width 0.254)
						(type default)
					)
					(fill
						(type none)
					)
				)
			)
			(symbol "R_10k_0402_1_1"
				(pin passive line
					(at 0 0 0)
					(length 0.635)
					(name "~"
						(effects
							(font
								(size 1.27 1.27)
							)
						)
					)
					(number "1"
						(effects
							(font
								(size 1.27 1.27)
							)
						)
					)
				)
				(pin passive line
					(at 5.08 0 180)
					(length 0.635)
					(name "~"
						(effects
							(font
								(size 1.27 1.27)
							)
						)
					)
					(number "2"
						(effects
							(font
								(size 1.27 1.27)
							)
						)
					)
				)
			)
		)
	(symbol "antmicroResistors0402:R_12k1_0402"
			(pin_numbers
				(hide yes)
			)
			(pin_names
				(hide yes)
			)
			(exclude_from_sim no)
			(in_bom yes)
			(on_board yes)
			(property "Reference" "R"
				(at 20.32 -5.08 0)
				(effects
					(font
						(size 1.27 1.27)
						(thickness 0.15)
					)
					(justify left bottom)
				)
			)
			(property "Value" "R_12k1_0402"
				(at 20.32 -12.7 0)
				(effects
					(font
						(size 1.27 1.27)
						(thickness 0.15)
					)
					(justify left bottom)
					(hide yes)
				)
			)
			(property "Footprint" "antmicro-footprints:R_0402_1005Metric"
				(at 20.32 -15.24 0)
				(effects
					(font
						(size 1.27 1.27)
						(thickness 0.15)
					)
					(justify left bottom)
					(hide yes)
				)
			)
			(property "Datasheet" "https://www.bourns.com/docs/product-datasheets/cr.pdf"
				(at 20.32 -17.78 0)
				(effects
					(font
						(size 1.27 1.27)
						(thickness 0.15)
					)
					(justify left bottom)
					(hide yes)
				)
			)
			(property "Description" "SMD Chip Resistor, 12.1 kohm, ± 1%, 62.5 mW, 0402 [1005 Metric], Thick Film, General Purpose"
				(at 0 0 0)
				(effects
					(font
						(size 1.27 1.27)
					)
					(hide yes)
				)
			)
			(property "MPN" "CR0402-FX-1212GLF"
				(at 20.32 -20.32 0)
				(effects
					(font
						(size 1.27 1.27)
						(thickness 0.15)
					)
					(justify left bottom)
					(hide yes)
				)
			)
			(property "Manufacturer" "Bourns"
				(at 20.32 -22.86 0)
				(effects
					(font
						(size 1.27 1.27)
						(thickness 0.15)
					)
					(justify left bottom)
					(hide yes)
				)
			)
			(property "License" "Apache-2.0"
				(at 20.32 -25.4 0)
				(effects
					(font
						(size 1.27 1.27)
						(thickness 0.15)
					)
					(justify left bottom)
					(hide yes)
				)
			)
			(property "Author" "Antmicro"
				(at 20.32 -27.94 0)
				(effects
					(font
						(size 1.27 1.27)
						(thickness 0.15)
					)
					(justify left bottom)
					(hide yes)
				)
			)
			(property "Val" "12k1"
				(at 20.32 -7.62 0)
				(effects
					(font
						(size 1.27 1.27)
						(thickness 0.15)
					)
					(justify left bottom)
				)
			)
			(property "Tolerance" "1%"
				(at 20.32 -10.16 0)
				(effects
					(font
						(size 1.27 1.27)
					)
					(justify left bottom)
					(hide yes)
				)
			)
			(property "ki_keywords" "0402, SMT, RESISTOR, PASSIVE"
				(at 0 0 0)
				(effects
					(font
						(size 1.27 1.27)
					)
					(hide yes)
				)
			)
			(symbol "R_12k1_0402_0_1"
				(rectangle
					(start 0.635 0.889)
					(end 4.445 -0.889)
					(stroke
						(width 0.254)
						(type default)
					)
					(fill
						(type none)
					)
				)
			)
			(symbol "R_12k1_0402_1_1"
				(pin passive line
					(at 0 0 0)
					(length 0.635)
					(name "~"
						(effects
							(font
								(size 1.27 1.27)
							)
						)
					)
					(number "1"
						(effects
							(font
								(size 1.27 1.27)
							)
						)
					)
				)
				(pin passive line
					(at 5.08 0 180)
					(length 0.635)
					(name "~"
						(effects
							(font
								(size 1.27 1.27)
							)
						)
					)
					(number "2"
						(effects
							(font
								(size 1.27 1.27)
							)
						)
					)
				)
			)
		)
	(symbol "antmicroResistors0402:R_12k_0402"
			(pin_numbers
				(hide yes)
			)
			(pin_names
				(hide yes)
			)
			(exclude_from_sim no)
			(in_bom yes)
			(on_board yes)
			(property "Reference" "R"
				(at 20.32 -5.08 0)
				(effects
					(font
						(size 1.27 1.27)
						(thickness 0.15)
					)
					(justify left bottom)
				)
			)
			(property "Value" "R_12k_0402"
				(at 20.32 -12.7 0)
				(effects
					(font
						(size 1.27 1.27)
						(thickness 0.15)
					)
					(justify left bottom)
					(hide yes)
				)
			)
			(property "Footprint" "antmicro-footprints:R_0402_1005Metric"
				(at 20.32 -15.24 0)
				(effects
					(font
						(size 1.27 1.27)
						(thickness 0.15)
					)
					(justify left bottom)
					(hide yes)
				)
			)
			(property "Datasheet" "https://www.bourns.com/docs/product-datasheets/cr.pdf"
				(at 20.32 -17.78 0)
				(effects
					(font
						(size 1.27 1.27)
						(thickness 0.15)
					)
					(justify left bottom)
					(hide yes)
				)
			)
			(property "Description" "SMD Chip Resistor, 12 kohm, ± 1%, 62.5 mW, 0402 [1005 Metric], Thick Film, General Purpose"
				(at 0 0 0)
				(effects
					(font
						(size 1.27 1.27)
					)
					(hide yes)
				)
			)
			(property "MPN" "CR0402-FX-1202GLF"
				(at 20.32 -20.32 0)
				(effects
					(font
						(size 1.27 1.27)
						(thickness 0.15)
					)
					(justify left bottom)
					(hide yes)
				)
			)
			(property "Manufacturer" "Bourns"
				(at 20.32 -22.86 0)
				(effects
					(font
						(size 1.27 1.27)
						(thickness 0.15)
					)
					(justify left bottom)
					(hide yes)
				)
			)
			(property "License" "Apache-2.0"
				(at 20.32 -25.4 0)
				(effects
					(font
						(size 1.27 1.27)
						(thickness 0.15)
					)
					(justify left bottom)
					(hide yes)
				)
			)
			(property "Author" "Antmicro"
				(at 20.32 -27.94 0)
				(effects
					(font
						(size 1.27 1.27)
						(thickness 0.15)
					)
					(justify left bottom)
					(hide yes)
				)
			)
			(property "Val" "12k"
				(at 20.32 -7.62 0)
				(effects
					(font
						(size 1.27 1.27)
						(thickness 0.15)
					)
					(justify left bottom)
				)
			)
			(property "Tolerance" "1%"
				(at 20.32 -10.16 0)
				(effects
					(font
						(size 1.27 1.27)
					)
					(justify left bottom)
					(hide yes)
				)
			)
			(property "ki_keywords" "0402, SMT, RESISTOR, PASSIVE"
				(at 0 0 0)
				(effects
					(font
						(size 1.27 1.27)
					)
					(hide yes)
				)
			)
			(symbol "R_12k_0402_0_1"
				(rectangle
					(start 0.635 0.889)
					(end 4.445 -0.889)
					(stroke
						(width 0.254)
						(type default)
					)
					(fill
						(type none)
					)
				)
			)
			(symbol "R_12k_0402_1_1"
				(pin passive line
					(at 0 0 0)
					(length 0.635)
					(name "~"
						(effects
							(font
								(size 1.27 1.27)
							)
						)
					)
					(number "1"
						(effects
							(font
								(size 1.27 1.27)
							)
						)
					)
				)
				(pin passive line
					(at 5.08 0 180)
					(length 0.635)
					(name "~"
						(effects
							(font
								(size 1.27 1.27)
							)
						)
					)
					(number "2"
						(effects
							(font
								(size 1.27 1.27)
							)
						)
					)
				)
			)
		)
	(symbol "antmicroResistors0402:R_15k_0402"
			(pin_numbers
				(hide yes)
			)
			(pin_names
				(hide yes)
			)
			(exclude_from_sim no)
			(in_bom yes)
			(on_board yes)
			(property "Reference" "R"
				(at 20.32 -5.08 0)
				(effects
					(font
						(size 1.27 1.27)
						(thickness 0.15)
					)
					(justify left bottom)
				)
			)
			(property "Value" "R_15k_0402"
				(at 20.32 -12.7 0)
				(effects
					(font
						(size 1.27 1.27)
						(thickness 0.15)
					)
					(justify left bottom)
					(hide yes)
				)
			)
			(property "Footprint" "antmicro-footprints:R_0402_1005Metric"
				(at 20.32 -15.24 0)
				(effects
					(font
						(size 1.27 1.27)
						(thickness 0.15)
					)
					(justify left bottom)
					(hide yes)
				)
			)
			(property "Datasheet" "https://www.bourns.com/docs/product-datasheets/cr.pdf"
				(at 20.32 -17.78 0)
				(effects
					(font
						(size 1.27 1.27)
						(thickness 0.15)
					)
					(justify left bottom)
					(hide yes)
				)
			)
			(property "Description" "SMD Chip Resistor, 15 kohm, ± 1%, 62.5 mW, 0402 [1005 Metric], Thick Film, General Purpose"
				(at 0 0 0)
				(effects
					(font
						(size 1.27 1.27)
					)
					(hide yes)
				)
			)
			(property "MPN" "CR0402-FX-1502GLF"
				(at 20.32 -20.32 0)
				(effects
					(font
						(size 1.27 1.27)
						(thickness 0.15)
					)
					(justify left bottom)
					(hide yes)
				)
			)
			(property "Manufacturer" "Bourns"
				(at 20.32 -22.86 0)
				(effects
					(font
						(size 1.27 1.27)
						(thickness 0.15)
					)
					(justify left bottom)
					(hide yes)
				)
			)
			(property "License" "Apache-2.0"
				(at 20.32 -25.4 0)
				(effects
					(font
						(size 1.27 1.27)
						(thickness 0.15)
					)
					(justify left bottom)
					(hide yes)
				)
			)
			(property "Author" "Antmicro"
				(at 20.32 -27.94 0)
				(effects
					(font
						(size 1.27 1.27)
						(thickness 0.15)
					)
					(justify left bottom)
					(hide yes)
				)
			)
			(property "Val" "15k"
				(at 20.32 -7.62 0)
				(effects
					(font
						(size 1.27 1.27)
						(thickness 0.15)
					)
					(justify left bottom)
				)
			)
			(property "Tolerance" "1%"
				(at 20.32 -10.16 0)
				(effects
					(font
						(size 1.27 1.27)
					)
					(justify left bottom)
					(hide yes)
				)
			)
			(property "ki_keywords" "0402, SMT, RESISTOR, PASSIVE"
				(at 0 0 0)
				(effects
					(font
						(size 1.27 1.27)
					)
					(hide yes)
				)
			)
			(symbol "R_15k_0402_0_1"
				(rectangle
					(start 0.635 0.889)
					(end 4.445 -0.889)
					(stroke
						(width 0.254)
						(type default)
					)
					(fill
						(type none)
					)
				)
			)
			(symbol "R_15k_0402_1_1"
				(pin passive line
					(at 0 0 0)
					(length 0.635)
					(name "~"
						(effects
							(font
								(size 1.27 1.27)
							)
						)
					)
					(number "1"
						(effects
							(font
								(size 1.27 1.27)
							)
						)
					)
				)
				(pin passive line
					(at 5.08 0 180)
					(length 0.635)
					(name "~"
						(effects
							(font
								(size 1.27 1.27)
							)
						)
					)
					(number "2"
						(effects
							(font
								(size 1.27 1.27)
							)
						)
					)
				)
			)
		)
	(symbol "antmicroResistors0402:R_1M8_0402"
			(pin_numbers
				(hide yes)
			)
			(pin_names
				(hide yes)
			)
			(exclude_from_sim no)
			(in_bom yes)
			(on_board yes)
			(property "Reference" "R"
				(at 20.32 -5.08 0)
				(effects
					(font
						(size 1.27 1.27)
						(thickness 0.15)
					)
					(justify left bottom)
				)
			)
			(property "Value" "R_1M8_0402"
				(at 20.32 -12.7 0)
				(effects
					(font
						(size 1.27 1.27)
						(thickness 0.15)
					)
					(justify left bottom)
					(hide yes)
				)
			)
			(property "Footprint" "antmicro-footprints:R_0402_1005Metric"
				(at 20.32 -15.24 0)
				(effects
					(font
						(size 1.27 1.27)
						(thickness 0.15)
					)
					(justify left bottom)
					(hide yes)
				)
			)
			(property "Datasheet" "https://www.bourns.com/docs/product-datasheets/cr.pdf"
				(at 20.32 -17.78 0)
				(effects
					(font
						(size 1.27 1.27)
						(thickness 0.15)
					)
					(justify left bottom)
					(hide yes)
				)
			)
			(property "Description" "SMD Chip Resistor"
				(at 0 0 0)
				(effects
					(font
						(size 1.27 1.27)
					)
					(hide yes)
				)
			)
			(property "MPN" "CR0402-FX-1804GLF"
				(at 20.32 -20.32 0)
				(effects
					(font
						(size 1.27 1.27)
						(thickness 0.15)
					)
					(justify left bottom)
					(hide yes)
				)
			)
			(property "Manufacturer" "Bourns"
				(at 20.32 -22.86 0)
				(effects
					(font
						(size 1.27 1.27)
						(thickness 0.15)
					)
					(justify left bottom)
					(hide yes)
				)
			)
			(property "License" "Apache-2.0"
				(at 20.32 -25.4 0)
				(effects
					(font
						(size 1.27 1.27)
						(thickness 0.15)
					)
					(justify left bottom)
					(hide yes)
				)
			)
			(property "Author" "Antmicro"
				(at 20.32 -27.94 0)
				(effects
					(font
						(size 1.27 1.27)
						(thickness 0.15)
					)
					(justify left bottom)
					(hide yes)
				)
			)
			(property "Val" "1M8"
				(at 20.32 -7.62 0)
				(effects
					(font
						(size 1.27 1.27)
						(thickness 0.15)
					)
					(justify left bottom)
				)
			)
			(property "Tolerance" "1%"
				(at 20.32 -10.16 0)
				(effects
					(font
						(size 1.27 1.27)
					)
					(justify left bottom)
					(hide yes)
				)
			)
			(property "ki_keywords" "0402, SMT, RESISTOR, PASSIVE"
				(at 0 0 0)
				(effects
					(font
						(size 1.27 1.27)
					)
					(hide yes)
				)
			)
			(symbol "R_1M8_0402_0_1"
				(rectangle
					(start 0.635 0.889)
					(end 4.445 -0.889)
					(stroke
						(width 0.254)
						(type default)
					)
					(fill
						(type none)
					)
				)
			)
			(symbol "R_1M8_0402_1_1"
				(pin passive line
					(at 0 0 0)
					(length 0.635)
					(name "~"
						(effects
							(font
								(size 1.27 1.27)
							)
						)
					)
					(number "1"
						(effects
							(font
								(size 1.27 1.27)
							)
						)
					)
				)
				(pin passive line
					(at 5.08 0 180)
					(length 0.635)
					(name "~"
						(effects
							(font
								(size 1.27 1.27)
							)
						)
					)
					(number "2"
						(effects
							(font
								(size 1.27 1.27)
							)
						)
					)
				)
			)
		)
	(symbol "antmicroResistors0402:R_1k_0402"
			(pin_numbers
				(hide yes)
			)
			(pin_names
				(hide yes)
			)
			(exclude_from_sim no)
			(in_bom yes)
			(on_board yes)
			(property "Reference" "R"
				(at 20.32 -5.08 0)
				(effects
					(font
						(size 1.27 1.27)
						(thickness 0.15)
					)
					(justify left bottom)
				)
			)
			(property "Value" "R_1k_0402"
				(at 20.32 -12.7 0)
				(effects
					(font
						(size 1.27 1.27)
						(thickness 0.15)
					)
					(justify left bottom)
					(hide yes)
				)
			)
			(property "Footprint" "antmicro-footprints:R_0402_1005Metric"
				(at 20.32 -15.24 0)
				(effects
					(font
						(size 1.27 1.27)
						(thickness 0.15)
					)
					(justify left bottom)
					(hide yes)
				)
			)
			(property "Datasheet" "https://www.bourns.com/docs/product-datasheets/cr.pdf"
				(at 20.32 -17.78 0)
				(effects
					(font
						(size 1.27 1.27)
						(thickness 0.15)
					)
					(justify left bottom)
					(hide yes)
				)
			)
			(property "Description" "SMD Chip Resistor, 1 kohm, ± 1%, 63 mW, 0402 [1005 Metric], Thick Film, General Purpose"
				(at 0 0 0)
				(effects
					(font
						(size 1.27 1.27)
					)
					(hide yes)
				)
			)
			(property "MPN" "CR0402-FX-1001GLF"
				(at 20.32 -20.32 0)
				(effects
					(font
						(size 1.27 1.27)
						(thickness 0.15)
					)
					(justify left bottom)
					(hide yes)
				)
			)
			(property "Manufacturer" "Bourns"
				(at 20.32 -22.86 0)
				(effects
					(font
						(size 1.27 1.27)
						(thickness 0.15)
					)
					(justify left bottom)
					(hide yes)
				)
			)
			(property "License" "Apache-2.0"
				(at 20.32 -25.4 0)
				(effects
					(font
						(size 1.27 1.27)
						(thickness 0.15)
					)
					(justify left bottom)
					(hide yes)
				)
			)
			(property "Author" "Antmicro"
				(at 20.32 -27.94 0)
				(effects
					(font
						(size 1.27 1.27)
						(thickness 0.15)
					)
					(justify left bottom)
					(hide yes)
				)
			)
			(property "Val" "1k"
				(at 20.32 -7.62 0)
				(effects
					(font
						(size 1.27 1.27)
						(thickness 0.15)
					)
					(justify left bottom)
				)
			)
			(property "Tolerance" "1%"
				(at 20.32 -10.16 0)
				(effects
					(font
						(size 1.27 1.27)
					)
					(justify left bottom)
					(hide yes)
				)
			)
			(property "ki_keywords" "0402, SMT, RESISTOR, PASSIVE"
				(at 0 0 0)
				(effects
					(font
						(size 1.27 1.27)
					)
					(hide yes)
				)
			)
			(symbol "R_1k_0402_0_1"
				(rectangle
					(start 0.635 0.889)
					(end 4.445 -0.889)
					(stroke
						(width 0.254)
						(type default)
					)
					(fill
						(type none)
					)
				)
			)
			(symbol "R_1k_0402_1_1"
				(pin passive line
					(at 0 0 0)
					(length 0.635)
					(name "~"
						(effects
							(font
								(size 1.27 1.27)
							)
						)
					)
					(number "1"
						(effects
							(font
								(size 1.27 1.27)
							)
						)
					)
				)
				(pin passive line
					(at 5.08 0 180)
					(length 0.635)
					(name "~"
						(effects
							(font
								(size 1.27 1.27)
							)
						)
					)
					(number "2"
						(effects
							(font
								(size 1.27 1.27)
							)
						)
					)
				)
			)
		)
	(symbol "antmicroResistors0402:R_200k_0402"
			(pin_numbers
				(hide yes)
			)
			(pin_names
				(hide yes)
			)
			(exclude_from_sim no)
			(in_bom yes)
			(on_board yes)
			(property "Reference" "R"
				(at 20.32 -5.08 0)
				(effects
					(font
						(size 1.27 1.27)
						(thickness 0.15)
					)
					(justify left bottom)
				)
			)
			(property "Value" "R_200k_0402"
				(at 20.32 -12.7 0)
				(effects
					(font
						(size 1.27 1.27)
						(thickness 0.15)
					)
					(justify left bottom)
					(hide yes)
				)
			)
			(property "Footprint" "antmicro-footprints:R_0402_1005Metric"
				(at 20.32 -15.24 0)
				(effects
					(font
						(size 1.27 1.27)
						(thickness 0.15)
					)
					(justify left bottom)
					(hide yes)
				)
			)
			(property "Datasheet" "https://www.bourns.com/docs/product-datasheets/cr.pdf"
				(at 20.32 -17.78 0)
				(effects
					(font
						(size 1.27 1.27)
						(thickness 0.15)
					)
					(justify left bottom)
					(hide yes)
				)
			)
			(property "Description" "SMD Chip Resistor, 200 kohm, ± 1%, 62.5 mW, 0402 [1005 Metric], Thick Film, General Purpose"
				(at 0 0 0)
				(effects
					(font
						(size 1.27 1.27)
					)
					(hide yes)
				)
			)
			(property "MPN" "CR0402-FX-2003GLF"
				(at 20.32 -20.32 0)
				(effects
					(font
						(size 1.27 1.27)
						(thickness 0.15)
					)
					(justify left bottom)
					(hide yes)
				)
			)
			(property "Manufacturer" "Bourns"
				(at 20.32 -22.86 0)
				(effects
					(font
						(size 1.27 1.27)
						(thickness 0.15)
					)
					(justify left bottom)
					(hide yes)
				)
			)
			(property "License" "Apache-2.0"
				(at 20.32 -25.4 0)
				(effects
					(font
						(size 1.27 1.27)
						(thickness 0.15)
					)
					(justify left bottom)
					(hide yes)
				)
			)
			(property "Author" "Antmicro"
				(at 20.32 -27.94 0)
				(effects
					(font
						(size 1.27 1.27)
						(thickness 0.15)
					)
					(justify left bottom)
					(hide yes)
				)
			)
			(property "Val" "200k"
				(at 20.32 -7.62 0)
				(effects
					(font
						(size 1.27 1.27)
						(thickness 0.15)
					)
					(justify left bottom)
				)
			)
			(property "Tolerance" "1%"
				(at 20.32 -10.16 0)
				(effects
					(font
						(size 1.27 1.27)
					)
					(justify left bottom)
					(hide yes)
				)
			)
			(property "ki_keywords" "0402, SMT, RESISTOR, PASSIVE"
				(at 0 0 0)
				(effects
					(font
						(size 1.27 1.27)
					)
					(hide yes)
				)
			)
			(symbol "R_200k_0402_0_1"
				(rectangle
					(start 0.635 0.889)
					(end 4.445 -0.889)
					(stroke
						(width 0.254)
						(type default)
					)
					(fill
						(type none)
					)
				)
			)
			(symbol "R_200k_0402_1_1"
				(pin passive line
					(at 0 0 0)
					(length 0.635)
					(name "~"
						(effects
							(font
								(size 1.27 1.27)
							)
						)
					)
					(number "1"
						(effects
							(font
								(size 1.27 1.27)
							)
						)
					)
				)
				(pin passive line
					(at 5.08 0 180)
					(length 0.635)
					(name "~"
						(effects
							(font
								(size 1.27 1.27)
							)
						)
					)
					(number "2"
						(effects
							(font
								(size 1.27 1.27)
							)
						)
					)
				)
			)
		)
	(symbol "antmicroResistors0402:R_220R_0402"
			(pin_numbers
				(hide yes)
			)
			(pin_names
				(hide yes)
			)
			(exclude_from_sim no)
			(in_bom yes)
			(on_board yes)
			(property "Reference" "R"
				(at 20.32 -5.08 0)
				(effects
					(font
						(size 1.27 1.27)
						(thickness 0.15)
					)
					(justify left bottom)
				)
			)
			(property "Value" "R_220R_0402"
				(at 20.32 -12.7 0)
				(effects
					(font
						(size 1.27 1.27)
						(thickness 0.15)
					)
					(justify left bottom)
					(hide yes)
				)
			)
			(property "Footprint" "antmicro-footprints:R_0402_1005Metric"
				(at 20.32 -15.24 0)
				(effects
					(font
						(size 1.27 1.27)
						(thickness 0.15)
					)
					(justify left bottom)
					(hide yes)
				)
			)
			(property "Datasheet" "https://www.bourns.com/docs/product-datasheets/cr.pdf"
				(at 20.32 -17.78 0)
				(effects
					(font
						(size 1.27 1.27)
						(thickness 0.15)
					)
					(justify left bottom)
					(hide yes)
				)
			)
			(property "Description" "SMD Chip Resistor, 220 ohm, ± 1%, 62.5 mW, 0402 [1005 Metric], Thick Film, General Purpose"
				(at 0 0 0)
				(effects
					(font
						(size 1.27 1.27)
					)
					(hide yes)
				)
			)
			(property "MPN" "CR0402-FX-2200GLF"
				(at 20.32 -20.32 0)
				(effects
					(font
						(size 1.27 1.27)
						(thickness 0.15)
					)
					(justify left bottom)
					(hide yes)
				)
			)
			(property "Manufacturer" "Bourns"
				(at 20.32 -22.86 0)
				(effects
					(font
						(size 1.27 1.27)
						(thickness 0.15)
					)
					(justify left bottom)
					(hide yes)
				)
			)
			(property "License" "Apache-2.0"
				(at 20.32 -25.4 0)
				(effects
					(font
						(size 1.27 1.27)
						(thickness 0.15)
					)
					(justify left bottom)
					(hide yes)
				)
			)
			(property "Author" "Antmicro"
				(at 20.32 -27.94 0)
				(effects
					(font
						(size 1.27 1.27)
						(thickness 0.15)
					)
					(justify left bottom)
					(hide yes)
				)
			)
			(property "Val" "220R"
				(at 20.32 -7.62 0)
				(effects
					(font
						(size 1.27 1.27)
						(thickness 0.15)
					)
					(justify left bottom)
				)
			)
			(property "Tolerance" "1%"
				(at 20.32 -10.16 0)
				(effects
					(font
						(size 1.27 1.27)
					)
					(justify left bottom)
					(hide yes)
				)
			)
			(property "ki_keywords" "0402, SMT, RESISTOR, PASSIVE"
				(at 0 0 0)
				(effects
					(font
						(size 1.27 1.27)
					)
					(hide yes)
				)
			)
			(symbol "R_220R_0402_0_1"
				(rectangle
					(start 0.635 0.889)
					(end 4.445 -0.889)
					(stroke
						(width 0.254)
						(type default)
					)
					(fill
						(type none)
					)
				)
			)
			(symbol "R_220R_0402_1_1"
				(pin passive line
					(at 0 0 0)
					(length 0.635)
					(name "~"
						(effects
							(font
								(size 1.27 1.27)
							)
						)
					)
					(number "1"
						(effects
							(font
								(size 1.27 1.27)
							)
						)
					)
				)
				(pin passive line
					(at 5.08 0 180)
					(length 0.635)
					(name "~"
						(effects
							(font
								(size 1.27 1.27)
							)
						)
					)
					(number "2"
						(effects
							(font
								(size 1.27 1.27)
							)
						)
					)
				)
			)
		)
	(symbol "antmicroResistors0402:R_22R_0402"
			(pin_numbers
				(hide yes)
			)
			(pin_names
				(hide yes)
			)
			(exclude_from_sim no)
			(in_bom yes)
			(on_board yes)
			(property "Reference" "R"
				(at 20.32 -5.08 0)
				(effects
					(font
						(size 1.27 1.27)
						(thickness 0.15)
					)
					(justify left bottom)
				)
			)
			(property "Value" "R_22R_0402"
				(at 20.32 -12.7 0)
				(effects
					(font
						(size 1.27 1.27)
						(thickness 0.15)
					)
					(justify left bottom)
					(hide yes)
				)
			)
			(property "Footprint" "antmicro-footprints:R_0402_1005Metric"
				(at 20.32 -15.24 0)
				(effects
					(font
						(size 1.27 1.27)
						(thickness 0.15)
					)
					(justify left bottom)
					(hide yes)
				)
			)
			(property "Datasheet" "https://www.bourns.com/docs/product-datasheets/cr.pdf"
				(at 20.32 -17.78 0)
				(effects
					(font
						(size 1.27 1.27)
						(thickness 0.15)
					)
					(justify left bottom)
					(hide yes)
				)
			)
			(property "Description" "SMD Chip Resistor, 22 ohm, ± 1%, 62.5 mW, 0402 [1005 Metric], Thick Film, General Purpose"
				(at 0 0 0)
				(effects
					(font
						(size 1.27 1.27)
					)
					(hide yes)
				)
			)
			(property "MPN" "CR0402-FX-22R0GLF"
				(at 20.32 -20.32 0)
				(effects
					(font
						(size 1.27 1.27)
						(thickness 0.15)
					)
					(justify left bottom)
					(hide yes)
				)
			)
			(property "Manufacturer" "Bourns"
				(at 20.32 -22.86 0)
				(effects
					(font
						(size 1.27 1.27)
						(thickness 0.15)
					)
					(justify left bottom)
					(hide yes)
				)
			)
			(property "License" "Apache-2.0"
				(at 20.32 -25.4 0)
				(effects
					(font
						(size 1.27 1.27)
						(thickness 0.15)
					)
					(justify left bottom)
					(hide yes)
				)
			)
			(property "Author" "Antmicro"
				(at 20.32 -27.94 0)
				(effects
					(font
						(size 1.27 1.27)
						(thickness 0.15)
					)
					(justify left bottom)
					(hide yes)
				)
			)
			(property "Val" "22R"
				(at 20.32 -7.62 0)
				(effects
					(font
						(size 1.27 1.27)
						(thickness 0.15)
					)
					(justify left bottom)
				)
			)
			(property "Tolerance" "1%"
				(at 20.32 -10.16 0)
				(effects
					(font
						(size 1.27 1.27)
					)
					(justify left bottom)
					(hide yes)
				)
			)
			(property "ki_keywords" "0402, SMT, RESISTOR, PASSIVE"
				(at 0 0 0)
				(effects
					(font
						(size 1.27 1.27)
					)
					(hide yes)
				)
			)
			(symbol "R_22R_0402_0_1"
				(rectangle
					(start 0.635 0.889)
					(end 4.445 -0.889)
					(stroke
						(width 0.254)
						(type default)
					)
					(fill
						(type none)
					)
				)
			)
			(symbol "R_22R_0402_1_1"
				(pin passive line
					(at 0 0 0)
					(length 0.635)
					(name "~"
						(effects
							(font
								(size 1.27 1.27)
							)
						)
					)
					(number "1"
						(effects
							(font
								(size 1.27 1.27)
							)
						)
					)
				)
				(pin passive line
					(at 5.08 0 180)
					(length 0.635)
					(name "~"
						(effects
							(font
								(size 1.27 1.27)
							)
						)
					)
					(number "2"
						(effects
							(font
								(size 1.27 1.27)
							)
						)
					)
				)
			)
		)
	(symbol "antmicroResistors0402:R_240R_0402"
			(pin_numbers
				(hide yes)
			)
			(pin_names
				(hide yes)
			)
			(exclude_from_sim no)
			(in_bom yes)
			(on_board yes)
			(property "Reference" "R"
				(at 20.32 -5.08 0)
				(effects
					(font
						(size 1.27 1.27)
						(thickness 0.15)
					)
					(justify left bottom)
				)
			)
			(property "Value" "R_240R_0402"
				(at 20.32 -12.7 0)
				(effects
					(font
						(size 1.27 1.27)
						(thickness 0.15)
					)
					(justify left bottom)
					(hide yes)
				)
			)
			(property "Footprint" "antmicro-footprints:R_0402_1005Metric"
				(at 20.32 -15.24 0)
				(effects
					(font
						(size 1.27 1.27)
						(thickness 0.15)
					)
					(justify left bottom)
					(hide yes)
				)
			)
			(property "Datasheet" "https://www.bourns.com/docs/product-datasheets/cr.pdf"
				(at 20.32 -17.78 0)
				(effects
					(font
						(size 1.27 1.27)
						(thickness 0.15)
					)
					(justify left bottom)
					(hide yes)
				)
			)
			(property "Description" "SMD Chip Resistor, 240 ohm, ± 1%, 63 mW, 0402 [1005 Metric], Thick Film, General Purpose"
				(at 0 0 0)
				(effects
					(font
						(size 1.27 1.27)
					)
					(hide yes)
				)
			)
			(property "MPN" "CR0402-FX-2400GLF"
				(at 20.32 -20.32 0)
				(effects
					(font
						(size 1.27 1.27)
						(thickness 0.15)
					)
					(justify left bottom)
					(hide yes)
				)
			)
			(property "Manufacturer" "Bourns"
				(at 20.32 -22.86 0)
				(effects
					(font
						(size 1.27 1.27)
						(thickness 0.15)
					)
					(justify left bottom)
					(hide yes)
				)
			)
			(property "License" "Apache-2.0"
				(at 20.32 -25.4 0)
				(effects
					(font
						(size 1.27 1.27)
						(thickness 0.15)
					)
					(justify left bottom)
					(hide yes)
				)
			)
			(property "Author" "Antmicro"
				(at 20.32 -27.94 0)
				(effects
					(font
						(size 1.27 1.27)
						(thickness 0.15)
					)
					(justify left bottom)
					(hide yes)
				)
			)
			(property "Val" "240R"
				(at 20.32 -7.62 0)
				(effects
					(font
						(size 1.27 1.27)
						(thickness 0.15)
					)
					(justify left bottom)
				)
			)
			(property "Tolerance" "1%"
				(at 20.32 -10.16 0)
				(effects
					(font
						(size 1.27 1.27)
					)
					(justify left bottom)
					(hide yes)
				)
			)
			(property "ki_keywords" "0402, SMT, RESISTOR, PASSIVE"
				(at 0 0 0)
				(effects
					(font
						(size 1.27 1.27)
					)
					(hide yes)
				)
			)
			(symbol "R_240R_0402_0_1"
				(rectangle
					(start 0.635 0.889)
					(end 4.445 -0.889)
					(stroke
						(width 0.254)
						(type default)
					)
					(fill
						(type none)
					)
				)
			)
			(symbol "R_240R_0402_1_1"
				(pin passive line
					(at 0 0 0)
					(length 0.635)
					(name "~"
						(effects
							(font
								(size 1.27 1.27)
							)
						)
					)
					(number "1"
						(effects
							(font
								(size 1.27 1.27)
							)
						)
					)
				)
				(pin passive line
					(at 5.08 0 180)
					(length 0.635)
					(name "~"
						(effects
							(font
								(size 1.27 1.27)
							)
						)
					)
					(number "2"
						(effects
							(font
								(size 1.27 1.27)
							)
						)
					)
				)
			)
		)
	(symbol "antmicroResistors0402:R_2k2_0402"
			(pin_numbers
				(hide yes)
			)
			(pin_names
				(hide yes)
			)
			(exclude_from_sim no)
			(in_bom yes)
			(on_board yes)
			(property "Reference" "R"
				(at 20.32 -5.08 0)
				(effects
					(font
						(size 1.27 1.27)
						(thickness 0.15)
					)
					(justify left bottom)
				)
			)
			(property "Value" "R_2k2_0402"
				(at 20.32 -12.7 0)
				(effects
					(font
						(size 1.27 1.27)
						(thickness 0.15)
					)
					(justify left bottom)
					(hide yes)
				)
			)
			(property "Footprint" "antmicro-footprints:R_0402_1005Metric"
				(at 20.32 -15.24 0)
				(effects
					(font
						(size 1.27 1.27)
						(thickness 0.15)
					)
					(justify left bottom)
					(hide yes)
				)
			)
			(property "Datasheet" "https://www.bourns.com/docs/product-datasheets/cr.pdf"
				(at 20.32 -17.78 0)
				(effects
					(font
						(size 1.27 1.27)
						(thickness 0.15)
					)
					(justify left bottom)
					(hide yes)
				)
			)
			(property "Description" "SMD Chip Resistor, 2.2 kohm, ± 1%, 62.5 mW, 0402 [1005 Metric], Thick Film, General Purpose"
				(at 0 0 0)
				(effects
					(font
						(size 1.27 1.27)
					)
					(hide yes)
				)
			)
			(property "MPN" "CR0402-FX-2201GLF"
				(at 20.32 -20.32 0)
				(effects
					(font
						(size 1.27 1.27)
						(thickness 0.15)
					)
					(justify left bottom)
					(hide yes)
				)
			)
			(property "Manufacturer" "Bourns"
				(at 20.32 -22.86 0)
				(effects
					(font
						(size 1.27 1.27)
						(thickness 0.15)
					)
					(justify left bottom)
					(hide yes)
				)
			)
			(property "License" "Apache-2.0"
				(at 20.32 -25.4 0)
				(effects
					(font
						(size 1.27 1.27)
						(thickness 0.15)
					)
					(justify left bottom)
					(hide yes)
				)
			)
			(property "Author" "Antmicro"
				(at 20.32 -27.94 0)
				(effects
					(font
						(size 1.27 1.27)
						(thickness 0.15)
					)
					(justify left bottom)
					(hide yes)
				)
			)
			(property "Val" "2k2"
				(at 20.32 -7.62 0)
				(effects
					(font
						(size 1.27 1.27)
						(thickness 0.15)
					)
					(justify left bottom)
				)
			)
			(property "Tolerance" "1%"
				(at 20.32 -10.16 0)
				(effects
					(font
						(size 1.27 1.27)
					)
					(justify left bottom)
					(hide yes)
				)
			)
			(property "ki_keywords" "0402, SMT, RESISTOR, PASSIVE"
				(at 0 0 0)
				(effects
					(font
						(size 1.27 1.27)
					)
					(hide yes)
				)
			)
			(symbol "R_2k2_0402_0_1"
				(rectangle
					(start 0.635 0.889)
					(end 4.445 -0.889)
					(stroke
						(width 0.254)
						(type default)
					)
					(fill
						(type none)
					)
				)
			)
			(symbol "R_2k2_0402_1_1"
				(pin passive line
					(at 0 0 0)
					(length 0.635)
					(name "~"
						(effects
							(font
								(size 1.27 1.27)
							)
						)
					)
					(number "1"
						(effects
							(font
								(size 1.27 1.27)
							)
						)
					)
				)
				(pin passive line
					(at 5.08 0 180)
					(length 0.635)
					(name "~"
						(effects
							(font
								(size 1.27 1.27)
							)
						)
					)
					(number "2"
						(effects
							(font
								(size 1.27 1.27)
							)
						)
					)
				)
			)
		)
	(symbol "antmicroResistors0402:R_330R_0402"
			(pin_numbers
				(hide yes)
			)
			(pin_names
				(hide yes)
			)
			(exclude_from_sim no)
			(in_bom yes)
			(on_board yes)
			(property "Reference" "R"
				(at 20.32 -5.08 0)
				(effects
					(font
						(size 1.27 1.27)
						(thickness 0.15)
					)
					(justify left bottom)
				)
			)
			(property "Value" "R_330R_0402"
				(at 20.32 -12.7 0)
				(effects
					(font
						(size 1.27 1.27)
						(thickness 0.15)
					)
					(justify left bottom)
					(hide yes)
				)
			)
			(property "Footprint" "antmicro-footprints:R_0402_1005Metric"
				(at 20.32 -15.24 0)
				(effects
					(font
						(size 1.27 1.27)
						(thickness 0.15)
					)
					(justify left bottom)
					(hide yes)
				)
			)
			(property "Datasheet" "https://www.bourns.com/docs/product-datasheets/cr.pdf"
				(at 20.32 -17.78 0)
				(effects
					(font
						(size 1.27 1.27)
						(thickness 0.15)
					)
					(justify left bottom)
					(hide yes)
				)
			)
			(property "Description" "SMD Chip Resistor, 330 ohm, ± 1%, 62.5 mW, 0402 [1005 Metric], Thick Film, General Purpose"
				(at 0 0 0)
				(effects
					(font
						(size 1.27 1.27)
					)
					(hide yes)
				)
			)
			(property "MPN" "CR0402-FX-3300GLF"
				(at 20.32 -20.32 0)
				(effects
					(font
						(size 1.27 1.27)
						(thickness 0.15)
					)
					(justify left bottom)
					(hide yes)
				)
			)
			(property "Manufacturer" "Bourns"
				(at 20.32 -22.86 0)
				(effects
					(font
						(size 1.27 1.27)
						(thickness 0.15)
					)
					(justify left bottom)
					(hide yes)
				)
			)
			(property "License" "Apache-2.0"
				(at 20.32 -25.4 0)
				(effects
					(font
						(size 1.27 1.27)
						(thickness 0.15)
					)
					(justify left bottom)
					(hide yes)
				)
			)
			(property "Author" "Antmicro"
				(at 20.32 -27.94 0)
				(effects
					(font
						(size 1.27 1.27)
						(thickness 0.15)
					)
					(justify left bottom)
					(hide yes)
				)
			)
			(property "Val" "330R"
				(at 20.32 -7.62 0)
				(effects
					(font
						(size 1.27 1.27)
						(thickness 0.15)
					)
					(justify left bottom)
				)
			)
			(property "Tolerance" "1%"
				(at 20.32 -10.16 0)
				(effects
					(font
						(size 1.27 1.27)
					)
					(justify left bottom)
					(hide yes)
				)
			)
			(property "ki_keywords" "0402, SMT, RESISTOR, PASSIVE"
				(at 0 0 0)
				(effects
					(font
						(size 1.27 1.27)
					)
					(hide yes)
				)
			)
			(symbol "R_330R_0402_0_1"
				(rectangle
					(start 0.635 0.889)
					(end 4.445 -0.889)
					(stroke
						(width 0.254)
						(type default)
					)
					(fill
						(type none)
					)
				)
			)
			(symbol "R_330R_0402_1_1"
				(pin passive line
					(at 0 0 0)
					(length 0.635)
					(name "~"
						(effects
							(font
								(size 1.27 1.27)
							)
						)
					)
					(number "1"
						(effects
							(font
								(size 1.27 1.27)
							)
						)
					)
				)
				(pin passive line
					(at 5.08 0 180)
					(length 0.635)
					(name "~"
						(effects
							(font
								(size 1.27 1.27)
							)
						)
					)
					(number "2"
						(effects
							(font
								(size 1.27 1.27)
							)
						)
					)
				)
			)
		)
	(symbol "antmicroResistors0402:R_3k4_0402"
			(pin_numbers
				(hide yes)
			)
			(pin_names
				(hide yes)
			)
			(exclude_from_sim no)
			(in_bom yes)
			(on_board yes)
			(property "Reference" "R"
				(at 20.32 -5.08 0)
				(effects
					(font
						(size 1.27 1.27)
						(thickness 0.15)
					)
					(justify left bottom)
				)
			)
			(property "Value" "R_3k4_0402"
				(at 20.32 -12.7 0)
				(effects
					(font
						(size 1.27 1.27)
						(thickness 0.15)
					)
					(justify left bottom)
					(hide yes)
				)
			)
			(property "Footprint" "antmicro-footprints:R_0402_1005Metric"
				(at 20.32 -15.24 0)
				(effects
					(font
						(size 1.27 1.27)
						(thickness 0.15)
					)
					(justify left bottom)
					(hide yes)
				)
			)
			(property "Datasheet" "https://www.yageo.com/upload/media/product/app/datasheet/rchip/pyu-rt_1-to-0.01_rohs_l.pdf"
				(at 20.32 -17.78 0)
				(effects
					(font
						(size 1.27 1.27)
						(thickness 0.15)
					)
					(justify left bottom)
					(hide yes)
				)
			)
			(property "Description" "SMD Chip Resistor, 3.4 kohm, ± 0.1%, 62.5 mW, 0402 [1005 Metric], Thin Film, High-Precision"
				(at 0 0 0)
				(effects
					(font
						(size 1.27 1.27)
					)
					(hide yes)
				)
			)
			(property "MPN" "RT0402BRD073K4L"
				(at 20.32 -20.32 0)
				(effects
					(font
						(size 1.27 1.27)
						(thickness 0.15)
					)
					(justify left bottom)
					(hide yes)
				)
			)
			(property "Manufacturer" "YAGEO"
				(at 20.32 -22.86 0)
				(effects
					(font
						(size 1.27 1.27)
						(thickness 0.15)
					)
					(justify left bottom)
					(hide yes)
				)
			)
			(property "License" "Apache-2.0"
				(at 20.32 -25.4 0)
				(effects
					(font
						(size 1.27 1.27)
						(thickness 0.15)
					)
					(justify left bottom)
					(hide yes)
				)
			)
			(property "Author" "Antmicro"
				(at 20.32 -27.94 0)
				(effects
					(font
						(size 1.27 1.27)
						(thickness 0.15)
					)
					(justify left bottom)
					(hide yes)
				)
			)
			(property "Val" "3k4"
				(at 20.32 -7.62 0)
				(effects
					(font
						(size 1.27 1.27)
						(thickness 0.15)
					)
					(justify left bottom)
				)
			)
			(property "Tolerance" "0.1%"
				(at 20.32 -10.16 0)
				(effects
					(font
						(size 1.27 1.27)
					)
					(justify left bottom)
					(hide yes)
				)
			)
			(property "ki_keywords" "0402, SMT, RESISTOR, PASSIVE"
				(at 0 0 0)
				(effects
					(font
						(size 1.27 1.27)
					)
					(hide yes)
				)
			)
			(symbol "R_3k4_0402_0_1"
				(rectangle
					(start 0.635 0.889)
					(end 4.445 -0.889)
					(stroke
						(width 0.254)
						(type default)
					)
					(fill
						(type none)
					)
				)
			)
			(symbol "R_3k4_0402_1_1"
				(pin passive line
					(at 0 0 0)
					(length 0.635)
					(name "~"
						(effects
							(font
								(size 1.27 1.27)
							)
						)
					)
					(number "1"
						(effects
							(font
								(size 1.27 1.27)
							)
						)
					)
				)
				(pin passive line
					(at 5.08 0 180)
					(length 0.635)
					(name "~"
						(effects
							(font
								(size 1.27 1.27)
							)
						)
					)
					(number "2"
						(effects
							(font
								(size 1.27 1.27)
							)
						)
					)
				)
			)
		)
	(symbol "antmicroResistors0402:R_47k_0402"
			(pin_numbers
				(hide yes)
			)
			(pin_names
				(hide yes)
			)
			(exclude_from_sim no)
			(in_bom yes)
			(on_board yes)
			(property "Reference" "R"
				(at 20.32 -5.08 0)
				(effects
					(font
						(size 1.27 1.27)
						(thickness 0.15)
					)
					(justify left bottom)
				)
			)
			(property "Value" "R_47k_0402"
				(at 20.32 -12.7 0)
				(effects
					(font
						(size 1.27 1.27)
						(thickness 0.15)
					)
					(justify left bottom)
					(hide yes)
				)
			)
			(property "Footprint" "antmicro-footprints:R_0402_1005Metric"
				(at 20.32 -15.24 0)
				(effects
					(font
						(size 1.27 1.27)
						(thickness 0.15)
					)
					(justify left bottom)
					(hide yes)
				)
			)
			(property "Datasheet" "https://www.bourns.com/docs/product-datasheets/cr.pdf"
				(at 20.32 -17.78 0)
				(effects
					(font
						(size 1.27 1.27)
						(thickness 0.15)
					)
					(justify left bottom)
					(hide yes)
				)
			)
			(property "Description" "SMD Chip Resistor, 47 kohm, ± 1%, 62.5 mW, 0402 [1005 Metric], Thick Film, General Purpose"
				(at 0 0 0)
				(effects
					(font
						(size 1.27 1.27)
					)
					(hide yes)
				)
			)
			(property "MPN" "CR0402-FX-4702GLF"
				(at 20.32 -20.32 0)
				(effects
					(font
						(size 1.27 1.27)
						(thickness 0.15)
					)
					(justify left bottom)
					(hide yes)
				)
			)
			(property "Manufacturer" "Bourns"
				(at 20.32 -22.86 0)
				(effects
					(font
						(size 1.27 1.27)
						(thickness 0.15)
					)
					(justify left bottom)
					(hide yes)
				)
			)
			(property "License" "Apache-2.0"
				(at 20.32 -25.4 0)
				(effects
					(font
						(size 1.27 1.27)
						(thickness 0.15)
					)
					(justify left bottom)
					(hide yes)
				)
			)
			(property "Author" "Antmicro"
				(at 20.32 -27.94 0)
				(effects
					(font
						(size 1.27 1.27)
						(thickness 0.15)
					)
					(justify left bottom)
					(hide yes)
				)
			)
			(property "Val" "47k"
				(at 20.32 -7.62 0)
				(effects
					(font
						(size 1.27 1.27)
						(thickness 0.15)
					)
					(justify left bottom)
				)
			)
			(property "Tolerance" "1%"
				(at 20.32 -10.16 0)
				(effects
					(font
						(size 1.27 1.27)
					)
					(justify left bottom)
					(hide yes)
				)
			)
			(property "ki_keywords" "0402, SMT, RESISTOR, PASSIVE"
				(at 0 0 0)
				(effects
					(font
						(size 1.27 1.27)
					)
					(hide yes)
				)
			)
			(symbol "R_47k_0402_0_1"
				(rectangle
					(start 0.635 0.889)
					(end 4.445 -0.889)
					(stroke
						(width 0.254)
						(type default)
					)
					(fill
						(type none)
					)
				)
			)
			(symbol "R_47k_0402_1_1"
				(pin passive line
					(at 0 0 0)
					(length 0.635)
					(name "~"
						(effects
							(font
								(size 1.27 1.27)
							)
						)
					)
					(number "1"
						(effects
							(font
								(size 1.27 1.27)
							)
						)
					)
				)
				(pin passive line
					(at 5.08 0 180)
					(length 0.635)
					(name "~"
						(effects
							(font
								(size 1.27 1.27)
							)
						)
					)
					(number "2"
						(effects
							(font
								(size 1.27 1.27)
							)
						)
					)
				)
			)
		)
	(symbol "antmicroResistors0402:R_49R9_0402"
			(pin_numbers
				(hide yes)
			)
			(pin_names
				(hide yes)
			)
			(exclude_from_sim no)
			(in_bom yes)
			(on_board yes)
			(property "Reference" "R"
				(at 20.32 -5.08 0)
				(effects
					(font
						(size 1.27 1.27)
						(thickness 0.15)
					)
					(justify left bottom)
				)
			)
			(property "Value" "R_49R9_0402"
				(at 20.32 -12.7 0)
				(effects
					(font
						(size 1.27 1.27)
						(thickness 0.15)
					)
					(justify left bottom)
					(hide yes)
				)
			)
			(property "Footprint" "antmicro-footprints:R_0402_1005Metric"
				(at 20.32 -15.24 0)
				(effects
					(font
						(size 1.27 1.27)
						(thickness 0.15)
					)
					(justify left bottom)
					(hide yes)
				)
			)
			(property "Datasheet" "https://www.bourns.com/docs/product-datasheets/cr.pdf"
				(at 20.32 -17.78 0)
				(effects
					(font
						(size 1.27 1.27)
						(thickness 0.15)
					)
					(justify left bottom)
					(hide yes)
				)
			)
			(property "Description" "SMD Chip Resistor, 49.9 ohm, ± 1%, 62.5 mW, 0402 [1005 Metric], Thick Film, General Purpose"
				(at 0 0 0)
				(effects
					(font
						(size 1.27 1.27)
					)
					(hide yes)
				)
			)
			(property "MPN" "CR0402-FX-49R9GLF"
				(at 20.32 -20.32 0)
				(effects
					(font
						(size 1.27 1.27)
						(thickness 0.15)
					)
					(justify left bottom)
					(hide yes)
				)
			)
			(property "Manufacturer" "Bourns"
				(at 20.32 -22.86 0)
				(effects
					(font
						(size 1.27 1.27)
						(thickness 0.15)
					)
					(justify left bottom)
					(hide yes)
				)
			)
			(property "License" "Apache-2.0"
				(at 20.32 -25.4 0)
				(effects
					(font
						(size 1.27 1.27)
						(thickness 0.15)
					)
					(justify left bottom)
					(hide yes)
				)
			)
			(property "Author" "Antmicro"
				(at 20.32 -27.94 0)
				(effects
					(font
						(size 1.27 1.27)
						(thickness 0.15)
					)
					(justify left bottom)
					(hide yes)
				)
			)
			(property "Val" "49R9"
				(at 20.32 -7.62 0)
				(effects
					(font
						(size 1.27 1.27)
						(thickness 0.15)
					)
					(justify left bottom)
				)
			)
			(property "Tolerance" "1%"
				(at 20.32 -10.16 0)
				(effects
					(font
						(size 1.27 1.27)
					)
					(justify left bottom)
					(hide yes)
				)
			)
			(property "ki_keywords" "0402, SMT, RESISTOR, PASSIVE"
				(at 0 0 0)
				(effects
					(font
						(size 1.27 1.27)
					)
					(hide yes)
				)
			)
			(symbol "R_49R9_0402_0_1"
				(rectangle
					(start 0.635 0.889)
					(end 4.445 -0.889)
					(stroke
						(width 0.254)
						(type default)
					)
					(fill
						(type none)
					)
				)
			)
			(symbol "R_49R9_0402_1_1"
				(pin passive line
					(at 0 0 0)
					(length 0.635)
					(name "~"
						(effects
							(font
								(size 1.27 1.27)
							)
						)
					)
					(number "1"
						(effects
							(font
								(size 1.27 1.27)
							)
						)
					)
				)
				(pin passive line
					(at 5.08 0 180)
					(length 0.635)
					(name "~"
						(effects
							(font
								(size 1.27 1.27)
							)
						)
					)
					(number "2"
						(effects
							(font
								(size 1.27 1.27)
							)
						)
					)
				)
			)
		)
	(symbol "antmicroResistors0402:R_49k9_0402"
			(pin_numbers
				(hide yes)
			)
			(pin_names
				(hide yes)
			)
			(exclude_from_sim no)
			(in_bom yes)
			(on_board yes)
			(property "Reference" "R"
				(at 20.32 -5.08 0)
				(effects
					(font
						(size 1.27 1.27)
						(thickness 0.15)
					)
					(justify left bottom)
				)
			)
			(property "Value" "R_49k9_0402"
				(at 20.32 -12.7 0)
				(effects
					(font
						(size 1.27 1.27)
						(thickness 0.15)
					)
					(justify left bottom)
					(hide yes)
				)
			)
			(property "Footprint" "antmicro-footprints:R_0402_1005Metric"
				(at 20.32 -15.24 0)
				(effects
					(font
						(size 1.27 1.27)
						(thickness 0.15)
					)
					(justify left bottom)
					(hide yes)
				)
			)
			(property "Datasheet" "https://www.bourns.com/docs/product-datasheets/cr.pdf"
				(at 20.32 -17.78 0)
				(effects
					(font
						(size 1.27 1.27)
						(thickness 0.15)
					)
					(justify left bottom)
					(hide yes)
				)
			)
			(property "Description" "SMD Chip Resistor, 49.9 kohm, ± 1%, 63 mW, 0402 [1005 Metric], Thick Film, General Purpose"
				(at 0 0 0)
				(effects
					(font
						(size 1.27 1.27)
					)
					(hide yes)
				)
			)
			(property "MPN" "CR0402-FX-4992GLF"
				(at 20.32 -20.32 0)
				(effects
					(font
						(size 1.27 1.27)
						(thickness 0.15)
					)
					(justify left bottom)
					(hide yes)
				)
			)
			(property "Manufacturer" "Bourns"
				(at 20.32 -22.86 0)
				(effects
					(font
						(size 1.27 1.27)
						(thickness 0.15)
					)
					(justify left bottom)
					(hide yes)
				)
			)
			(property "License" "Apache-2.0"
				(at 20.32 -25.4 0)
				(effects
					(font
						(size 1.27 1.27)
						(thickness 0.15)
					)
					(justify left bottom)
					(hide yes)
				)
			)
			(property "Author" "Antmicro"
				(at 20.32 -27.94 0)
				(effects
					(font
						(size 1.27 1.27)
						(thickness 0.15)
					)
					(justify left bottom)
					(hide yes)
				)
			)
			(property "Val" "49k9"
				(at 20.32 -7.62 0)
				(effects
					(font
						(size 1.27 1.27)
						(thickness 0.15)
					)
					(justify left bottom)
				)
			)
			(property "Tolerance" "1%"
				(at 20.32 -10.16 0)
				(effects
					(font
						(size 1.27 1.27)
					)
					(justify left bottom)
					(hide yes)
				)
			)
			(property "ki_keywords" "0402, SMT, RESISTOR, PASSIVE"
				(at 0 0 0)
				(effects
					(font
						(size 1.27 1.27)
					)
					(hide yes)
				)
			)
			(symbol "R_49k9_0402_0_1"
				(rectangle
					(start 0.635 0.889)
					(end 4.445 -0.889)
					(stroke
						(width 0.254)
						(type default)
					)
					(fill
						(type none)
					)
				)
			)
			(symbol "R_49k9_0402_1_1"
				(pin passive line
					(at 0 0 0)
					(length 0.635)
					(name "~"
						(effects
							(font
								(size 1.27 1.27)
							)
						)
					)
					(number "1"
						(effects
							(font
								(size 1.27 1.27)
							)
						)
					)
				)
				(pin passive line
					(at 5.08 0 180)
					(length 0.635)
					(name "~"
						(effects
							(font
								(size 1.27 1.27)
							)
						)
					)
					(number "2"
						(effects
							(font
								(size 1.27 1.27)
							)
						)
					)
				)
			)
		)
	(symbol "antmicroResistors0402:R_4k7_0402"
			(pin_numbers
				(hide yes)
			)
			(pin_names
				(hide yes)
			)
			(exclude_from_sim no)
			(in_bom yes)
			(on_board yes)
			(property "Reference" "R"
				(at 20.32 -5.08 0)
				(effects
					(font
						(size 1.27 1.27)
						(thickness 0.15)
					)
					(justify left bottom)
				)
			)
			(property "Value" "R_4k7_0402"
				(at 20.32 -12.7 0)
				(effects
					(font
						(size 1.27 1.27)
						(thickness 0.15)
					)
					(justify left bottom)
					(hide yes)
				)
			)
			(property "Footprint" "antmicro-footprints:R_0402_1005Metric"
				(at 20.32 -15.24 0)
				(effects
					(font
						(size 1.27 1.27)
						(thickness 0.15)
					)
					(justify left bottom)
					(hide yes)
				)
			)
			(property "Datasheet" "https://www.bourns.com/docs/product-datasheets/cr.pdf"
				(at 20.32 -17.78 0)
				(effects
					(font
						(size 1.27 1.27)
						(thickness 0.15)
					)
					(justify left bottom)
					(hide yes)
				)
			)
			(property "Description" "SMD Chip Resistor, 4.7 kohm, ± 1%, 62.5 mW, 0402 [1005 Metric], Thick Film, General Purpose"
				(at 0 0 0)
				(effects
					(font
						(size 1.27 1.27)
					)
					(hide yes)
				)
			)
			(property "MPN" "CR0402-FX-4701GLF"
				(at 20.32 -20.32 0)
				(effects
					(font
						(size 1.27 1.27)
						(thickness 0.15)
					)
					(justify left bottom)
					(hide yes)
				)
			)
			(property "Manufacturer" "Bourns"
				(at 20.32 -22.86 0)
				(effects
					(font
						(size 1.27 1.27)
						(thickness 0.15)
					)
					(justify left bottom)
					(hide yes)
				)
			)
			(property "License" "Apache-2.0"
				(at 20.32 -25.4 0)
				(effects
					(font
						(size 1.27 1.27)
						(thickness 0.15)
					)
					(justify left bottom)
					(hide yes)
				)
			)
			(property "Author" "Antmicro"
				(at 20.32 -27.94 0)
				(effects
					(font
						(size 1.27 1.27)
						(thickness 0.15)
					)
					(justify left bottom)
					(hide yes)
				)
			)
			(property "Val" "4k7"
				(at 20.32 -7.62 0)
				(effects
					(font
						(size 1.27 1.27)
						(thickness 0.15)
					)
					(justify left bottom)
				)
			)
			(property "Tolerance" "1%"
				(at 20.32 -10.16 0)
				(effects
					(font
						(size 1.27 1.27)
					)
					(justify left bottom)
					(hide yes)
				)
			)
			(property "ki_keywords" "0402, SMT, RESISTOR, PASSIVE"
				(at 0 0 0)
				(effects
					(font
						(size 1.27 1.27)
					)
					(hide yes)
				)
			)
			(symbol "R_4k7_0402_0_1"
				(rectangle
					(start 0.635 0.889)
					(end 4.445 -0.889)
					(stroke
						(width 0.254)
						(type default)
					)
					(fill
						(type none)
					)
				)
			)
			(symbol "R_4k7_0402_1_1"
				(pin passive line
					(at 0 0 0)
					(length 0.635)
					(name "~"
						(effects
							(font
								(size 1.27 1.27)
							)
						)
					)
					(number "1"
						(effects
							(font
								(size 1.27 1.27)
							)
						)
					)
				)
				(pin passive line
					(at 5.08 0 180)
					(length 0.635)
					(name "~"
						(effects
							(font
								(size 1.27 1.27)
							)
						)
					)
					(number "2"
						(effects
							(font
								(size 1.27 1.27)
							)
						)
					)
				)
			)
		)
	(symbol "antmicroResistors0402:R_4k99_0402"
			(pin_numbers
				(hide yes)
			)
			(pin_names
				(hide yes)
			)
			(exclude_from_sim no)
			(in_bom yes)
			(on_board yes)
			(property "Reference" "R"
				(at 20.32 -5.08 0)
				(effects
					(font
						(size 1.27 1.27)
						(thickness 0.15)
					)
					(justify left bottom)
				)
			)
			(property "Value" "R_4k99_0402"
				(at 20.32 -12.7 0)
				(effects
					(font
						(size 1.27 1.27)
						(thickness 0.15)
					)
					(justify left bottom)
					(hide yes)
				)
			)
			(property "Footprint" "antmicro-footprints:R_0402_1005Metric"
				(at 20.32 -15.24 0)
				(effects
					(font
						(size 1.27 1.27)
						(thickness 0.15)
					)
					(justify left bottom)
					(hide yes)
				)
			)
			(property "Datasheet" "https://www.bourns.com/docs/product-datasheets/cr.pdf"
				(at 20.32 -17.78 0)
				(effects
					(font
						(size 1.27 1.27)
						(thickness 0.15)
					)
					(justify left bottom)
					(hide yes)
				)
			)
			(property "Description" "SMD Chip Resistor, 4.99 kohm, ± 1%, 62.5 mW, 0402 [1005 Metric], Thick Film, General Purpose"
				(at 0 0 0)
				(effects
					(font
						(size 1.27 1.27)
					)
					(hide yes)
				)
			)
			(property "MPN" "CR0402-FX-4991GLF"
				(at 20.32 -20.32 0)
				(effects
					(font
						(size 1.27 1.27)
						(thickness 0.15)
					)
					(justify left bottom)
					(hide yes)
				)
			)
			(property "Manufacturer" "Bourns"
				(at 20.32 -22.86 0)
				(effects
					(font
						(size 1.27 1.27)
						(thickness 0.15)
					)
					(justify left bottom)
					(hide yes)
				)
			)
			(property "License" "Apache-2.0"
				(at 20.32 -25.4 0)
				(effects
					(font
						(size 1.27 1.27)
						(thickness 0.15)
					)
					(justify left bottom)
					(hide yes)
				)
			)
			(property "Author" "Antmicro"
				(at 20.32 -27.94 0)
				(effects
					(font
						(size 1.27 1.27)
						(thickness 0.15)
					)
					(justify left bottom)
					(hide yes)
				)
			)
			(property "Val" "4k99"
				(at 20.32 -7.62 0)
				(effects
					(font
						(size 1.27 1.27)
						(thickness 0.15)
					)
					(justify left bottom)
				)
			)
			(property "Tolerance" "1%"
				(at 20.32 -10.16 0)
				(effects
					(font
						(size 1.27 1.27)
					)
					(justify left bottom)
					(hide yes)
				)
			)
			(property "ki_keywords" "0402, SMT, RESISTOR, PASSIVE"
				(at 0 0 0)
				(effects
					(font
						(size 1.27 1.27)
					)
					(hide yes)
				)
			)
			(symbol "R_4k99_0402_0_1"
				(rectangle
					(start 0.635 0.889)
					(end 4.445 -0.889)
					(stroke
						(width 0.254)
						(type default)
					)
					(fill
						(type none)
					)
				)
			)
			(symbol "R_4k99_0402_1_1"
				(pin passive line
					(at 0 0 0)
					(length 0.635)
					(name "~"
						(effects
							(font
								(size 1.27 1.27)
							)
						)
					)
					(number "1"
						(effects
							(font
								(size 1.27 1.27)
							)
						)
					)
				)
				(pin passive line
					(at 5.08 0 180)
					(length 0.635)
					(name "~"
						(effects
							(font
								(size 1.27 1.27)
							)
						)
					)
					(number "2"
						(effects
							(font
								(size 1.27 1.27)
							)
						)
					)
				)
			)
		)
	(symbol "antmicroResistors0402:R_5k11_0402"
			(pin_numbers
				(hide yes)
			)
			(pin_names
				(hide yes)
			)
			(exclude_from_sim no)
			(in_bom yes)
			(on_board yes)
			(property "Reference" "R"
				(at 20.32 -5.08 0)
				(effects
					(font
						(size 1.27 1.27)
						(thickness 0.15)
					)
					(justify left bottom)
				)
			)
			(property "Value" "R_5k11_0402"
				(at 20.32 -12.7 0)
				(effects
					(font
						(size 1.27 1.27)
						(thickness 0.15)
					)
					(justify left bottom)
					(hide yes)
				)
			)
			(property "Footprint" "antmicro-footprints:R_0402_1005Metric"
				(at 20.32 -15.24 0)
				(effects
					(font
						(size 1.27 1.27)
						(thickness 0.15)
					)
					(justify left bottom)
					(hide yes)
				)
			)
			(property "Datasheet" "https://www.bourns.com/docs/product-datasheets/cr.pdf"
				(at 20.32 -17.78 0)
				(effects
					(font
						(size 1.27 1.27)
						(thickness 0.15)
					)
					(justify left bottom)
					(hide yes)
				)
			)
			(property "Description" "SMD Chip Resistor, 5.11 kohm, ± 1%, 63 mW, 0402 [1005 Metric], Thick Film, General Purpose"
				(at 0 0 0)
				(effects
					(font
						(size 1.27 1.27)
					)
					(hide yes)
				)
			)
			(property "MPN" "CR0402-FX-5111GLF"
				(at 20.32 -20.32 0)
				(effects
					(font
						(size 1.27 1.27)
						(thickness 0.15)
					)
					(justify left bottom)
					(hide yes)
				)
			)
			(property "Manufacturer" "Bourns"
				(at 20.32 -22.86 0)
				(effects
					(font
						(size 1.27 1.27)
						(thickness 0.15)
					)
					(justify left bottom)
					(hide yes)
				)
			)
			(property "License" "Apache-2.0"
				(at 20.32 -25.4 0)
				(effects
					(font
						(size 1.27 1.27)
						(thickness 0.15)
					)
					(justify left bottom)
					(hide yes)
				)
			)
			(property "Author" "Antmicro"
				(at 20.32 -27.94 0)
				(effects
					(font
						(size 1.27 1.27)
						(thickness 0.15)
					)
					(justify left bottom)
					(hide yes)
				)
			)
			(property "Val" "5k11"
				(at 20.32 -7.62 0)
				(effects
					(font
						(size 1.27 1.27)
						(thickness 0.15)
					)
					(justify left bottom)
				)
			)
			(property "Tolerance" "1%"
				(at 20.32 -10.16 0)
				(effects
					(font
						(size 1.27 1.27)
					)
					(justify left bottom)
					(hide yes)
				)
			)
			(property "ki_keywords" "0402, SMT, RESISTOR, PASSIVE"
				(at 0 0 0)
				(effects
					(font
						(size 1.27 1.27)
					)
					(hide yes)
				)
			)
			(symbol "R_5k11_0402_0_1"
				(rectangle
					(start 0.635 0.889)
					(end 4.445 -0.889)
					(stroke
						(width 0.254)
						(type default)
					)
					(fill
						(type none)
					)
				)
			)
			(symbol "R_5k11_0402_1_1"
				(pin passive line
					(at 0 0 0)
					(length 0.635)
					(name "~"
						(effects
							(font
								(size 1.27 1.27)
							)
						)
					)
					(number "1"
						(effects
							(font
								(size 1.27 1.27)
							)
						)
					)
				)
				(pin passive line
					(at 5.08 0 180)
					(length 0.635)
					(name "~"
						(effects
							(font
								(size 1.27 1.27)
							)
						)
					)
					(number "2"
						(effects
							(font
								(size 1.27 1.27)
							)
						)
					)
				)
			)
		)
	(symbol "antmicroResistors0402:R_60k4_0402"
			(pin_numbers
				(hide yes)
			)
			(pin_names
				(hide yes)
			)
			(exclude_from_sim no)
			(in_bom yes)
			(on_board yes)
			(property "Reference" "R"
				(at 20.32 -5.08 0)
				(effects
					(font
						(size 1.27 1.27)
						(thickness 0.15)
					)
					(justify left bottom)
				)
			)
			(property "Value" "R_60k4_0402"
				(at 20.32 -12.7 0)
				(effects
					(font
						(size 1.27 1.27)
						(thickness 0.15)
					)
					(justify left bottom)
					(hide yes)
				)
			)
			(property "Footprint" "antmicro-footprints:R_0402_1005Metric"
				(at 20.32 -15.24 0)
				(effects
					(font
						(size 1.27 1.27)
						(thickness 0.15)
					)
					(justify left bottom)
					(hide yes)
				)
			)
			(property "Datasheet" "https://www.bourns.com/docs/product-datasheets/cr.pdf"
				(at 20.32 -17.78 0)
				(effects
					(font
						(size 1.27 1.27)
						(thickness 0.15)
					)
					(justify left bottom)
					(hide yes)
				)
			)
			(property "Description" "SMD Chip Resistor"
				(at 0 0 0)
				(effects
					(font
						(size 1.27 1.27)
					)
					(hide yes)
				)
			)
			(property "MPN" "CR0402-FX-6042GLF"
				(at 20.32 -20.32 0)
				(effects
					(font
						(size 1.27 1.27)
						(thickness 0.15)
					)
					(justify left bottom)
					(hide yes)
				)
			)
			(property "Manufacturer" "Bourns"
				(at 20.32 -22.86 0)
				(effects
					(font
						(size 1.27 1.27)
						(thickness 0.15)
					)
					(justify left bottom)
					(hide yes)
				)
			)
			(property "License" "Apache-2.0"
				(at 20.32 -25.4 0)
				(effects
					(font
						(size 1.27 1.27)
						(thickness 0.15)
					)
					(justify left bottom)
					(hide yes)
				)
			)
			(property "Author" "Antmicro"
				(at 20.32 -27.94 0)
				(effects
					(font
						(size 1.27 1.27)
						(thickness 0.15)
					)
					(justify left bottom)
					(hide yes)
				)
			)
			(property "Val" "60k4"
				(at 20.32 -7.62 0)
				(effects
					(font
						(size 1.27 1.27)
						(thickness 0.15)
					)
					(justify left bottom)
				)
			)
			(property "Tolerance" "1%"
				(at 20.32 -10.16 0)
				(effects
					(font
						(size 1.27 1.27)
					)
					(justify left bottom)
					(hide yes)
				)
			)
			(property "ki_keywords" "0402, SMT, RESISTOR, PASSIVE"
				(at 0 0 0)
				(effects
					(font
						(size 1.27 1.27)
					)
					(hide yes)
				)
			)
			(symbol "R_60k4_0402_0_1"
				(rectangle
					(start 0.635 0.889)
					(end 4.445 -0.889)
					(stroke
						(width 0.254)
						(type default)
					)
					(fill
						(type none)
					)
				)
			)
			(symbol "R_60k4_0402_1_1"
				(pin passive line
					(at 0 0 0)
					(length 0.635)
					(name "~"
						(effects
							(font
								(size 1.27 1.27)
							)
						)
					)
					(number "1"
						(effects
							(font
								(size 1.27 1.27)
							)
						)
					)
				)
				(pin passive line
					(at 5.08 0 180)
					(length 0.635)
					(name "~"
						(effects
							(font
								(size 1.27 1.27)
							)
						)
					)
					(number "2"
						(effects
							(font
								(size 1.27 1.27)
							)
						)
					)
				)
			)
		)
	(symbol "antmicroResistors0402:R_64k9_0402"
			(pin_numbers
				(hide yes)
			)
			(pin_names
				(hide yes)
			)
			(exclude_from_sim no)
			(in_bom yes)
			(on_board yes)
			(property "Reference" "R"
				(at 20.32 -5.08 0)
				(effects
					(font
						(size 1.27 1.27)
						(thickness 0.15)
					)
					(justify left bottom)
				)
			)
			(property "Value" "R_64k9_0402"
				(at 20.32 -12.7 0)
				(effects
					(font
						(size 1.27 1.27)
						(thickness 0.15)
					)
					(justify left bottom)
					(hide yes)
				)
			)
			(property "Footprint" "antmicro-footprints:R_0402_1005Metric"
				(at 20.32 -15.24 0)
				(effects
					(font
						(size 1.27 1.27)
						(thickness 0.15)
					)
					(justify left bottom)
					(hide yes)
				)
			)
			(property "Datasheet" "https://www.bourns.com/docs/product-datasheets/cr.pdf"
				(at 20.32 -17.78 0)
				(effects
					(font
						(size 1.27 1.27)
						(thickness 0.15)
					)
					(justify left bottom)
					(hide yes)
				)
			)
			(property "Description" "SMD Chip Resistor"
				(at 0 0 0)
				(effects
					(font
						(size 1.27 1.27)
					)
					(hide yes)
				)
			)
			(property "MPN" "CR0402-FX-6492GLF"
				(at 20.32 -20.32 0)
				(effects
					(font
						(size 1.27 1.27)
						(thickness 0.15)
					)
					(justify left bottom)
					(hide yes)
				)
			)
			(property "Manufacturer" "Bourns"
				(at 20.32 -22.86 0)
				(effects
					(font
						(size 1.27 1.27)
						(thickness 0.15)
					)
					(justify left bottom)
					(hide yes)
				)
			)
			(property "License" "Apache-2.0"
				(at 20.32 -25.4 0)
				(effects
					(font
						(size 1.27 1.27)
						(thickness 0.15)
					)
					(justify left bottom)
					(hide yes)
				)
			)
			(property "Author" "Antmicro"
				(at 20.32 -27.94 0)
				(effects
					(font
						(size 1.27 1.27)
						(thickness 0.15)
					)
					(justify left bottom)
					(hide yes)
				)
			)
			(property "Val" "64k9"
				(at 20.32 -7.62 0)
				(effects
					(font
						(size 1.27 1.27)
						(thickness 0.15)
					)
					(justify left bottom)
				)
			)
			(property "Tolerance" "1%"
				(at 20.32 -10.16 0)
				(effects
					(font
						(size 1.27 1.27)
					)
					(justify left bottom)
					(hide yes)
				)
			)
			(property "ki_keywords" "0402, SMT, RESISTOR, PASSIVE"
				(at 0 0 0)
				(effects
					(font
						(size 1.27 1.27)
					)
					(hide yes)
				)
			)
			(symbol "R_64k9_0402_0_1"
				(rectangle
					(start 0.635 0.889)
					(end 4.445 -0.889)
					(stroke
						(width 0.254)
						(type default)
					)
					(fill
						(type none)
					)
				)
			)
			(symbol "R_64k9_0402_1_1"
				(pin passive line
					(at 0 0 0)
					(length 0.635)
					(name "~"
						(effects
							(font
								(size 1.27 1.27)
							)
						)
					)
					(number "1"
						(effects
							(font
								(size 1.27 1.27)
							)
						)
					)
				)
				(pin passive line
					(at 5.08 0 180)
					(length 0.635)
					(name "~"
						(effects
							(font
								(size 1.27 1.27)
							)
						)
					)
					(number "2"
						(effects
							(font
								(size 1.27 1.27)
							)
						)
					)
				)
			)
		)
	(symbol "antmicroResistors0402:R_6k49_0402"
			(pin_numbers
				(hide yes)
			)
			(pin_names
				(hide yes)
			)
			(exclude_from_sim no)
			(in_bom yes)
			(on_board yes)
			(property "Reference" "R"
				(at 20.32 -5.08 0)
				(effects
					(font
						(size 1.27 1.27)
						(thickness 0.15)
					)
					(justify left bottom)
				)
			)
			(property "Value" "R_6k49_0402"
				(at 20.32 -12.7 0)
				(effects
					(font
						(size 1.27 1.27)
						(thickness 0.15)
					)
					(justify left bottom)
					(hide yes)
				)
			)
			(property "Footprint" "antmicro-footprints:R_0402_1005Metric"
				(at 20.32 -15.24 0)
				(effects
					(font
						(size 1.27 1.27)
						(thickness 0.15)
					)
					(justify left bottom)
					(hide yes)
				)
			)
			(property "Datasheet" "https://www.farnell.com/datasheets/3795017.pdf"
				(at 20.32 -17.78 0)
				(effects
					(font
						(size 1.27 1.27)
						(thickness 0.15)
					)
					(justify left bottom)
					(hide yes)
				)
			)
			(property "Description" "SMD Chip Resistor, 6.49 kohm, ± 1%, 62.5 mW, 0402 [1005 Metric], Thick Film, General Purpose"
				(at 0 0 0)
				(effects
					(font
						(size 1.27 1.27)
					)
					(hide yes)
				)
			)
			(property "MPN" "RMCF0402FT6K49"
				(at 20.32 -20.32 0)
				(effects
					(font
						(size 1.27 1.27)
						(thickness 0.15)
					)
					(justify left bottom)
					(hide yes)
				)
			)
			(property "Manufacturer" "Stackpole Electronics"
				(at 20.32 -22.86 0)
				(effects
					(font
						(size 1.27 1.27)
						(thickness 0.15)
					)
					(justify left bottom)
					(hide yes)
				)
			)
			(property "License" "Apache-2.0"
				(at 20.32 -25.4 0)
				(effects
					(font
						(size 1.27 1.27)
						(thickness 0.15)
					)
					(justify left bottom)
					(hide yes)
				)
			)
			(property "Author" "Antmicro"
				(at 20.32 -27.94 0)
				(effects
					(font
						(size 1.27 1.27)
						(thickness 0.15)
					)
					(justify left bottom)
					(hide yes)
				)
			)
			(property "Val" "6k49"
				(at 20.32 -7.62 0)
				(effects
					(font
						(size 1.27 1.27)
						(thickness 0.15)
					)
					(justify left bottom)
				)
			)
			(property "Tolerance" "1%"
				(at 20.32 -10.16 0)
				(effects
					(font
						(size 1.27 1.27)
					)
					(justify left bottom)
					(hide yes)
				)
			)
			(property "ki_keywords" "0402, SMT, RESISTOR, PASSIVE"
				(at 0 0 0)
				(effects
					(font
						(size 1.27 1.27)
					)
					(hide yes)
				)
			)
			(symbol "R_6k49_0402_0_1"
				(rectangle
					(start 0.635 0.889)
					(end 4.445 -0.889)
					(stroke
						(width 0.254)
						(type default)
					)
					(fill
						(type none)
					)
				)
			)
			(symbol "R_6k49_0402_1_1"
				(pin passive line
					(at 0 0 0)
					(length 0.635)
					(name "~"
						(effects
							(font
								(size 1.27 1.27)
							)
						)
					)
					(number "1"
						(effects
							(font
								(size 1.27 1.27)
							)
						)
					)
				)
				(pin passive line
					(at 5.08 0 180)
					(length 0.635)
					(name "~"
						(effects
							(font
								(size 1.27 1.27)
							)
						)
					)
					(number "2"
						(effects
							(font
								(size 1.27 1.27)
							)
						)
					)
				)
			)
		)
	(symbol "antmicroResistors0402:R_8k16_0402"
			(pin_numbers
				(hide yes)
			)
			(pin_names
				(hide yes)
			)
			(exclude_from_sim no)
			(in_bom yes)
			(on_board yes)
			(property "Reference" "R"
				(at 20.32 -5.08 0)
				(effects
					(font
						(size 1.27 1.27)
						(thickness 0.15)
					)
					(justify left bottom)
				)
			)
			(property "Value" "R_8k16_0402"
				(at 20.32 -12.7 0)
				(effects
					(font
						(size 1.27 1.27)
						(thickness 0.15)
					)
					(justify left bottom)
					(hide yes)
				)
			)
			(property "Footprint" "antmicro-footprints:R_0402_1005Metric"
				(at 20.32 -15.24 0)
				(effects
					(font
						(size 1.27 1.27)
						(thickness 0.15)
					)
					(justify left bottom)
					(hide yes)
				)
			)
			(property "Datasheet" "https://www.yageo.com/upload/media/product/app/datasheet/rchip/pyu-rt_1-to-0.01_rohs_l.pdf"
				(at 20.32 -17.78 0)
				(effects
					(font
						(size 1.27 1.27)
						(thickness 0.15)
					)
					(justify left bottom)
					(hide yes)
				)
			)
			(property "Description" "SMD Chip Resistor, 8.16 kohm, ± 0.1%, 62.5 mW, 0402 [1005 Metric], Thin Film, High-Precision"
				(at 0 0 0)
				(effects
					(font
						(size 1.27 1.27)
					)
					(hide yes)
				)
			)
			(property "MPN" "RT0402BRE078K16L"
				(at 20.32 -20.32 0)
				(effects
					(font
						(size 1.27 1.27)
						(thickness 0.15)
					)
					(justify left bottom)
					(hide yes)
				)
			)
			(property "Manufacturer" "YAGEO"
				(at 20.32 -22.86 0)
				(effects
					(font
						(size 1.27 1.27)
						(thickness 0.15)
					)
					(justify left bottom)
					(hide yes)
				)
			)
			(property "License" "Apache-2.0"
				(at 20.32 -25.4 0)
				(effects
					(font
						(size 1.27 1.27)
						(thickness 0.15)
					)
					(justify left bottom)
					(hide yes)
				)
			)
			(property "Author" "Antmicro"
				(at 20.32 -27.94 0)
				(effects
					(font
						(size 1.27 1.27)
						(thickness 0.15)
					)
					(justify left bottom)
					(hide yes)
				)
			)
			(property "Val" "8k16"
				(at 20.32 -7.62 0)
				(effects
					(font
						(size 1.27 1.27)
						(thickness 0.15)
					)
					(justify left bottom)
				)
			)
			(property "Tolerance" "0.1%"
				(at 20.32 -10.16 0)
				(effects
					(font
						(size 1.27 1.27)
					)
					(justify left bottom)
					(hide yes)
				)
			)
			(property "ki_keywords" "0402, SMT, RESISTOR, PASSIVE"
				(at 0 0 0)
				(effects
					(font
						(size 1.27 1.27)
					)
					(hide yes)
				)
			)
			(symbol "R_8k16_0402_0_1"
				(rectangle
					(start 0.635 0.889)
					(end 4.445 -0.889)
					(stroke
						(width 0.254)
						(type default)
					)
					(fill
						(type none)
					)
				)
			)
			(symbol "R_8k16_0402_1_1"
				(pin passive line
					(at 0 0 0)
					(length 0.635)
					(name "~"
						(effects
							(font
								(size 1.27 1.27)
							)
						)
					)
					(number "1"
						(effects
							(font
								(size 1.27 1.27)
							)
						)
					)
				)
				(pin passive line
					(at 5.08 0 180)
					(length 0.635)
					(name "~"
						(effects
							(font
								(size 1.27 1.27)
							)
						)
					)
					(number "2"
						(effects
							(font
								(size 1.27 1.27)
							)
						)
					)
				)
			)
		)
	(symbol "antmicroResistors0603:R_0R_22.4A_0603"
			(pin_numbers
				(hide yes)
			)
			(pin_names
				(hide yes)
			)
			(exclude_from_sim no)
			(in_bom yes)
			(on_board yes)
			(property "Reference" "R"
				(at 15.24 -2.54 0)
				(effects
					(font
						(size 1.27 1.27)
						(thickness 0.15)
					)
					(justify left bottom)
				)
			)
			(property "Value" "R_0R_22.4A_0603"
				(at 15.24 -5.08 0)
				(effects
					(font
						(size 1.27 1.27)
						(thickness 0.15)
					)
					(justify left bottom)
				)
			)
			(property "Footprint" "antmicro-footprints:R_0603_1608Metric"
				(at 15.24 -10.16 0)
				(effects
					(font
						(size 1.27 1.27)
						(thickness 0.15)
					)
					(justify left bottom)
					(hide yes)
				)
			)
			(property "Datasheet" "https://fscdn.rohm.com/en/products/databook/datasheet/passive/resistor/chip_resistor/pmr-jpw-e.pdf"
				(at 15.24 -12.7 0)
				(effects
					(font
						(size 1.27 1.27)
						(thickness 0.15)
					)
					(justify left bottom)
					(hide yes)
				)
			)
			(property "Description" "SMD Chip Resistor"
				(at 0 0 0)
				(effects
					(font
						(size 1.27 1.27)
					)
					(hide yes)
				)
			)
			(property "MPN" "PMR03EZPJ000"
				(at 15.24 -15.24 0)
				(effects
					(font
						(size 1.27 1.27)
						(thickness 0.15)
					)
					(justify left bottom)
					(hide yes)
				)
			)
			(property "Manufacturer" "ROHM Semiconductor"
				(at 15.24 -17.78 0)
				(effects
					(font
						(size 1.27 1.27)
						(thickness 0.15)
					)
					(justify left bottom)
					(hide yes)
				)
			)
			(property "Val" "0R"
				(at 15.24 -7.62 0)
				(effects
					(font
						(size 1.27 1.27)
						(thickness 0.15)
					)
					(justify left bottom)
				)
			)
			(property "Max. Curr." "22.4A"
				(at 15.24 -20.32 0)
				(effects
					(font
						(size 1.27 1.27)
						(thickness 0.15)
					)
					(justify left bottom)
				)
			)
			(property "Author" "Antmicro"
				(at 15.24 -22.86 0)
				(effects
					(font
						(size 1.27 1.27)
						(thickness 0.15)
					)
					(justify left bottom)
					(hide yes)
				)
			)
			(property "License" "Apache-2.0"
				(at 15.24 -25.4 0)
				(effects
					(font
						(size 1.27 1.27)
						(thickness 0.15)
					)
					(justify left bottom)
					(hide yes)
				)
			)
			(property "Tolerance" "template_tolerance"
				(at 20.32 -10.16 0)
				(effects
					(font
						(size 1.27 1.27)
					)
					(justify left bottom)
					(hide yes)
				)
			)
			(property "ki_keywords" "0603, SMT, RESISTOR, PASSIVE"
				(at 0 0 0)
				(effects
					(font
						(size 1.27 1.27)
					)
					(hide yes)
				)
			)
			(symbol "R_0R_22.4A_0603_0_1"
				(rectangle
					(start 0.635 0.889)
					(end 4.445 -0.889)
					(stroke
						(width 0.254)
						(type default)
					)
					(fill
						(type none)
					)
				)
			)
			(symbol "R_0R_22.4A_0603_1_1"
				(pin passive line
					(at 0 0 0)
					(length 0.635)
					(name "~"
						(effects
							(font
								(size 1.27 1.27)
							)
						)
					)
					(number "1"
						(effects
							(font
								(size 1.27 1.27)
							)
						)
					)
				)
				(pin passive line
					(at 5.08 0 180)
					(length 0.635)
					(name "~"
						(effects
							(font
								(size 1.27 1.27)
							)
						)
					)
					(number "2"
						(effects
							(font
								(size 1.27 1.27)
							)
						)
					)
				)
			)
		)
	(symbol "antmicroResistorsmisc:R_0R002_0805"
			(pin_numbers
				(hide yes)
			)
			(pin_names
				(hide yes)
			)
			(exclude_from_sim no)
			(in_bom yes)
			(on_board yes)
			(property "Reference" "R"
				(at 20.32 -5.08 0)
				(effects
					(font
						(size 1.27 1.27)
						(thickness 0.15)
					)
					(justify left bottom)
				)
			)
			(property "Value" "R_0R002_0805"
				(at 20.32 -12.7 0)
				(effects
					(font
						(size 1.27 1.27)
						(thickness 0.15)
					)
					(justify left bottom)
					(hide yes)
				)
			)
			(property "Footprint" "antmicro-footprints:R_0805_2012Metric"
				(at 20.32 -15.24 0)
				(effects
					(font
						(size 1.27 1.27)
						(thickness 0.15)
					)
					(justify left bottom)
					(hide yes)
				)
			)
			(property "Datasheet" "https://www2.mouser.com/datasheet/2/447/PYu_PA0100_2512_51_RoHS_2-2604383.pdf"
				(at 20.32 -17.78 0)
				(effects
					(font
						(size 1.27 1.27)
						(thickness 0.15)
					)
					(justify left bottom)
					(hide yes)
				)
			)
			(property "Description" "Current Sense Resistors - SMD 2 mOhms 500 mWa 1 % 50 ppm/C AEC-Q200"
				(at 0 0 0)
				(effects
					(font
						(size 1.27 1.27)
					)
					(hide yes)
				)
			)
			(property "MPN" "PA0805FRE470R002L"
				(at 20.32 -20.32 0)
				(effects
					(font
						(size 1.27 1.27)
						(thickness 0.15)
					)
					(justify left bottom)
					(hide yes)
				)
			)
			(property "Manufacturer" "YAGEO"
				(at 20.32 -22.86 0)
				(effects
					(font
						(size 1.27 1.27)
						(thickness 0.15)
					)
					(justify left bottom)
					(hide yes)
				)
			)
			(property "License" "Apache-2.0"
				(at 20.32 -25.4 0)
				(effects
					(font
						(size 1.27 1.27)
						(thickness 0.15)
					)
					(justify left bottom)
					(hide yes)
				)
			)
			(property "Author" "Antmicro"
				(at 20.32 -27.94 0)
				(effects
					(font
						(size 1.27 1.27)
						(thickness 0.15)
					)
					(justify left bottom)
					(hide yes)
				)
			)
			(property "Val" "0R002"
				(at 20.32 -7.62 0)
				(effects
					(font
						(size 1.27 1.27)
						(thickness 0.15)
					)
					(justify left bottom)
				)
			)
			(property "Tolerance" "1%"
				(at 20.32 -10.16 0)
				(effects
					(font
						(size 1.27 1.27)
					)
					(justify left bottom)
					(hide yes)
				)
			)
			(property "ki_keywords" "0805, SMT, RESISTOR, PASSIVE"
				(at 0 0 0)
				(effects
					(font
						(size 1.27 1.27)
					)
					(hide yes)
				)
			)
			(symbol "R_0R002_0805_0_1"
				(rectangle
					(start 0.635 0.889)
					(end 4.445 -0.889)
					(stroke
						(width 0.254)
						(type default)
					)
					(fill
						(type none)
					)
				)
			)
			(symbol "R_0R002_0805_1_1"
				(pin passive line
					(at 0 0 0)
					(length 0.635)
					(name "~"
						(effects
							(font
								(size 1.27 1.27)
							)
						)
					)
					(number "1"
						(effects
							(font
								(size 1.27 1.27)
							)
						)
					)
				)
				(pin passive line
					(at 5.08 0 180)
					(length 0.635)
					(name "~"
						(effects
							(font
								(size 1.27 1.27)
							)
						)
					)
					(number "2"
						(effects
							(font
								(size 1.27 1.27)
							)
						)
					)
				)
			)
		)
	(symbol "antmicroResistorsmisc:R_0R01_1206"
			(pin_numbers
				(hide yes)
			)
			(pin_names
				(hide yes)
			)
			(exclude_from_sim no)
			(in_bom yes)
			(on_board yes)
			(property "Reference" "R"
				(at 20.32 -5.08 0)
				(effects
					(font
						(size 1.27 1.27)
						(thickness 0.15)
					)
					(justify left bottom)
				)
			)
			(property "Value" "R_0R01_1206"
				(at 20.32 -12.7 0)
				(effects
					(font
						(size 1.27 1.27)
						(thickness 0.15)
					)
					(justify left bottom)
					(hide yes)
				)
			)
			(property "Footprint" "antmicro-footprints:R_1206_3216Metric"
				(at 20.32 -15.24 0)
				(effects
					(font
						(size 1.27 1.27)
						(thickness 0.15)
					)
					(justify left bottom)
					(hide yes)
				)
			)
			(property "Datasheet" "https://www.yageo.com/upload/media/product/productsearch/datasheet/rchip/PYu-RL_Group_521_RoHS_L_2.pdf"
				(at 20.32 -17.78 0)
				(effects
					(font
						(size 1.27 1.27)
						(thickness 0.15)
					)
					(justify left bottom)
					(hide yes)
				)
			)
			(property "Description" "SMD Chip Resistor, 0.01 ohm, ± 1%, 500 mW, 1206 [3216 Metric], Thick Film, General Purpose"
				(at 0 0 0)
				(effects
					(font
						(size 1.27 1.27)
					)
					(hide yes)
				)
			)
			(property "MPN" "RL1206FR-7W0R01L"
				(at 20.32 -20.32 0)
				(effects
					(font
						(size 1.27 1.27)
						(thickness 0.15)
					)
					(justify left bottom)
					(hide yes)
				)
			)
			(property "Manufacturer" "YAGEO"
				(at 20.32 -22.86 0)
				(effects
					(font
						(size 1.27 1.27)
						(thickness 0.15)
					)
					(justify left bottom)
					(hide yes)
				)
			)
			(property "License" "Apache-2.0"
				(at 20.32 -25.4 0)
				(effects
					(font
						(size 1.27 1.27)
						(thickness 0.15)
					)
					(justify left bottom)
					(hide yes)
				)
			)
			(property "Author" "Antmicro"
				(at 20.32 -27.94 0)
				(effects
					(font
						(size 1.27 1.27)
						(thickness 0.15)
					)
					(justify left bottom)
					(hide yes)
				)
			)
			(property "Val" "0R01"
				(at 20.32 -7.62 0)
				(effects
					(font
						(size 1.27 1.27)
						(thickness 0.15)
					)
					(justify left bottom)
				)
			)
			(property "Tolerance" "1%"
				(at 20.32 -10.16 0)
				(effects
					(font
						(size 1.27 1.27)
					)
					(justify left bottom)
					(hide yes)
				)
			)
			(property "ki_keywords" "0402, SMT, RESISTOR, PASSIVE"
				(at 0 0 0)
				(effects
					(font
						(size 1.27 1.27)
					)
					(hide yes)
				)
			)
			(symbol "R_0R01_1206_0_1"
				(rectangle
					(start 0.635 0.889)
					(end 4.445 -0.889)
					(stroke
						(width 0.254)
						(type default)
					)
					(fill
						(type none)
					)
				)
			)
			(symbol "R_0R01_1206_1_1"
				(pin passive line
					(at 0 0 0)
					(length 0.635)
					(name "~"
						(effects
							(font
								(size 1.27 1.27)
							)
						)
					)
					(number "1"
						(effects
							(font
								(size 1.27 1.27)
							)
						)
					)
				)
				(pin passive line
					(at 5.08 0 180)
					(length 0.635)
					(name "~"
						(effects
							(font
								(size 1.27 1.27)
							)
						)
					)
					(number "2"
						(effects
							(font
								(size 1.27 1.27)
							)
						)
					)
				)
			)
		)
	(symbol "antmicroResistorsmisc:R_0R_0201"
			(pin_numbers
				(hide yes)
			)
			(pin_names
				(hide yes)
			)
			(exclude_from_sim no)
			(in_bom yes)
			(on_board yes)
			(property "Reference" "R"
				(at 20.32 -5.08 0)
				(effects
					(font
						(size 1.27 1.27)
						(thickness 0.15)
					)
					(justify left bottom)
				)
			)
			(property "Value" "R_0R_0201"
				(at 20.32 -12.7 0)
				(effects
					(font
						(size 1.27 1.27)
						(thickness 0.15)
					)
					(justify left bottom)
					(hide yes)
				)
			)
			(property "Footprint" "antmicro-footprints:R_0201"
				(at 20.32 -15.24 0)
				(effects
					(font
						(size 1.27 1.27)
						(thickness 0.15)
					)
					(justify left bottom)
					(hide yes)
				)
			)
			(property "Datasheet" "https://www.bourns.com/docs/product-datasheets/cr.pdf"
				(at 20.32 -17.78 0)
				(effects
					(font
						(size 1.27 1.27)
						(thickness 0.15)
					)
					(justify left bottom)
					(hide yes)
				)
			)
			(property "Description" "SMD Chip Resistor"
				(at 0 0 0)
				(effects
					(font
						(size 1.27 1.27)
					)
					(hide yes)
				)
			)
			(property "MPN" "CR0201-FX-0R00GLF"
				(at 20.32 -20.32 0)
				(effects
					(font
						(size 1.27 1.27)
						(thickness 0.15)
					)
					(justify left bottom)
					(hide yes)
				)
			)
			(property "Manufacturer" "Bourns"
				(at 20.32 -22.86 0)
				(effects
					(font
						(size 1.27 1.27)
						(thickness 0.15)
					)
					(justify left bottom)
					(hide yes)
				)
			)
			(property "License" "Apache-2.0"
				(at 20.32 -25.4 0)
				(effects
					(font
						(size 1.27 1.27)
						(thickness 0.15)
					)
					(justify left bottom)
					(hide yes)
				)
			)
			(property "Author" "Antmicro"
				(at 20.32 -27.94 0)
				(effects
					(font
						(size 1.27 1.27)
						(thickness 0.15)
					)
					(justify left bottom)
					(hide yes)
				)
			)
			(property "Val" "0R"
				(at 20.32 -7.62 0)
				(effects
					(font
						(size 1.27 1.27)
						(thickness 0.15)
					)
					(justify left bottom)
				)
			)
			(property "Tolerance" "1%"
				(at 20.32 -10.16 0)
				(effects
					(font
						(size 1.27 1.27)
					)
					(justify left bottom)
					(hide yes)
				)
			)
			(symbol "R_0R_0201_0_1"
				(rectangle
					(start 0.635 0.889)
					(end 4.445 -0.889)
					(stroke
						(width 0.254)
						(type default)
					)
					(fill
						(type none)
					)
				)
			)
			(symbol "R_0R_0201_1_1"
				(pin passive line
					(at 0 0 0)
					(length 0.635)
					(name "~"
						(effects
							(font
								(size 1.27 1.27)
							)
						)
					)
					(number "1"
						(effects
							(font
								(size 1.27 1.27)
							)
						)
					)
				)
				(pin passive line
					(at 5.08 0 180)
					(length 0.635)
					(name "~"
						(effects
							(font
								(size 1.27 1.27)
							)
						)
					)
					(number "2"
						(effects
							(font
								(size 1.27 1.27)
							)
						)
					)
				)
			)
		)
	(symbol "antmicroResonators:Resonator_114.285MHZ_ABM8"
			(pin_names
				(hide yes)
			)
			(exclude_from_sim no)
			(in_bom yes)
			(on_board yes)
			(property "Reference" "Y"
				(at 15.24 -5.08 0)
				(effects
					(font
						(size 1.27 1.27)
						(thickness 0.15)
					)
					(justify left bottom)
				)
			)
			(property "Value" "Resonator_114.285MHZ_ABM8"
				(at 15.24 -12.7 0)
				(effects
					(font
						(size 1.27 1.27)
						(thickness 0.15)
					)
					(justify left bottom)
					(hide yes)
				)
			)
			(property "Footprint" "antmicro-footprints:Resonator_SMD_Abracon_ABM8G_3.2x2.5mm"
				(at 15.24 -15.24 0)
				(effects
					(font
						(size 1.27 1.27)
						(thickness 0.15)
					)
					(justify left bottom)
					(hide yes)
				)
			)
			(property "Datasheet" "https://abracon.com/Resonators/ABM8-166.pdf"
				(at 15.24 -17.78 0)
				(effects
					(font
						(size 1.27 1.27)
						(thickness 0.15)
					)
					(justify left bottom)
					(hide yes)
				)
			)
			(property "Description" "Crystal, 114.285 MHz, SMD, 3.2mm x 2.5mm, 20 ppm, 18 pF, 20 ppm, ABM8 Series"
				(at 0 0 0)
				(effects
					(font
						(size 1.27 1.27)
					)
					(hide yes)
				)
			)
			(property "MPN" "ABM8-166-114.285MHZ-T2"
				(at 15.24 -7.62 0)
				(effects
					(font
						(size 1.27 1.27)
						(thickness 0.15)
					)
					(justify left bottom)
				)
			)
			(property "Manufacturer" "Abracon"
				(at 15.24 -20.32 0)
				(effects
					(font
						(size 1.27 1.27)
						(thickness 0.15)
					)
					(justify left bottom)
					(hide yes)
				)
			)
			(property "Author" "Antmicro"
				(at 15.24 -22.86 0)
				(effects
					(font
						(size 1.27 1.27)
						(thickness 0.15)
					)
					(justify left bottom)
					(hide yes)
				)
			)
			(property "License" "Apache-2.0"
				(at 15.24 -25.4 0)
				(effects
					(font
						(size 1.27 1.27)
						(thickness 0.15)
					)
					(justify left bottom)
					(hide yes)
				)
			)
			(property "Val" "114.285 MHz"
				(at 15.24 -10.16 0)
				(effects
					(font
						(size 1.27 1.27)
						(thickness 0.15)
					)
					(justify left bottom)
				)
			)
			(property "ki_keywords" "SMT, CERAMIC, OSCILLATOR"
				(at 0 0 0)
				(effects
					(font
						(size 1.27 1.27)
					)
					(hide yes)
				)
			)
			(symbol "Resonator_114.285MHZ_ABM8_1_1"
				(polyline
					(pts
						(xy 1.905 1.905) (xy 1.905 2.54) (xy 5.715 2.54) (xy 5.715 1.905)
					)
					(stroke
						(width 0.254)
						(type default)
					)
					(fill
						(type none)
					)
				)
				(polyline
					(pts
						(xy 1.905 -1.905) (xy 1.905 -2.54) (xy 5.715 -2.54) (xy 5.715 -1.905)
					)
					(stroke
						(width 0.254)
						(type default)
					)
					(fill
						(type none)
					)
				)
				(polyline
					(pts
						(xy 2.54 1.27) (xy 2.54 -1.27)
					)
					(stroke
						(width 0.254)
						(type default)
					)
					(fill
						(type background)
					)
				)
				(rectangle
					(start 3.175 1.905)
					(end 4.445 -1.905)
					(stroke
						(width 0.254)
						(type default)
					)
					(fill
						(type background)
					)
				)
				(polyline
					(pts
						(xy 5.08 1.27) (xy 5.08 -1.27)
					)
					(stroke
						(width 0.254)
						(type default)
					)
					(fill
						(type background)
					)
				)
				(pin passive line
					(at 0 0 0)
					(length 2.54)
					(name "~"
						(effects
							(font
								(size 1.27 1.27)
							)
						)
					)
					(number "1"
						(effects
							(font
								(size 1.27 1.27)
							)
						)
					)
				)
				(pin passive line
					(at 3.81 -5.08 90)
					(length 2.54)
					(name "SH"
						(effects
							(font
								(size 1.27 1.27)
							)
						)
					)
					(number "2"
						(effects
							(font
								(size 1.27 1.27)
							)
						)
					)
				)
				(pin passive line
					(at 3.81 -5.08 90)
					(length 2.54)
					(hide yes)
					(name "SH"
						(effects
							(font
								(size 1.27 1.27)
							)
						)
					)
					(number "4"
						(effects
							(font
								(size 1.27 1.27)
							)
						)
					)
				)
				(pin passive line
					(at 7.62 0 180)
					(length 2.54)
					(name "~"
						(effects
							(font
								(size 1.27 1.27)
							)
						)
					)
					(number "3"
						(effects
							(font
								(size 1.27 1.27)
							)
						)
					)
				)
			)
		)
	(symbol "antmicroResonators:Resonator_12MHz_ABM8G"
			(pin_names
				(hide yes)
			)
			(exclude_from_sim no)
			(in_bom yes)
			(on_board yes)
			(property "Reference" "Y"
				(at 15.24 -5.08 0)
				(effects
					(font
						(size 1.27 1.27)
						(thickness 0.15)
					)
					(justify left bottom)
				)
			)
			(property "Value" "Resonator_12MHz_ABM8G"
				(at 15.24 -12.7 0)
				(effects
					(font
						(size 1.27 1.27)
						(thickness 0.15)
					)
					(justify left bottom)
					(hide yes)
				)
			)
			(property "Footprint" "antmicro-footprints:Resonator_SMD_Abracon_ABM8G_3.2x2.5mm"
				(at 15.24 -15.24 0)
				(effects
					(font
						(size 1.27 1.27)
						(thickness 0.15)
					)
					(justify left bottom)
					(hide yes)
				)
			)
			(property "Datasheet" "https://abracon.com/Resonators/ABM8G.pdf"
				(at 15.24 -17.78 0)
				(effects
					(font
						(size 1.27 1.27)
						(thickness 0.15)
					)
					(justify left bottom)
					(hide yes)
				)
			)
			(property "Description" "Crystal, 12 MHz, SMT, 3.2mm x 2.5mm, 30 ppm, 18 pF, 20 ppm, ABM8G"
				(at 0 0 0)
				(effects
					(font
						(size 1.27 1.27)
					)
					(hide yes)
				)
			)
			(property "MPN" "ABM8G-12.000MHZ-18-D2Y-T"
				(at 15.24 -7.62 0)
				(effects
					(font
						(size 1.27 1.27)
						(thickness 0.15)
					)
					(justify left bottom)
				)
			)
			(property "Manufacturer" "Abracon"
				(at 15.24 -20.32 0)
				(effects
					(font
						(size 1.27 1.27)
						(thickness 0.15)
					)
					(justify left bottom)
					(hide yes)
				)
			)
			(property "Author" "Antmicro"
				(at 15.24 -22.86 0)
				(effects
					(font
						(size 1.27 1.27)
						(thickness 0.15)
					)
					(justify left bottom)
					(hide yes)
				)
			)
			(property "License" "Apache-2.0"
				(at 15.24 -25.4 0)
				(effects
					(font
						(size 1.27 1.27)
						(thickness 0.15)
					)
					(justify left bottom)
					(hide yes)
				)
			)
			(property "Val" "12 MHz"
				(at 15.24 -10.16 0)
				(effects
					(font
						(size 1.27 1.27)
						(thickness 0.15)
					)
					(justify left bottom)
				)
			)
			(property "ki_keywords" "SMT, CERAMIC, OSCILLATOR"
				(at 0 0 0)
				(effects
					(font
						(size 1.27 1.27)
					)
					(hide yes)
				)
			)
			(symbol "Resonator_12MHz_ABM8G_1_1"
				(polyline
					(pts
						(xy 1.905 1.905) (xy 1.905 2.54) (xy 5.715 2.54) (xy 5.715 1.905)
					)
					(stroke
						(width 0.254)
						(type default)
					)
					(fill
						(type none)
					)
				)
				(polyline
					(pts
						(xy 1.905 -1.905) (xy 1.905 -2.54) (xy 5.715 -2.54) (xy 5.715 -1.905)
					)
					(stroke
						(width 0.254)
						(type default)
					)
					(fill
						(type none)
					)
				)
				(polyline
					(pts
						(xy 2.54 1.27) (xy 2.54 -1.27)
					)
					(stroke
						(width 0.254)
						(type default)
					)
					(fill
						(type background)
					)
				)
				(rectangle
					(start 3.175 1.905)
					(end 4.445 -1.905)
					(stroke
						(width 0.254)
						(type default)
					)
					(fill
						(type background)
					)
				)
				(polyline
					(pts
						(xy 5.08 1.27) (xy 5.08 -1.27)
					)
					(stroke
						(width 0.254)
						(type default)
					)
					(fill
						(type background)
					)
				)
				(pin passive line
					(at 0 0 0)
					(length 2.54)
					(name "~"
						(effects
							(font
								(size 1.27 1.27)
							)
						)
					)
					(number "1"
						(effects
							(font
								(size 1.27 1.27)
							)
						)
					)
				)
				(pin passive line
					(at 3.81 -5.08 90)
					(length 2.54)
					(name "SH"
						(effects
							(font
								(size 1.27 1.27)
							)
						)
					)
					(number "2"
						(effects
							(font
								(size 1.27 1.27)
							)
						)
					)
				)
				(pin passive line
					(at 3.81 -5.08 90)
					(length 2.54)
					(hide yes)
					(name "SH"
						(effects
							(font
								(size 1.27 1.27)
							)
						)
					)
					(number "4"
						(effects
							(font
								(size 1.27 1.27)
							)
						)
					)
				)
				(pin passive line
					(at 7.62 0 180)
					(length 2.54)
					(name "~"
						(effects
							(font
								(size 1.27 1.27)
							)
						)
					)
					(number "3"
						(effects
							(font
								(size 1.27 1.27)
							)
						)
					)
				)
			)
		)
	(symbol "antmicroResonators:Resonator_25MHz_ABM8G"
			(pin_names
				(hide yes)
			)
			(exclude_from_sim no)
			(in_bom yes)
			(on_board yes)
			(property "Reference" "Y"
				(at 15.24 -5.08 0)
				(effects
					(font
						(size 1.27 1.27)
						(thickness 0.15)
					)
					(justify left bottom)
				)
			)
			(property "Value" "Resonator_25MHz_ABM8G"
				(at 15.24 -12.7 0)
				(effects
					(font
						(size 1.27 1.27)
						(thickness 0.15)
					)
					(justify left bottom)
					(hide yes)
				)
			)
			(property "Footprint" "antmicro-footprints:Resonator_SMD_Abracon_ABM8G_3.2x2.5mm"
				(at 15.24 -15.24 0)
				(effects
					(font
						(size 1.27 1.27)
						(thickness 0.15)
					)
					(justify left bottom)
					(hide yes)
				)
			)
			(property "Datasheet" "https://abracon.com/Resonators/ABM8G.pdf"
				(at 15.24 -17.78 0)
				(effects
					(font
						(size 1.27 1.27)
						(thickness 0.15)
					)
					(justify left bottom)
					(hide yes)
				)
			)
			(property "Description" "Crystal, 25 MHz, SMD, 3.2mm x 2.5mm, 30 ppm, 18 pF, 20 ppm, ABM8G"
				(at 0 0 0)
				(effects
					(font
						(size 1.27 1.27)
					)
					(hide yes)
				)
			)
			(property "MPN" "ABM8G-25.000MHZ-18-D2Y-T3"
				(at 15.24 -7.62 0)
				(effects
					(font
						(size 1.27 1.27)
						(thickness 0.15)
					)
					(justify left bottom)
					(hide yes)
				)
			)
			(property "Manufacturer" "Abracon"
				(at 15.24 -20.32 0)
				(effects
					(font
						(size 1.27 1.27)
						(thickness 0.15)
					)
					(justify left bottom)
					(hide yes)
				)
			)
			(property "Author" "Antmicro"
				(at 15.24 -22.86 0)
				(effects
					(font
						(size 1.27 1.27)
						(thickness 0.15)
					)
					(justify left bottom)
					(hide yes)
				)
			)
			(property "License" "Apache-2.0"
				(at 15.24 -25.4 0)
				(effects
					(font
						(size 1.27 1.27)
						(thickness 0.15)
					)
					(justify left bottom)
					(hide yes)
				)
			)
			(property "Val" "25 MHz"
				(at 15.24 -10.16 0)
				(effects
					(font
						(size 1.27 1.27)
						(thickness 0.15)
					)
					(justify left bottom)
				)
			)
			(property "ki_keywords" "SMT, CERAMIC, OSCILLATOR"
				(at 0 0 0)
				(effects
					(font
						(size 1.27 1.27)
					)
					(hide yes)
				)
			)
			(symbol "Resonator_25MHz_ABM8G_1_1"
				(polyline
					(pts
						(xy 1.905 1.905) (xy 1.905 2.54) (xy 5.715 2.54) (xy 5.715 1.905)
					)
					(stroke
						(width 0.254)
						(type default)
					)
					(fill
						(type none)
					)
				)
				(polyline
					(pts
						(xy 1.905 -1.905) (xy 1.905 -2.54) (xy 5.715 -2.54) (xy 5.715 -1.905)
					)
					(stroke
						(width 0.254)
						(type default)
					)
					(fill
						(type none)
					)
				)
				(polyline
					(pts
						(xy 2.54 1.27) (xy 2.54 -1.27)
					)
					(stroke
						(width 0.254)
						(type default)
					)
					(fill
						(type background)
					)
				)
				(rectangle
					(start 3.175 1.905)
					(end 4.445 -1.905)
					(stroke
						(width 0.254)
						(type default)
					)
					(fill
						(type background)
					)
				)
				(polyline
					(pts
						(xy 5.08 1.27) (xy 5.08 -1.27)
					)
					(stroke
						(width 0.254)
						(type default)
					)
					(fill
						(type background)
					)
				)
				(pin passive line
					(at 0 0 0)
					(length 2.54)
					(name "~"
						(effects
							(font
								(size 1.27 1.27)
							)
						)
					)
					(number "1"
						(effects
							(font
								(size 1.27 1.27)
							)
						)
					)
				)
				(pin passive line
					(at 3.81 -5.08 90)
					(length 2.54)
					(name "SH"
						(effects
							(font
								(size 1.27 1.27)
							)
						)
					)
					(number "2"
						(effects
							(font
								(size 1.27 1.27)
							)
						)
					)
				)
				(pin passive line
					(at 3.81 -5.08 90)
					(length 2.54)
					(hide yes)
					(name "SH"
						(effects
							(font
								(size 1.27 1.27)
							)
						)
					)
					(number "4"
						(effects
							(font
								(size 1.27 1.27)
							)
						)
					)
				)
				(pin passive line
					(at 7.62 0 180)
					(length 2.54)
					(name "~"
						(effects
							(font
								(size 1.27 1.27)
							)
						)
					)
					(number "3"
						(effects
							(font
								(size 1.27 1.27)
							)
						)
					)
				)
			)
		)
	(symbol "antmicroShuntsJumpers:Net-Tie_P0.127mm"
			(pin_names
				(hide yes)
			)
			(exclude_from_sim no)
			(in_bom no)
			(on_board yes)
			(property "Reference" "TP"
				(at 21.59 -5.08 0)
				(effects
					(font
						(size 1.27 1.27)
						(thickness 0.15)
					)
					(justify left bottom)
				)
			)
			(property "Value" "Net-Tie_P0.127mm"
				(at 21.59 -7.62 0)
				(effects
					(font
						(size 1.27 1.27)
						(thickness 0.15)
					)
					(justify left bottom)
				)
			)
			(property "Footprint" "antmicro-footprints:NetTie-2_SMD_Pad0.127mm"
				(at 21.59 -12.7 0)
				(effects
					(font
						(size 1.27 1.27)
						(thickness 0.15)
					)
					(justify left bottom)
					(hide yes)
				)
			)
			(property "Datasheet" ""
				(at 21.59 -15.24 0)
				(effects
					(font
						(size 1.27 1.27)
						(thickness 0.15)
					)
					(justify left bottom)
					(hide yes)
				)
			)
			(property "Description" "Net tie, 2 pins"
				(at 0 0 0)
				(effects
					(font
						(size 1.27 1.27)
					)
					(hide yes)
				)
			)
			(property "MPN" ""
				(at 21.59 -10.16 0)
				(effects
					(font
						(size 1.27 1.27)
						(thickness 0.15)
					)
					(justify left bottom)
				)
			)
			(property "Manufacturer" ""
				(at 21.59 -17.78 0)
				(effects
					(font
						(size 1.27 1.27)
						(thickness 0.15)
					)
					(justify left bottom)
					(hide yes)
				)
			)
			(property "Author" "Antmicro"
				(at 21.59 -20.32 0)
				(effects
					(font
						(size 1.27 1.27)
						(thickness 0.15)
					)
					(justify left bottom)
					(hide yes)
				)
			)
			(property "License" "Apache-2.0"
				(at 21.59 -22.86 0)
				(effects
					(font
						(size 1.27 1.27)
						(thickness 0.15)
					)
					(justify left bottom)
					(hide yes)
				)
			)
			(property "ki_fp_filters" "Net*Tie*"
				(at 0 0 0)
				(effects
					(font
						(size 1.27 1.27)
					)
					(hide yes)
				)
			)
			(symbol "Net-Tie_P0.127mm_1_1"
				(polyline
					(pts
						(xy 2.54 0) (xy 3.81 0)
					)
					(stroke
						(width 0.254)
						(type default)
					)
					(fill
						(type none)
					)
				)
				(pin passive line
					(at 0 0 0)
					(length 2.54)
					(name "1"
						(effects
							(font
								(size 1.27 1.27)
							)
						)
					)
					(number "1"
						(effects
							(font
								(size 1.27 1.27)
							)
						)
					)
				)
				(pin passive line
					(at 6.35 0 180)
					(length 2.54)
					(name "2"
						(effects
							(font
								(size 1.27 1.27)
							)
						)
					)
					(number "2"
						(effects
							(font
								(size 1.27 1.27)
							)
						)
					)
				)
			)
		)
	(symbol "antmicroSlideSwitches:CVS-03B"
			(pin_names
				(hide yes)
			)
			(exclude_from_sim no)
			(in_bom yes)
			(on_board yes)
			(property "Reference" "SW"
				(at 26.67 -2.54 0)
				(effects
					(font
						(size 1.27 1.27)
						(thickness 0.15)
					)
					(justify left bottom)
				)
			)
			(property "Value" "CVS-03B"
				(at 26.67 -5.08 0)
				(effects
					(font
						(size 1.27 1.27)
						(thickness 0.15)
					)
					(justify left bottom)
				)
			)
			(property "Footprint" "antmicro-footprints:SW_DIP_SPSTx03_Slide_Copal_CVS-03xB_W5.9mm_P1mm"
				(at 26.67 -7.62 0)
				(effects
					(font
						(size 1.27 1.27)
						(thickness 0.15)
					)
					(justify left bottom)
					(hide yes)
				)
			)
			(property "Datasheet" "https://www.mouser.com/datasheet/2/972/cvs-1827291.pdf"
				(at 26.67 -10.16 0)
				(effects
					(font
						(size 1.27 1.27)
						(thickness 0.15)
					)
					(justify left bottom)
					(hide yes)
				)
			)
			(property "Description" "Slide switch"
				(at 0 0 0)
				(effects
					(font
						(size 1.27 1.27)
					)
					(hide yes)
				)
			)
			(property "MPN" "CVS-03B"
				(at 26.67 -12.7 0)
				(effects
					(font
						(size 1.27 1.27)
						(thickness 0.15)
					)
					(justify left bottom)
					(hide yes)
				)
			)
			(property "Manufacturer" "Nidec Components"
				(at 26.67 -15.24 0)
				(effects
					(font
						(size 1.27 1.27)
						(thickness 0.15)
					)
					(justify left bottom)
					(hide yes)
				)
			)
			(property "Author" "Antmicro"
				(at 26.67 -17.78 0)
				(effects
					(font
						(size 1.27 1.27)
						(thickness 0.15)
					)
					(justify left bottom)
					(hide yes)
				)
			)
			(property "License" "Apache-2.0"
				(at 26.67 -20.32 0)
				(effects
					(font
						(size 1.27 1.27)
						(thickness 0.15)
					)
					(justify left bottom)
					(hide yes)
				)
			)
			(property "ki_keywords" "HORIZONTAL, SMT, SWITCH, MECHANICAL"
				(at 0 0 0)
				(effects
					(font
						(size 1.27 1.27)
					)
					(hide yes)
				)
			)
			(property "ki_fp_filters" "SW?DIP?x2*"
				(at 0 0 0)
				(effects
					(font
						(size 1.27 1.27)
					)
					(hide yes)
				)
			)
			(symbol "CVS-03B_1_1"
				(rectangle
					(start 2.54 2.54)
					(end 10.16 -8.89)
					(stroke
						(width 0.254)
						(type default)
					)
					(fill
						(type background)
					)
				)
				(polyline
					(pts
						(xy 3.81 0) (xy 2.54 0)
					)
					(stroke
						(width 0.254)
						(type default)
					)
					(fill
						(type none)
					)
				)
				(polyline
					(pts
						(xy 3.81 -2.54) (xy 2.54 -2.54)
					)
					(stroke
						(width 0.254)
						(type default)
					)
					(fill
						(type none)
					)
				)
				(polyline
					(pts
						(xy 3.827 -5.0976) (xy 2.557 -5.0976)
					)
					(stroke
						(width 0.254)
						(type default)
					)
					(fill
						(type none)
					)
				)
				(circle
					(center 4.318 0)
					(radius 0.508)
					(stroke
						(width 0.254)
						(type default)
					)
					(fill
						(type none)
					)
				)
				(circle
					(center 4.318 -2.54)
					(radius 0.508)
					(stroke
						(width 0.254)
						(type default)
					)
					(fill
						(type none)
					)
				)
				(circle
					(center 4.318 -5.08)
					(radius 0.508)
					(stroke
						(width 0.254)
						(type default)
					)
					(fill
						(type none)
					)
				)
				(polyline
					(pts
						(xy 4.826 0.127) (xy 8.7122 1.1684)
					)
					(stroke
						(width 0.254)
						(type default)
					)
					(fill
						(type none)
					)
				)
				(polyline
					(pts
						(xy 4.826 -2.413) (xy 8.7122 -1.3716)
					)
					(stroke
						(width 0.254)
						(type default)
					)
					(fill
						(type none)
					)
				)
				(polyline
					(pts
						(xy 4.826 -4.953) (xy 8.7122 -3.9116)
					)
					(stroke
						(width 0.254)
						(type default)
					)
					(fill
						(type none)
					)
				)
				(circle
					(center 8.382 0)
					(radius 0.508)
					(stroke
						(width 0.254)
						(type default)
					)
					(fill
						(type none)
					)
				)
				(circle
					(center 8.382 -2.54)
					(radius 0.508)
					(stroke
						(width 0.254)
						(type default)
					)
					(fill
						(type none)
					)
				)
				(circle
					(center 8.382 -5.08)
					(radius 0.508)
					(stroke
						(width 0.254)
						(type default)
					)
					(fill
						(type none)
					)
				)
				(polyline
					(pts
						(xy 10.16 0) (xy 8.89 0)
					)
					(stroke
						(width 0.254)
						(type default)
					)
					(fill
						(type none)
					)
				)
				(polyline
					(pts
						(xy 10.16 -2.54) (xy 8.89 -2.54)
					)
					(stroke
						(width 0.254)
						(type default)
					)
					(fill
						(type none)
					)
				)
				(polyline
					(pts
						(xy 10.16 -5.08) (xy 8.89 -5.08)
					)
					(stroke
						(width 0.254)
						(type default)
					)
					(fill
						(type none)
					)
				)
				(text "SH"
					(at 8.255 -7.62 0)
					(effects
						(font
							(size 1.27 1.27)
							(thickness 0.15)
						)
					)
				)
				(pin passive line
					(at 0 0 0)
					(length 2.54)
					(name "1"
						(effects
							(font
								(size 1.27 1.27)
							)
						)
					)
					(number "1"
						(effects
							(font
								(size 1.27 1.27)
							)
						)
					)
				)
				(pin passive line
					(at 0 -2.54 0)
					(length 2.54)
					(name "2"
						(effects
							(font
								(size 1.27 1.27)
							)
						)
					)
					(number "2"
						(effects
							(font
								(size 1.27 1.27)
							)
						)
					)
				)
				(pin passive line
					(at 0 -5.08 0)
					(length 2.54)
					(name "3"
						(effects
							(font
								(size 1.27 1.27)
							)
						)
					)
					(number "3"
						(effects
							(font
								(size 1.27 1.27)
							)
						)
					)
				)
				(pin passive line
					(at 12.7 0 180)
					(length 2.54)
					(name "6"
						(effects
							(font
								(size 1.27 1.27)
							)
						)
					)
					(number "6"
						(effects
							(font
								(size 1.27 1.27)
							)
						)
					)
				)
				(pin passive line
					(at 12.7 -2.54 180)
					(length 2.54)
					(name "5"
						(effects
							(font
								(size 1.27 1.27)
							)
						)
					)
					(number "5"
						(effects
							(font
								(size 1.27 1.27)
							)
						)
					)
				)
				(pin passive line
					(at 12.7 -5.08 180)
					(length 2.54)
					(name "4"
						(effects
							(font
								(size 1.27 1.27)
							)
						)
					)
					(number "4"
						(effects
							(font
								(size 1.27 1.27)
							)
						)
					)
				)
				(pin power_in line
					(at 12.7 -7.62 180)
					(length 2.54)
					(name "7"
						(effects
							(font
								(size 1.27 1.27)
							)
						)
					)
					(number "7"
						(effects
							(font
								(size 1.27 1.27)
							)
						)
					)
				)
			)
		)
	(symbol "antmicroSlideSwitches:SW_CVS-08TB"
			(pin_names
				(hide yes)
			)
			(exclude_from_sim no)
			(in_bom yes)
			(on_board yes)
			(property "Reference" "SW"
				(at 26.67 -2.54 0)
				(effects
					(font
						(size 1.27 1.27)
						(thickness 0.15)
					)
					(justify left bottom)
				)
			)
			(property "Value" "SW_CVS-08TB"
				(at 26.67 -5.08 0)
				(effects
					(font
						(size 1.27 1.27)
						(thickness 0.15)
					)
					(justify left bottom)
				)
			)
			(property "Footprint" "antmicro-footprints:SW_DIP_SPSTx08_Slide_Copal_CVS-08xB_W5.9mm_P1mm"
				(at 26.67 -7.62 0)
				(effects
					(font
						(size 1.27 1.27)
						(thickness 0.15)
					)
					(justify left bottom)
					(hide yes)
				)
			)
			(property "Datasheet" "https://www.mouser.com/datasheet/2/972/cvs-1827291.pdf"
				(at 26.67 -10.16 0)
				(effects
					(font
						(size 1.27 1.27)
						(thickness 0.15)
					)
					(justify left bottom)
					(hide yes)
				)
			)
			(property "Description" "DIP / SIP Switch, 8 Circuits, Slide, Surface Mount, SPST, 6 V, 100 mA"
				(at 0 0 0)
				(effects
					(font
						(size 1.27 1.27)
					)
					(hide yes)
				)
			)
			(property "MPN" "CVS-08TB"
				(at 26.67 -12.7 0)
				(effects
					(font
						(size 1.27 1.27)
						(thickness 0.15)
					)
					(justify left bottom)
					(hide yes)
				)
			)
			(property "Manufacturer" "Nidec Components"
				(at 26.67 -15.24 0)
				(effects
					(font
						(size 1.27 1.27)
						(thickness 0.15)
					)
					(justify left bottom)
					(hide yes)
				)
			)
			(property "Author" "Antmicro"
				(at 26.67 -17.78 0)
				(effects
					(font
						(size 1.27 1.27)
						(thickness 0.15)
					)
					(justify left bottom)
					(hide yes)
				)
			)
			(property "License" "Apache-2.0"
				(at 26.67 -20.32 0)
				(effects
					(font
						(size 1.27 1.27)
						(thickness 0.15)
					)
					(justify left bottom)
					(hide yes)
				)
			)
			(property "ki_keywords" "SWITCH, SLIDE, SPST"
				(at 0 0 0)
				(effects
					(font
						(size 1.27 1.27)
					)
					(hide yes)
				)
			)
			(property "ki_fp_filters" "SW?DIP?x2*"
				(at 0 0 0)
				(effects
					(font
						(size 1.27 1.27)
					)
					(hide yes)
				)
			)
			(symbol "SW_CVS-08TB_1_1"
				(rectangle
					(start 2.54 2.54)
					(end 10.16 -21.59)
					(stroke
						(width 0.254)
						(type default)
					)
					(fill
						(type background)
					)
				)
				(polyline
					(pts
						(xy 2.54 0) (xy 3.81 0)
					)
					(stroke
						(width 0.254)
						(type default)
					)
					(fill
						(type none)
					)
				)
				(polyline
					(pts
						(xy 2.54 -2.54) (xy 3.81 -2.54)
					)
					(stroke
						(width 0.254)
						(type default)
					)
					(fill
						(type none)
					)
				)
				(polyline
					(pts
						(xy 2.54 -5.08) (xy 3.81 -5.08)
					)
					(stroke
						(width 0.254)
						(type default)
					)
					(fill
						(type none)
					)
				)
				(polyline
					(pts
						(xy 2.54 -7.62) (xy 3.81 -7.62)
					)
					(stroke
						(width 0.254)
						(type default)
					)
					(fill
						(type none)
					)
				)
				(polyline
					(pts
						(xy 2.54 -10.16) (xy 3.81 -10.16)
					)
					(stroke
						(width 0.254)
						(type default)
					)
					(fill
						(type none)
					)
				)
				(polyline
					(pts
						(xy 2.54 -12.7) (xy 3.81 -12.7)
					)
					(stroke
						(width 0.254)
						(type default)
					)
					(fill
						(type none)
					)
				)
				(polyline
					(pts
						(xy 2.54 -17.78) (xy 3.81 -17.78)
					)
					(stroke
						(width 0.254)
						(type default)
					)
					(fill
						(type none)
					)
				)
				(polyline
					(pts
						(xy 2.5435 -15.235) (xy 3.8135 -15.235)
					)
					(stroke
						(width 0.254)
						(type default)
					)
					(fill
						(type none)
					)
				)
				(circle
					(center 4.318 0)
					(radius 0.508)
					(stroke
						(width 0.254)
						(type default)
					)
					(fill
						(type none)
					)
				)
				(circle
					(center 4.318 -2.54)
					(radius 0.508)
					(stroke
						(width 0.254)
						(type default)
					)
					(fill
						(type none)
					)
				)
				(circle
					(center 4.318 -5.08)
					(radius 0.508)
					(stroke
						(width 0.254)
						(type default)
					)
					(fill
						(type none)
					)
				)
				(circle
					(center 4.318 -7.62)
					(radius 0.508)
					(stroke
						(width 0.254)
						(type default)
					)
					(fill
						(type none)
					)
				)
				(circle
					(center 4.318 -10.16)
					(radius 0.508)
					(stroke
						(width 0.254)
						(type default)
					)
					(fill
						(type none)
					)
				)
				(circle
					(center 4.318 -12.7)
					(radius 0.508)
					(stroke
						(width 0.254)
						(type default)
					)
					(fill
						(type none)
					)
				)
				(circle
					(center 4.318 -15.24)
					(radius 0.508)
					(stroke
						(width 0.254)
						(type default)
					)
					(fill
						(type none)
					)
				)
				(circle
					(center 4.318 -17.78)
					(radius 0.508)
					(stroke
						(width 0.254)
						(type default)
					)
					(fill
						(type none)
					)
				)
				(polyline
					(pts
						(xy 4.826 0.127) (xy 8.7122 1.1684)
					)
					(stroke
						(width 0.254)
						(type default)
					)
					(fill
						(type none)
					)
				)
				(polyline
					(pts
						(xy 4.826 -2.413) (xy 8.7122 -1.3716)
					)
					(stroke
						(width 0.254)
						(type default)
					)
					(fill
						(type none)
					)
				)
				(polyline
					(pts
						(xy 4.826 -4.953) (xy 8.7122 -3.9116)
					)
					(stroke
						(width 0.254)
						(type default)
					)
					(fill
						(type none)
					)
				)
				(polyline
					(pts
						(xy 4.826 -7.493) (xy 8.7122 -6.4516)
					)
					(stroke
						(width 0.254)
						(type default)
					)
					(fill
						(type none)
					)
				)
				(polyline
					(pts
						(xy 4.826 -10.033) (xy 8.7122 -8.9916)
					)
					(stroke
						(width 0.254)
						(type default)
					)
					(fill
						(type none)
					)
				)
				(polyline
					(pts
						(xy 4.826 -12.573) (xy 8.7122 -11.5316)
					)
					(stroke
						(width 0.254)
						(type default)
					)
					(fill
						(type none)
					)
				)
				(polyline
					(pts
						(xy 4.826 -15.113) (xy 8.7122 -14.0716)
					)
					(stroke
						(width 0.254)
						(type default)
					)
					(fill
						(type none)
					)
				)
				(polyline
					(pts
						(xy 4.826 -17.653) (xy 8.7122 -16.6116)
					)
					(stroke
						(width 0.254)
						(type default)
					)
					(fill
						(type none)
					)
				)
				(circle
					(center 8.382 0)
					(radius 0.508)
					(stroke
						(width 0.254)
						(type default)
					)
					(fill
						(type none)
					)
				)
				(circle
					(center 8.382 -2.54)
					(radius 0.508)
					(stroke
						(width 0.254)
						(type default)
					)
					(fill
						(type none)
					)
				)
				(circle
					(center 8.382 -5.08)
					(radius 0.508)
					(stroke
						(width 0.254)
						(type default)
					)
					(fill
						(type none)
					)
				)
				(circle
					(center 8.382 -7.62)
					(radius 0.508)
					(stroke
						(width 0.254)
						(type default)
					)
					(fill
						(type none)
					)
				)
				(circle
					(center 8.382 -10.16)
					(radius 0.508)
					(stroke
						(width 0.254)
						(type default)
					)
					(fill
						(type none)
					)
				)
				(circle
					(center 8.382 -12.7)
					(radius 0.508)
					(stroke
						(width 0.254)
						(type default)
					)
					(fill
						(type none)
					)
				)
				(circle
					(center 8.382 -15.24)
					(radius 0.508)
					(stroke
						(width 0.254)
						(type default)
					)
					(fill
						(type none)
					)
				)
				(circle
					(center 8.382 -17.78)
					(radius 0.508)
					(stroke
						(width 0.254)
						(type default)
					)
					(fill
						(type none)
					)
				)
				(polyline
					(pts
						(xy 8.89 0) (xy 10.16 0)
					)
					(stroke
						(width 0.254)
						(type default)
					)
					(fill
						(type none)
					)
				)
				(polyline
					(pts
						(xy 8.89 -2.54) (xy 10.16 -2.54)
					)
					(stroke
						(width 0.254)
						(type default)
					)
					(fill
						(type none)
					)
				)
				(polyline
					(pts
						(xy 8.89 -5.08) (xy 10.16 -5.08)
					)
					(stroke
						(width 0.254)
						(type default)
					)
					(fill
						(type none)
					)
				)
				(polyline
					(pts
						(xy 8.89 -7.62) (xy 10.16 -7.62)
					)
					(stroke
						(width 0.254)
						(type default)
					)
					(fill
						(type none)
					)
				)
				(polyline
					(pts
						(xy 8.89 -10.16) (xy 10.16 -10.16)
					)
					(stroke
						(width 0.254)
						(type default)
					)
					(fill
						(type none)
					)
				)
				(polyline
					(pts
						(xy 8.89 -12.7) (xy 10.16 -12.7)
					)
					(stroke
						(width 0.254)
						(type default)
					)
					(fill
						(type none)
					)
				)
				(polyline
					(pts
						(xy 8.89 -17.78) (xy 10.16 -17.78)
					)
					(stroke
						(width 0.254)
						(type default)
					)
					(fill
						(type none)
					)
				)
				(polyline
					(pts
						(xy 8.8935 -15.235) (xy 10.1635 -15.235)
					)
					(stroke
						(width 0.254)
						(type default)
					)
					(fill
						(type none)
					)
				)
				(text "SH"
					(at 6.985 -20.955 0)
					(effects
						(font
							(size 1.27 1.27)
							(thickness 0.15)
						)
						(justify left bottom)
					)
				)
				(pin passive line
					(at 0 0 0)
					(length 2.54)
					(name "1"
						(effects
							(font
								(size 1.27 1.27)
							)
						)
					)
					(number "1"
						(effects
							(font
								(size 1.27 1.27)
							)
						)
					)
				)
				(pin passive line
					(at 0 -2.54 0)
					(length 2.54)
					(name "2"
						(effects
							(font
								(size 1.27 1.27)
							)
						)
					)
					(number "2"
						(effects
							(font
								(size 1.27 1.27)
							)
						)
					)
				)
				(pin passive line
					(at 0 -5.08 0)
					(length 2.54)
					(name "3"
						(effects
							(font
								(size 1.27 1.27)
							)
						)
					)
					(number "3"
						(effects
							(font
								(size 1.27 1.27)
							)
						)
					)
				)
				(pin passive line
					(at 0 -7.62 0)
					(length 2.54)
					(name "4"
						(effects
							(font
								(size 1.27 1.27)
							)
						)
					)
					(number "4"
						(effects
							(font
								(size 1.27 1.27)
							)
						)
					)
				)
				(pin passive line
					(at 0 -10.16 0)
					(length 2.54)
					(name "5"
						(effects
							(font
								(size 1.27 1.27)
							)
						)
					)
					(number "5"
						(effects
							(font
								(size 1.27 1.27)
							)
						)
					)
				)
				(pin passive line
					(at 0 -12.7 0)
					(length 2.54)
					(name "6"
						(effects
							(font
								(size 1.27 1.27)
							)
						)
					)
					(number "6"
						(effects
							(font
								(size 1.27 1.27)
							)
						)
					)
				)
				(pin passive line
					(at 0 -15.24 0)
					(length 2.54)
					(name "7"
						(effects
							(font
								(size 1.27 1.27)
							)
						)
					)
					(number "7"
						(effects
							(font
								(size 1.27 1.27)
							)
						)
					)
				)
				(pin passive line
					(at 0 -17.78 0)
					(length 2.54)
					(name "8"
						(effects
							(font
								(size 1.27 1.27)
							)
						)
					)
					(number "8"
						(effects
							(font
								(size 1.27 1.27)
							)
						)
					)
				)
				(pin passive line
					(at 12.7 0 180)
					(length 2.54)
					(name "16"
						(effects
							(font
								(size 1.27 1.27)
							)
						)
					)
					(number "16"
						(effects
							(font
								(size 1.27 1.27)
							)
						)
					)
				)
				(pin passive line
					(at 12.7 -2.54 180)
					(length 2.54)
					(name "15"
						(effects
							(font
								(size 1.27 1.27)
							)
						)
					)
					(number "15"
						(effects
							(font
								(size 1.27 1.27)
							)
						)
					)
				)
				(pin passive line
					(at 12.7 -5.08 180)
					(length 2.54)
					(name "14"
						(effects
							(font
								(size 1.27 1.27)
							)
						)
					)
					(number "14"
						(effects
							(font
								(size 1.27 1.27)
							)
						)
					)
				)
				(pin passive line
					(at 12.7 -7.62 180)
					(length 2.54)
					(name "13"
						(effects
							(font
								(size 1.27 1.27)
							)
						)
					)
					(number "13"
						(effects
							(font
								(size 1.27 1.27)
							)
						)
					)
				)
				(pin passive line
					(at 12.7 -10.16 180)
					(length 2.54)
					(name "12"
						(effects
							(font
								(size 1.27 1.27)
							)
						)
					)
					(number "12"
						(effects
							(font
								(size 1.27 1.27)
							)
						)
					)
				)
				(pin passive line
					(at 12.7 -12.7 180)
					(length 2.54)
					(name "11"
						(effects
							(font
								(size 1.27 1.27)
							)
						)
					)
					(number "11"
						(effects
							(font
								(size 1.27 1.27)
							)
						)
					)
				)
				(pin passive line
					(at 12.7 -15.24 180)
					(length 2.54)
					(name "10"
						(effects
							(font
								(size 1.27 1.27)
							)
						)
					)
					(number "10"
						(effects
							(font
								(size 1.27 1.27)
							)
						)
					)
				)
				(pin passive line
					(at 12.7 -17.78 180)
					(length 2.54)
					(name "9"
						(effects
							(font
								(size 1.27 1.27)
							)
						)
					)
					(number "9"
						(effects
							(font
								(size 1.27 1.27)
							)
						)
					)
				)
				(pin power_in line
					(at 12.7 -20.32 180)
					(length 2.54)
					(name "17"
						(effects
							(font
								(size 1.27 1.27)
							)
						)
					)
					(number "17"
						(effects
							(font
								(size 1.27 1.27)
							)
						)
					)
				)
			)
		)
	(symbol "antmicroTVSDiodes:PESD5V0X1UB"
			(pin_numbers
				(hide yes)
			)
			(pin_names
				(hide yes)
			)
			(exclude_from_sim no)
			(in_bom yes)
			(on_board yes)
			(property "Reference" "D"
				(at 15.24 0 0)
				(effects
					(font
						(size 1.27 1.27)
						(thickness 0.15)
					)
					(justify left bottom)
				)
			)
			(property "Value" "PESD5V0X1UB"
				(at 15.24 -5.08 0)
				(effects
					(font
						(size 1.27 1.27)
						(thickness 0.15)
					)
					(justify left bottom)
					(hide yes)
				)
			)
			(property "Footprint" "antmicro-footprints:SOD-523"
				(at 15.24 -7.62 0)
				(effects
					(font
						(size 1.27 1.27)
						(thickness 0.15)
					)
					(justify left bottom)
					(hide yes)
				)
			)
			(property "Datasheet" "https://assets.nexperia.com/documents/data-sheet/PESD5V0X1UB.pdf"
				(at 15.24 -10.16 0)
				(effects
					(font
						(size 1.27 1.27)
						(thickness 0.15)
					)
					(justify left bottom)
					(hide yes)
				)
			)
			(property "Description" "Unidirectional TVS, 8 kV,  SOD-523, 5.5 V, 0.95 pF"
				(at 0 0 0)
				(effects
					(font
						(size 1.27 1.27)
					)
					(hide yes)
				)
			)
			(property "MPN" "PESD5V0X1UB,135"
				(at 15.24 -2.54 0)
				(effects
					(font
						(size 1.27 1.27)
						(thickness 0.15)
					)
					(justify left bottom)
				)
			)
			(property "Manufacturer" "Nexperia"
				(at 15.24 -12.7 0)
				(effects
					(font
						(size 1.27 1.27)
						(thickness 0.15)
					)
					(justify left bottom)
					(hide yes)
				)
			)
			(property "Author" "Antmicro"
				(at 15.24 -15.24 0)
				(effects
					(font
						(size 1.27 1.27)
						(thickness 0.15)
					)
					(justify left bottom)
					(hide yes)
				)
			)
			(property "License" "Apache-2.0"
				(at 15.24 -17.78 0)
				(effects
					(font
						(size 1.27 1.27)
						(thickness 0.15)
					)
					(justify left bottom)
					(hide yes)
				)
			)
			(property "ki_keywords" "DIODE, SEMICONDUCTOR, TVS, ESD"
				(at 0 0 0)
				(effects
					(font
						(size 1.27 1.27)
					)
					(hide yes)
				)
			)
			(symbol "PESD5V0X1UB_0_1"
				(polyline
					(pts
						(xy 1.905 0) (xy 0.635 0)
					)
					(stroke
						(width 0)
						(type default)
					)
					(fill
						(type none)
					)
				)
				(polyline
					(pts
						(xy 4.445 0) (xy 3.175 0)
					)
					(stroke
						(width 0)
						(type default)
					)
					(fill
						(type none)
					)
				)
			)
			(symbol "PESD5V0X1UB_1_1"
				(polyline
					(pts
						(xy 1.778 1.016) (xy 1.397 1.016)
					)
					(stroke
						(width 0.254)
						(type default)
					)
					(fill
						(type none)
					)
				)
				(polyline
					(pts
						(xy 1.778 1.016) (xy 1.778 -1.016)
					)
					(stroke
						(width 0.254)
						(type default)
					)
					(fill
						(type none)
					)
				)
				(polyline
					(pts
						(xy 2.159 -1.016) (xy 1.778 -1.016)
					)
					(stroke
						(width 0.254)
						(type default)
					)
					(fill
						(type none)
					)
				)
				(polyline
					(pts
						(xy 3.302 1.016) (xy 3.302 -1.016) (xy 1.778 0) (xy 3.302 1.016)
					)
					(stroke
						(width 0.254)
						(type default)
					)
					(fill
						(type outline)
					)
				)
				(pin passive line
					(at 0 0 0)
					(length 0.635)
					(name "C"
						(effects
							(font
								(size 1.27 1.27)
							)
						)
					)
					(number "1"
						(effects
							(font
								(size 1.27 1.27)
							)
						)
					)
				)
				(pin passive line
					(at 5.08 0 180)
					(length 0.635)
					(name "A"
						(effects
							(font
								(size 1.27 1.27)
							)
						)
					)
					(number "2"
						(effects
							(font
								(size 1.27 1.27)
							)
						)
					)
				)
			)
		)
	(symbol "antmicroTVSDiodes:TPD4E05U06QDQARQ1"
			(exclude_from_sim no)
			(in_bom yes)
			(on_board yes)
			(property "Reference" "U"
				(at 24.13 0 0)
				(effects
					(font
						(size 1.27 1.27)
						(thickness 0.15)
					)
					(justify left bottom)
				)
			)
			(property "Value" "TPD4E05U06QDQARQ1"
				(at 24.13 -10.16 0)
				(effects
					(font
						(size 1.27 1.27)
						(thickness 0.15)
					)
					(justify left bottom)
					(hide yes)
				)
			)
			(property "Footprint" "antmicro-footprints:USON-10_2.5x1mm_P0.5mm"
				(at 24.13 -5.08 0)
				(effects
					(font
						(size 1.27 1.27)
						(thickness 0.15)
					)
					(justify left bottom)
					(hide yes)
				)
			)
			(property "Datasheet" "https://www.ti.com/lit/ds/symlink/tpd4e05u06-q1.pdf?HQS=dis-mous-null-mousermode-dsf-pf-null-wwe&ts=1663591265741&ref_url=https%253A%252F%252Fwww.mouser.com%252F"
				(at 24.13 -7.62 0)
				(effects
					(font
						(size 1.27 1.27)
						(thickness 0.15)
					)
					(justify left bottom)
					(hide yes)
				)
			)
			(property "Description" "TVS diode array, 12 kV, USON-10, 5.5 V, 0.5 pF"
				(at 0 0 0)
				(effects
					(font
						(size 1.27 1.27)
					)
					(hide yes)
				)
			)
			(property "MPN" "TPD4E05U06QDQARQ1"
				(at 24.13 -2.54 0)
				(effects
					(font
						(size 1.27 1.27)
						(thickness 0.15)
					)
					(justify left bottom)
				)
			)
			(property "Manufacturer" "Texas Instruments"
				(at 24.13 -12.7 0)
				(effects
					(font
						(size 1.27 1.27)
						(thickness 0.15)
					)
					(justify left bottom)
					(hide yes)
				)
			)
			(property "Author" "Antmicro"
				(at 24.13 -15.24 0)
				(effects
					(font
						(size 1.27 1.27)
						(thickness 0.15)
					)
					(justify left bottom)
					(hide yes)
				)
			)
			(property "License" "Apache-2.0"
				(at 24.13 -17.78 0)
				(effects
					(font
						(size 1.27 1.27)
						(thickness 0.15)
					)
					(justify left bottom)
					(hide yes)
				)
			)
			(property "ki_keywords" "SMT, DIODE, SEMICONDUCTOR, TVS, ESD"
				(at 0 0 0)
				(effects
					(font
						(size 1.27 1.27)
					)
					(hide yes)
				)
			)
			(symbol "TPD4E05U06QDQARQ1_1_1"
				(rectangle
					(start 2.54 2.54)
					(end 8.89 -11.43)
					(stroke
						(width 0.254)
						(type default)
					)
					(fill
						(type background)
					)
				)
				(polyline
					(pts
						(xy 2.54 0) (xy 7.62 0)
					)
					(stroke
						(width 0.254)
						(type default)
					)
					(fill
						(type background)
					)
				)
				(polyline
					(pts
						(xy 2.54 -2.54) (xy 7.62 -2.54)
					)
					(stroke
						(width 0.254)
						(type default)
					)
					(fill
						(type background)
					)
				)
				(polyline
					(pts
						(xy 2.54 -5.08) (xy 7.62 -5.08)
					)
					(stroke
						(width 0.254)
						(type default)
					)
					(fill
						(type background)
					)
				)
				(polyline
					(pts
						(xy 2.54 -7.62) (xy 7.62 -7.62)
					)
					(stroke
						(width 0.254)
						(type default)
					)
					(fill
						(type background)
					)
				)
				(polyline
					(pts
						(xy 4.826 -0.635) (xy 5.08 -0.381) (xy 5.08 0.381) (xy 5.334 0.635)
					)
					(stroke
						(width 0.254)
						(type default)
					)
					(fill
						(type background)
					)
				)
				(polyline
					(pts
						(xy 4.826 -3.175) (xy 5.08 -2.921) (xy 5.08 -2.159) (xy 5.334 -1.905)
					)
					(stroke
						(width 0.254)
						(type default)
					)
					(fill
						(type background)
					)
				)
				(polyline
					(pts
						(xy 4.826 -5.715) (xy 5.08 -5.461) (xy 5.08 -4.699) (xy 5.334 -4.445)
					)
					(stroke
						(width 0.254)
						(type default)
					)
					(fill
						(type background)
					)
				)
				(polyline
					(pts
						(xy 4.826 -8.255) (xy 5.08 -8.001) (xy 5.08 -7.239) (xy 5.334 -6.985)
					)
					(stroke
						(width 0.254)
						(type default)
					)
					(fill
						(type background)
					)
				)
				(polyline
					(pts
						(xy 5.08 0) (xy 3.81 -0.635) (xy 3.81 0.635) (xy 5.08 0)
					)
					(stroke
						(width 0.254)
						(type default)
					)
					(fill
						(type background)
					)
				)
				(polyline
					(pts
						(xy 5.08 0) (xy 6.35 -0.635) (xy 6.35 0.635) (xy 5.08 0)
					)
					(stroke
						(width 0.254)
						(type default)
					)
					(fill
						(type background)
					)
				)
				(polyline
					(pts
						(xy 5.08 -2.54) (xy 3.81 -3.175) (xy 3.81 -1.905) (xy 5.08 -2.54)
					)
					(stroke
						(width 0.254)
						(type default)
					)
					(fill
						(type background)
					)
				)
				(polyline
					(pts
						(xy 5.08 -2.54) (xy 6.35 -3.175) (xy 6.35 -1.905) (xy 5.08 -2.54)
					)
					(stroke
						(width 0.254)
						(type default)
					)
					(fill
						(type background)
					)
				)
				(polyline
					(pts
						(xy 5.08 -5.08) (xy 3.81 -5.715) (xy 3.81 -4.445) (xy 5.08 -5.08)
					)
					(stroke
						(width 0.254)
						(type default)
					)
					(fill
						(type background)
					)
				)
				(polyline
					(pts
						(xy 5.08 -5.08) (xy 6.35 -4.445) (xy 6.35 -5.715) (xy 5.08 -5.08)
					)
					(stroke
						(width 0.254)
						(type default)
					)
					(fill
						(type background)
					)
				)
				(polyline
					(pts
						(xy 5.08 -7.62) (xy 3.81 -8.255) (xy 3.81 -6.985) (xy 5.08 -7.62)
					)
					(stroke
						(width 0.254)
						(type default)
					)
					(fill
						(type background)
					)
				)
				(polyline
					(pts
						(xy 6.35 -6.985) (xy 6.35 -8.255) (xy 5.08 -7.62) (xy 6.35 -6.985)
					)
					(stroke
						(width 0.254)
						(type default)
					)
					(fill
						(type background)
					)
				)
				(polyline
					(pts
						(xy 7.62 0) (xy 7.62 -10.16)
					)
					(stroke
						(width 0.254)
						(type default)
					)
					(fill
						(type background)
					)
				)
				(circle
					(center 7.62 -2.54)
					(radius 0.254)
					(stroke
						(width 0.254)
						(type default)
					)
					(fill
						(type background)
					)
				)
				(circle
					(center 7.62 -5.08)
					(radius 0.254)
					(stroke
						(width 0.254)
						(type default)
					)
					(fill
						(type background)
					)
				)
				(circle
					(center 7.62 -5.08)
					(radius 0.254)
					(stroke
						(width 0.254)
						(type default)
					)
					(fill
						(type background)
					)
				)
				(circle
					(center 7.62 -7.62)
					(radius 0.254)
					(stroke
						(width 0.254)
						(type default)
					)
					(fill
						(type background)
					)
				)
				(polyline
					(pts
						(xy 7.62 -10.16) (xy 2.54 -10.16)
					)
					(stroke
						(width 0.254)
						(type default)
					)
					(fill
						(type background)
					)
				)
				(pin passive line
					(at 0 0 0)
					(length 2.54)
					(name "~"
						(effects
							(font
								(size 1.27 1.27)
							)
						)
					)
					(number "1"
						(effects
							(font
								(size 1.27 1.27)
							)
						)
					)
				)
				(pin passive line
					(at 0 0 0)
					(length 2.54)
					(hide yes)
					(name "~"
						(effects
							(font
								(size 1.27 1.27)
							)
						)
					)
					(number "10"
						(effects
							(font
								(size 1.27 1.27)
							)
						)
					)
				)
				(pin passive line
					(at 0 -2.54 0)
					(length 2.54)
					(name "~"
						(effects
							(font
								(size 1.27 1.27)
							)
						)
					)
					(number "2"
						(effects
							(font
								(size 1.27 1.27)
							)
						)
					)
				)
				(pin passive line
					(at 0 -2.54 0)
					(length 2.54)
					(hide yes)
					(name "~"
						(effects
							(font
								(size 1.27 1.27)
							)
						)
					)
					(number "9"
						(effects
							(font
								(size 1.27 1.27)
							)
						)
					)
				)
				(pin passive line
					(at 0 -5.08 0)
					(length 2.54)
					(name "~"
						(effects
							(font
								(size 1.27 1.27)
							)
						)
					)
					(number "4"
						(effects
							(font
								(size 1.27 1.27)
							)
						)
					)
				)
				(pin passive line
					(at 0 -5.08 0)
					(length 2.54)
					(hide yes)
					(name "~"
						(effects
							(font
								(size 1.27 1.27)
							)
						)
					)
					(number "7"
						(effects
							(font
								(size 1.27 1.27)
							)
						)
					)
				)
				(pin passive line
					(at 0 -7.62 0)
					(length 2.54)
					(name "~"
						(effects
							(font
								(size 1.27 1.27)
							)
						)
					)
					(number "5"
						(effects
							(font
								(size 1.27 1.27)
							)
						)
					)
				)
				(pin passive line
					(at 0 -7.62 0)
					(length 2.54)
					(hide yes)
					(name "~"
						(effects
							(font
								(size 1.27 1.27)
							)
						)
					)
					(number "6"
						(effects
							(font
								(size 1.27 1.27)
							)
						)
					)
				)
				(pin power_in line
					(at 0 -10.16 0)
					(length 2.54)
					(name "~"
						(effects
							(font
								(size 1.27 1.27)
							)
						)
					)
					(number "3"
						(effects
							(font
								(size 1.27 1.27)
							)
						)
					)
				)
				(pin passive line
					(at 0 -10.16 0)
					(length 2.54)
					(hide yes)
					(name "~"
						(effects
							(font
								(size 1.27 1.27)
							)
						)
					)
					(number "8"
						(effects
							(font
								(size 1.27 1.27)
							)
						)
					)
				)
			)
		)
	(symbol "antmicroTemperatureSensorsAnalogandDigitalOutput:TMP451AIDQFR"
			(exclude_from_sim no)
			(in_bom yes)
			(on_board yes)
			(property "Reference" "U"
				(at 27.94 0 0)
				(effects
					(font
						(size 1.27 1.27)
						(thickness 0.15)
					)
					(justify left bottom)
				)
			)
			(property "Value" "TMP451AIDQFR"
				(at 27.94 -7.62 0)
				(effects
					(font
						(size 1.27 1.27)
						(thickness 0.15)
					)
					(justify left bottom)
					(hide yes)
				)
			)
			(property "Footprint" "antmicro-footprints:WSON-8_2x2mm"
				(at 27.94 -10.16 0)
				(effects
					(font
						(size 1.27 1.27)
						(thickness 0.15)
					)
					(justify left bottom)
					(hide yes)
				)
			)
			(property "Datasheet" "https://www.ti.com/lit/ds/symlink/tmp451.pdf?ts=1727409102766"
				(at 27.94 -12.7 0)
				(effects
					(font
						(size 1.27 1.27)
						(thickness 0.15)
					)
					(justify left bottom)
					(hide yes)
				)
			)
			(property "Description" "Board Mount Temperature Sensors AC +/-1degC Remote & Local Temp sensor"
				(at 0 0 0)
				(effects
					(font
						(size 1.27 1.27)
					)
					(hide yes)
				)
			)
			(property "MPN" "TMP451AIDQFR"
				(at 27.94 -2.54 0)
				(effects
					(font
						(size 1.27 1.27)
						(thickness 0.15)
					)
					(justify left bottom)
				)
			)
			(property "Manufacturer" "Texas Instruments"
				(at 27.94 -5.08 0)
				(effects
					(font
						(size 1.27 1.27)
						(thickness 0.15)
					)
					(justify left bottom)
					(hide yes)
				)
			)
			(property "Author" "Antmicro"
				(at 27.94 -15.24 0)
				(effects
					(font
						(size 1.27 1.27)
						(thickness 0.15)
					)
					(justify left bottom)
					(hide yes)
				)
			)
			(property "License" "Apache-2.0"
				(at 27.94 -17.78 0)
				(effects
					(font
						(size 1.27 1.27)
						(thickness 0.15)
					)
					(justify left bottom)
					(hide yes)
				)
			)
			(property "ki_keywords" "DIGITAL, SENSOR, I2C"
				(at 0 0 0)
				(effects
					(font
						(size 1.27 1.27)
					)
					(hide yes)
				)
			)
			(symbol "TMP451AIDQFR_1_1"
				(rectangle
					(start 2.54 2.54)
					(end 15.24 -15.24)
					(stroke
						(width 0.254)
						(type default)
					)
					(fill
						(type background)
					)
				)
				(pin power_in line
					(at 0 0 0)
					(length 2.54)
					(name "V+"
						(effects
							(font
								(size 1.27 1.27)
							)
						)
					)
					(number "1"
						(effects
							(font
								(size 1.27 1.27)
							)
						)
					)
				)
				(pin bidirectional line
					(at 0 -5.08 0)
					(length 2.54)
					(name "SDA"
						(effects
							(font
								(size 1.27 1.27)
							)
						)
					)
					(number "7"
						(effects
							(font
								(size 1.27 1.27)
							)
						)
					)
				)
				(pin input line
					(at 0 -7.62 0)
					(length 2.54)
					(name "SCL"
						(effects
							(font
								(size 1.27 1.27)
							)
						)
					)
					(number "8"
						(effects
							(font
								(size 1.27 1.27)
							)
						)
					)
				)
				(pin output line
					(at 0 -10.16 0)
					(length 2.54)
					(name "~{ALERT}"
						(effects
							(font
								(size 1.27 1.27)
							)
						)
					)
					(number "6"
						(effects
							(font
								(size 1.27 1.27)
							)
						)
					)
					(alternate "~{THERM2}" output line)
				)
				(pin output line
					(at 0 -12.7 0)
					(length 2.54)
					(name "~{THERM}"
						(effects
							(font
								(size 1.27 1.27)
							)
						)
					)
					(number "4"
						(effects
							(font
								(size 1.27 1.27)
							)
						)
					)
				)
				(pin input line
					(at 17.78 -2.54 180)
					(length 2.54)
					(name "D+"
						(effects
							(font
								(size 1.27 1.27)
							)
						)
					)
					(number "2"
						(effects
							(font
								(size 1.27 1.27)
							)
						)
					)
				)
				(pin input line
					(at 17.78 -5.08 180)
					(length 2.54)
					(name "D-"
						(effects
							(font
								(size 1.27 1.27)
							)
						)
					)
					(number "3"
						(effects
							(font
								(size 1.27 1.27)
							)
						)
					)
				)
				(pin power_in line
					(at 17.78 -12.7 180)
					(length 2.54)
					(name "GND"
						(effects
							(font
								(size 1.27 1.27)
							)
						)
					)
					(number "5"
						(effects
							(font
								(size 1.27 1.27)
							)
						)
					)
				)
			)
		)
	(symbol "antmicroTestPoints:TP_0.75mm_SMD"
			(pin_names
				(hide yes)
			)
			(exclude_from_sim no)
			(in_bom no)
			(on_board yes)
			(property "Reference" "TP"
				(at 10.16 -1.27 0)
				(effects
					(font
						(size 1.27 1.27)
						(thickness 0.15)
					)
					(justify left bottom)
				)
			)
			(property "Value" "TP_0.75mm_SMD"
				(at 10.16 -3.81 0)
				(effects
					(font
						(size 1.27 1.27)
						(thickness 0.15)
					)
					(justify left bottom)
					(hide yes)
				)
			)
			(property "Footprint" "antmicro-footprints:TP_SMD_0.75mm"
				(at 10.16 -6.35 0)
				(effects
					(font
						(size 1.27 1.27)
						(thickness 0.15)
					)
					(justify left bottom)
					(hide yes)
				)
			)
			(property "Datasheet" ""
				(at 17.78 -12.7 0)
				(effects
					(font
						(size 1.27 1.27)
						(thickness 0.15)
					)
					(justify left bottom)
					(hide yes)
				)
			)
			(property "Description" "SMT test point"
				(at 0 0 0)
				(effects
					(font
						(size 1.27 1.27)
					)
					(hide yes)
				)
			)
			(property "MPN" ""
				(at 10.795 -11.43 0)
				(effects
					(font
						(size 1.27 1.27)
						(thickness 0.15)
					)
					(justify left bottom)
					(hide yes)
				)
			)
			(property "Manufacturer" ""
				(at 10.795 -6.35 0)
				(effects
					(font
						(size 1.27 1.27)
						(thickness 0.15)
					)
					(justify left bottom)
					(hide yes)
				)
			)
			(property "Author" "Antmicro"
				(at 10.16 -8.89 0)
				(effects
					(font
						(size 1.27 1.27)
						(thickness 0.15)
					)
					(justify left bottom)
					(hide yes)
				)
			)
			(property "License" "Apache-2.0"
				(at 10.16 -11.43 0)
				(effects
					(font
						(size 1.27 1.27)
						(thickness 0.15)
					)
					(justify left bottom)
					(hide yes)
				)
			)
			(property "ki_keywords" "TESTPOINT"
				(at 0 0 0)
				(effects
					(font
						(size 1.27 1.27)
					)
					(hide yes)
				)
			)
			(symbol "TP_0.75mm_SMD_1_1"
				(circle
					(center 3.175 0)
					(radius 0.635)
					(stroke
						(width 0.254)
						(type default)
					)
					(fill
						(type none)
					)
				)
				(pin passive line
					(at 0 0 0)
					(length 2.54)
					(name "1"
						(effects
							(font
								(size 1.27 1.27)
							)
						)
					)
					(number "1"
						(effects
							(font
								(size 1.27 1.27)
							)
						)
					)
				)
			)
		)
	(symbol "antmicroTestPoints:TP_1206_SMD_RCW-0C"
			(pin_names
				(hide yes)
			)
			(exclude_from_sim no)
			(in_bom no)
			(on_board yes)
			(property "Reference" "TP"
				(at 17.78 -5.08 0)
				(effects
					(font
						(size 1.27 1.27)
						(thickness 0.15)
					)
					(justify left bottom)
				)
			)
			(property "Value" "TP_1206_SMD_RCW-0C"
				(at 17.78 -7.62 0)
				(effects
					(font
						(size 1.27 1.27)
						(thickness 0.15)
					)
					(justify left bottom)
				)
			)
			(property "Footprint" "antmicro-footprints:TP_1206_SMD_RCW-0C"
				(at 17.78 -10.16 0)
				(effects
					(font
						(size 1.27 1.27)
						(thickness 0.15)
					)
					(justify left bottom)
					(hide yes)
				)
			)
			(property "Datasheet" "https://www.te.com/commerce/DocumentDelivery/DDEController?Action=srchrtrv&DocNm=1773266&DocType=DS&DocLang=English"
				(at 17.78 -12.7 0)
				(effects
					(font
						(size 1.27 1.27)
						(thickness 0.15)
					)
					(justify left bottom)
					(hide yes)
				)
			)
			(property "Description" "Circuit Probe Pad, SMD, Test Point, 1206"
				(at 0 0 0)
				(effects
					(font
						(size 1.27 1.27)
					)
					(hide yes)
				)
			)
			(property "MPN" "RCW-0C"
				(at 17.78 -15.24 0)
				(effects
					(font
						(size 1.27 1.27)
						(thickness 0.15)
					)
					(justify left bottom)
					(hide yes)
				)
			)
			(property "Manufacturer" "TE Connectivity"
				(at 17.78 -17.78 0)
				(effects
					(font
						(size 1.27 1.27)
						(thickness 0.15)
					)
					(justify left bottom)
					(hide yes)
				)
			)
			(property "Author" "Antmicro"
				(at 17.78 -20.32 0)
				(effects
					(font
						(size 1.27 1.27)
						(thickness 0.15)
					)
					(justify left bottom)
					(hide yes)
				)
			)
			(property "License" "Apache-2.0"
				(at 17.78 -22.86 0)
				(effects
					(font
						(size 1.27 1.27)
						(thickness 0.15)
					)
					(justify left bottom)
					(hide yes)
				)
			)
			(property "ki_keywords" "1206, SMT, TESTPOINT, PASSIVE"
				(at 0 0 0)
				(effects
					(font
						(size 1.27 1.27)
					)
					(hide yes)
				)
			)
			(symbol "TP_1206_SMD_RCW-0C_1_1"
				(circle
					(center 3.175 0)
					(radius 0.635)
					(stroke
						(width 0.254)
						(type default)
					)
					(fill
						(type none)
					)
				)
				(pin passive line
					(at 0 0 0)
					(length 2.54)
					(name "1"
						(effects
							(font
								(size 1.27 1.27)
							)
						)
					)
					(number "1"
						(effects
							(font
								(size 1.27 1.27)
							)
						)
					)
				)
			)
		)
	(symbol "antmicroTestPoints:TP_1mm_SMD"
			(pin_names
				(hide yes)
			)
			(exclude_from_sim no)
			(in_bom no)
			(on_board yes)
			(property "Reference" "TP"
				(at 15.24 -5.08 0)
				(effects
					(font
						(size 1.27 1.27)
						(thickness 0.15)
					)
					(justify left bottom)
				)
			)
			(property "Value" "TP_1mm_SMD"
				(at 15.24 -7.62 0)
				(effects
					(font
						(size 1.27 1.27)
						(thickness 0.15)
					)
					(justify left bottom)
					(hide yes)
				)
			)
			(property "Footprint" "antmicro-footprints:TP_SMD_1mm"
				(at 15.24 -10.16 0)
				(effects
					(font
						(size 1.27 1.27)
						(thickness 0.15)
					)
					(justify left bottom)
					(hide yes)
				)
			)
			(property "Datasheet" ""
				(at 17.78 -12.7 0)
				(effects
					(font
						(size 1.27 1.27)
						(thickness 0.15)
					)
					(justify left bottom)
					(hide yes)
				)
			)
			(property "Description" "Test point 1mm SMD"
				(at 15.24 -20.32 0)
				(effects
					(font
						(size 1.27 1.27)
					)
					(justify left bottom)
					(hide yes)
				)
			)
			(property "MPN" ""
				(at 0 0 0)
				(effects
					(font
						(size 1.27 1.27)
					)
					(hide yes)
				)
			)
			(property "Manufacturer" ""
				(at 0 0 0)
				(effects
					(font
						(size 1.27 1.27)
					)
					(hide yes)
				)
			)
			(property "Author" "Antmicro"
				(at 15.24 -15.24 0)
				(effects
					(font
						(size 1.27 1.27)
						(thickness 0.15)
					)
					(justify left bottom)
					(hide yes)
				)
			)
			(property "License" "Apache-2.0"
				(at 15.24 -17.78 0)
				(effects
					(font
						(size 1.27 1.27)
						(thickness 0.15)
					)
					(justify left bottom)
					(hide yes)
				)
			)
			(property "ki_keywords" "TESTPOINT"
				(at 0 0 0)
				(effects
					(font
						(size 1.27 1.27)
					)
					(hide yes)
				)
			)
			(symbol "TP_1mm_SMD_1_1"
				(circle
					(center 3.175 0)
					(radius 0.635)
					(stroke
						(width 0.254)
						(type default)
					)
					(fill
						(type none)
					)
				)
				(pin passive line
					(at 0 0 0)
					(length 2.54)
					(name "1"
						(effects
							(font
								(size 1.27 1.27)
							)
						)
					)
					(number "1"
						(effects
							(font
								(size 1.27 1.27)
							)
						)
					)
				)
			)
		)
	(symbol "antmicroTransistorsFETsMOSFETsSingle:BSS138PW"
			(pin_names
				(offset 0)
			)
			(exclude_from_sim no)
			(in_bom yes)
			(on_board yes)
			(property "Reference" "Q"
				(at 3.81 -6.35 0)
				(effects
					(font
						(size 1.27 1.27)
						(thickness 0.15)
					)
					(justify left bottom)
				)
			)
			(property "Value" "BSS138PW"
				(at 22.86 -8.89 0)
				(effects
					(font
						(size 1.27 1.27)
						(thickness 0.15)
					)
					(justify left bottom)
				)
			)
			(property "Footprint" "antmicro-footprints:SC70-3"
				(at 22.86 -11.43 0)
				(effects
					(font
						(size 1.27 1.27)
						(thickness 0.15)
					)
					(justify left bottom)
					(hide yes)
				)
			)
			(property "Datasheet" "https://assets.nexperia.com/documents/data-sheet/BSS138PW.pdf"
				(at 22.86 -13.97 0)
				(effects
					(font
						(size 1.27 1.27)
						(thickness 0.15)
					)
					(justify left bottom)
					(hide yes)
				)
			)
			(property "Description" "Power MOSFET, N Channel, 60 V, 320 mA, 0.9 ohm, SOT-323, Surface Mount"
				(at 0 0 0)
				(effects
					(font
						(size 1.27 1.27)
					)
					(hide yes)
				)
			)
			(property "MPN" "BSS138PW"
				(at 22.86 -16.51 0)
				(effects
					(font
						(size 1.27 1.27)
						(thickness 0.15)
					)
					(justify left bottom)
					(hide yes)
				)
			)
			(property "Manufacturer" "Nexperia"
				(at 22.86 -19.05 0)
				(effects
					(font
						(size 1.27 1.27)
						(thickness 0.15)
					)
					(justify left bottom)
					(hide yes)
				)
			)
			(property "Author" "Antmicro"
				(at 22.86 -21.59 0)
				(effects
					(font
						(size 1.27 1.27)
						(thickness 0.15)
					)
					(justify left bottom)
					(hide yes)
				)
			)
			(property "License" "Apache-2.0"
				(at 22.86 -24.13 0)
				(effects
					(font
						(size 1.27 1.27)
						(thickness 0.15)
					)
					(justify left bottom)
					(hide yes)
				)
			)
			(property "ki_keywords" "SMT, TRANSISTOR, SEMICONDUCTOR, MOSFET, NMOS"
				(at 0 0 0)
				(effects
					(font
						(size 1.27 1.27)
					)
					(hide yes)
				)
			)
			(symbol "BSS138PW_1_1"
				(polyline
					(pts
						(xy 2.54 0) (xy 4.572 0) (xy 4.572 3.937)
					)
					(stroke
						(width 0.254)
						(type default)
					)
					(fill
						(type none)
					)
				)
				(polyline
					(pts
						(xy 5.08 4.445) (xy 5.08 3.429)
					)
					(stroke
						(width 0.254)
						(type default)
					)
					(fill
						(type background)
					)
				)
				(polyline
					(pts
						(xy 5.08 2.54) (xy 5.08 3.048)
					)
					(stroke
						(width 0.254)
						(type default)
					)
					(fill
						(type background)
					)
				)
				(polyline
					(pts
						(xy 5.08 2.54) (xy 5.08 2.032)
					)
					(stroke
						(width 0.254)
						(type default)
					)
					(fill
						(type background)
					)
				)
				(polyline
					(pts
						(xy 5.08 2.54) (xy 5.842 3.048) (xy 5.842 2.032) (xy 5.08 2.54)
					)
					(stroke
						(width 0.254)
						(type default)
					)
					(fill
						(type outline)
					)
				)
				(polyline
					(pts
						(xy 5.08 1.143) (xy 5.08 1.651)
					)
					(stroke
						(width 0.254)
						(type default)
					)
					(fill
						(type background)
					)
				)
				(polyline
					(pts
						(xy 5.08 1.143) (xy 5.08 0.635)
					)
					(stroke
						(width 0.254)
						(type default)
					)
					(fill
						(type background)
					)
				)
				(circle
					(center 6.35 2.54)
					(radius 3.302)
					(stroke
						(width 0.254)
						(type default)
					)
					(fill
						(type background)
					)
				)
				(polyline
					(pts
						(xy 7.493 0.635) (xy 8.636 0.635) (xy 8.636 3.937) (xy 8.636 4.445) (xy 7.493 4.445)
					)
					(stroke
						(width 0.254)
						(type default)
					)
					(fill
						(type background)
					)
				)
				(polyline
					(pts
						(xy 7.62 6.35) (xy 7.62 3.937) (xy 5.08 3.937)
					)
					(stroke
						(width 0.254)
						(type default)
					)
					(fill
						(type background)
					)
				)
				(circle
					(center 7.62 4.445)
					(radius 0.127)
					(stroke
						(width 0.254)
						(type default)
					)
					(fill
						(type background)
					)
				)
				(polyline
					(pts
						(xy 7.62 1.143) (xy 5.08 1.143)
					)
					(stroke
						(width 0.254)
						(type default)
					)
					(fill
						(type background)
					)
				)
				(circle
					(center 7.62 1.143)
					(radius 0.127)
					(stroke
						(width 0.254)
						(type default)
					)
					(fill
						(type background)
					)
				)
				(circle
					(center 7.62 0.635)
					(radius 0.127)
					(stroke
						(width 0.254)
						(type default)
					)
					(fill
						(type background)
					)
				)
				(polyline
					(pts
						(xy 7.62 -1.27) (xy 7.62 2.54) (xy 5.08 2.54)
					)
					(stroke
						(width 0.254)
						(type default)
					)
					(fill
						(type background)
					)
				)
				(polyline
					(pts
						(xy 8.636 3.048) (xy 8.128 2.286) (xy 9.144 2.286) (xy 8.636 3.048)
					)
					(stroke
						(width 0.254)
						(type default)
					)
					(fill
						(type outline)
					)
				)
				(polyline
					(pts
						(xy 9.144 3.048) (xy 8.128 3.048)
					)
					(stroke
						(width 0.254)
						(type default)
					)
					(fill
						(type background)
					)
				)
				(pin passive line
					(at 0 0 0)
					(length 2.54)
					(name "G"
						(effects
							(font
								(size 1.27 1.27)
							)
						)
					)
					(number "1"
						(effects
							(font
								(size 1.27 1.27)
							)
						)
					)
				)
				(pin passive line
					(at 7.62 8.89 270)
					(length 2.54)
					(name "D"
						(effects
							(font
								(size 1.27 1.27)
							)
						)
					)
					(number "3"
						(effects
							(font
								(size 1.27 1.27)
							)
						)
					)
				)
				(pin passive line
					(at 7.62 -3.81 90)
					(length 2.54)
					(name "S"
						(effects
							(font
								(size 1.27 1.27)
							)
						)
					)
					(number "2"
						(effects
							(font
								(size 1.27 1.27)
							)
						)
					)
				)
			)
		)
	(symbol "antmicroTransistorsFETsMOSFETsSingle:BSS84AKW"
			(pin_names
				(offset 0)
			)
			(exclude_from_sim no)
			(in_bom yes)
			(on_board yes)
			(property "Reference" "Q"
				(at 22.86 -2.54 0)
				(effects
					(font
						(size 1.27 1.27)
						(thickness 0.15)
					)
					(justify left bottom)
				)
			)
			(property "Value" "BSS84AKW"
				(at 22.86 -7.62 0)
				(effects
					(font
						(size 1.27 1.27)
						(thickness 0.15)
					)
					(justify left bottom)
					(hide yes)
				)
			)
			(property "Footprint" "antmicro-footprints:SOT-323"
				(at 22.86 -10.16 0)
				(effects
					(font
						(size 1.27 1.27)
						(thickness 0.15)
					)
					(justify left bottom)
					(hide yes)
				)
			)
			(property "Datasheet" "https://assets.nexperia.com/documents/data-sheet/BSS84AKW.pdf"
				(at 22.86 -12.7 0)
				(effects
					(font
						(size 1.27 1.27)
						(thickness 0.15)
					)
					(justify left bottom)
					(hide yes)
				)
			)
			(property "Description" "Power MOSFET, P Channel, 50 V, 150 mA, 4.5 ohm, SOT-323, Surface Mount"
				(at 0 0 0)
				(effects
					(font
						(size 1.27 1.27)
					)
					(hide yes)
				)
			)
			(property "MPN" "BSS84AKW,115"
				(at 22.86 -5.08 0)
				(effects
					(font
						(size 1.27 1.27)
						(thickness 0.15)
					)
					(justify left bottom)
				)
			)
			(property "Manufacturer" "Nexperia"
				(at 22.86 -15.24 0)
				(effects
					(font
						(size 1.27 1.27)
						(thickness 0.15)
					)
					(justify left bottom)
					(hide yes)
				)
			)
			(property "Author" "Antmicro"
				(at 22.86 -17.78 0)
				(effects
					(font
						(size 1.27 1.27)
						(thickness 0.15)
					)
					(justify left bottom)
					(hide yes)
				)
			)
			(property "License" "Apache-2.0"
				(at 22.86 -20.32 0)
				(effects
					(font
						(size 1.27 1.27)
						(thickness 0.15)
					)
					(justify left bottom)
					(hide yes)
				)
			)
			(property "ki_keywords" "SMT, TRANSISTOR, SEMICONDUCTOR, MOSFET, PMOS"
				(at 0 0 0)
				(effects
					(font
						(size 1.27 1.27)
					)
					(hide yes)
				)
			)
			(symbol "BSS84AKW_1_1"
				(polyline
					(pts
						(xy 2.54 0) (xy 4.572 0) (xy 4.572 3.937)
					)
					(stroke
						(width 0.254)
						(type default)
					)
					(fill
						(type none)
					)
				)
				(polyline
					(pts
						(xy 5.08 4.445) (xy 5.08 3.429)
					)
					(stroke
						(width 0.254)
						(type default)
					)
					(fill
						(type background)
					)
				)
				(polyline
					(pts
						(xy 5.08 2.54) (xy 5.08 3.048)
					)
					(stroke
						(width 0.254)
						(type default)
					)
					(fill
						(type background)
					)
				)
				(polyline
					(pts
						(xy 5.08 2.54) (xy 5.08 2.032)
					)
					(stroke
						(width 0.254)
						(type default)
					)
					(fill
						(type background)
					)
				)
				(polyline
					(pts
						(xy 5.08 1.143) (xy 5.08 1.651)
					)
					(stroke
						(width 0.254)
						(type default)
					)
					(fill
						(type background)
					)
				)
				(polyline
					(pts
						(xy 5.08 1.143) (xy 5.08 0.635)
					)
					(stroke
						(width 0.254)
						(type default)
					)
					(fill
						(type background)
					)
				)
				(circle
					(center 6.35 2.54)
					(radius 3.302)
					(stroke
						(width 0.254)
						(type default)
					)
					(fill
						(type background)
					)
				)
				(polyline
					(pts
						(xy 7.239 2.54) (xy 6.477 3.048) (xy 6.477 2.032) (xy 7.239 2.54)
					)
					(stroke
						(width 0.254)
						(type default)
					)
					(fill
						(type outline)
					)
				)
				(polyline
					(pts
						(xy 7.493 0.635) (xy 8.636 0.635) (xy 8.636 3.937) (xy 8.636 4.445) (xy 7.493 4.445)
					)
					(stroke
						(width 0.254)
						(type default)
					)
					(fill
						(type background)
					)
				)
				(polyline
					(pts
						(xy 7.62 6.35) (xy 7.62 3.937) (xy 5.08 3.937)
					)
					(stroke
						(width 0.254)
						(type default)
					)
					(fill
						(type none)
					)
				)
				(circle
					(center 7.62 4.445)
					(radius 0.127)
					(stroke
						(width 0.254)
						(type default)
					)
					(fill
						(type background)
					)
				)
				(polyline
					(pts
						(xy 7.62 1.143) (xy 5.08 1.143)
					)
					(stroke
						(width 0.254)
						(type default)
					)
					(fill
						(type background)
					)
				)
				(circle
					(center 7.62 1.143)
					(radius 0.127)
					(stroke
						(width 0.254)
						(type default)
					)
					(fill
						(type background)
					)
				)
				(circle
					(center 7.62 0.635)
					(radius 0.127)
					(stroke
						(width 0.254)
						(type default)
					)
					(fill
						(type background)
					)
				)
				(polyline
					(pts
						(xy 7.62 -1.27) (xy 7.62 2.54) (xy 5.08 2.54)
					)
					(stroke
						(width 0.254)
						(type default)
					)
					(fill
						(type none)
					)
				)
				(polyline
					(pts
						(xy 8.636 2.286) (xy 9.144 3.048) (xy 8.128 3.048) (xy 8.636 2.286)
					)
					(stroke
						(width 0.254)
						(type default)
					)
					(fill
						(type outline)
					)
				)
				(polyline
					(pts
						(xy 9.144 2.3368) (xy 8.128 2.3368)
					)
					(stroke
						(width 0.254)
						(type default)
					)
					(fill
						(type background)
					)
				)
				(pin bidirectional line
					(at 0 0 0)
					(length 2.54)
					(name "G"
						(effects
							(font
								(size 1.27 1.27)
							)
						)
					)
					(number "1"
						(effects
							(font
								(size 1.27 1.27)
							)
						)
					)
				)
				(pin bidirectional line
					(at 7.62 8.89 270)
					(length 2.54)
					(name "D"
						(effects
							(font
								(size 1.27 1.27)
							)
						)
					)
					(number "3"
						(effects
							(font
								(size 1.27 1.27)
							)
						)
					)
				)
				(pin bidirectional line
					(at 7.62 -3.81 90)
					(length 2.54)
					(name "S"
						(effects
							(font
								(size 1.27 1.27)
							)
						)
					)
					(number "2"
						(effects
							(font
								(size 1.27 1.27)
							)
						)
					)
				)
			)
		)
	(symbol "antmicroTransistorsFETsMOSFETsSingle:SI7613DN-T1-GE3"
			(pin_names
				(offset 0)
			)
			(exclude_from_sim no)
			(in_bom yes)
			(on_board yes)
			(property "Reference" "Q"
				(at 15.24 5.08 0)
				(effects
					(font
						(size 1.27 1.27)
						(thickness 0.15)
					)
					(justify left bottom)
				)
			)
			(property "Value" "SI7613DN-T1-GE3"
				(at 15.24 2.54 0)
				(effects
					(font
						(size 1.27 1.27)
						(thickness 0.15)
					)
					(justify left bottom)
				)
			)
			(property "Footprint" "antmicro-footprints:Vishay_PowerPAK_1212-8_Single"
				(at 15.24 1.27 0)
				(effects
					(font
						(size 1.27 1.27)
						(thickness 0.15)
					)
					(justify left bottom)
					(hide yes)
				)
			)
			(property "Datasheet" "https://www.vishay.com/docs/64809/si7613dn.pdf"
				(at 15.24 -1.27 0)
				(effects
					(font
						(size 1.27 1.27)
						(thickness 0.15)
					)
					(justify left bottom)
					(hide yes)
				)
			)
			(property "Description" "Power MOSFET, P Channel, 20 V, 35 A, 0.0072 ohm, PowerPAK 1212, Surface Mount"
				(at 0 0 0)
				(effects
					(font
						(size 1.27 1.27)
					)
					(hide yes)
				)
			)
			(property "MPN" "SI7613DN-T1-GE3"
				(at 15.24 -5.08 0)
				(effects
					(font
						(size 1.27 1.27)
						(thickness 0.15)
					)
					(justify left bottom)
					(hide yes)
				)
			)
			(property "Manufacturer" "Vishay"
				(at 15.24 -7.62 0)
				(effects
					(font
						(size 1.27 1.27)
						(thickness 0.15)
					)
					(justify left bottom)
					(hide yes)
				)
			)
			(property "Author" "Antmicro"
				(at 15.24 -10.16 0)
				(effects
					(font
						(size 1.27 1.27)
						(thickness 0.15)
					)
					(justify left bottom)
					(hide yes)
				)
			)
			(property "License" "Apache-2.0"
				(at 15.24 -12.7 0)
				(effects
					(font
						(size 1.27 1.27)
						(thickness 0.15)
					)
					(justify left bottom)
					(hide yes)
				)
			)
			(property "ki_keywords" "SMT, TRANSISTOR, SEMICONDUCTOR, MOSFET, PMOS"
				(at 0 0 0)
				(effects
					(font
						(size 1.27 1.27)
					)
					(hide yes)
				)
			)
			(symbol "SI7613DN-T1-GE3_1_1"
				(polyline
					(pts
						(xy 2.54 0) (xy 4.572 0) (xy 4.572 3.937)
					)
					(stroke
						(width 0.254)
						(type default)
					)
					(fill
						(type none)
					)
				)
				(polyline
					(pts
						(xy 5.08 4.445) (xy 5.08 3.429)
					)
					(stroke
						(width 0.254)
						(type default)
					)
					(fill
						(type background)
					)
				)
				(polyline
					(pts
						(xy 5.08 2.54) (xy 5.08 3.048)
					)
					(stroke
						(width 0.254)
						(type default)
					)
					(fill
						(type background)
					)
				)
				(polyline
					(pts
						(xy 5.08 2.54) (xy 5.08 2.032)
					)
					(stroke
						(width 0.254)
						(type default)
					)
					(fill
						(type background)
					)
				)
				(polyline
					(pts
						(xy 5.08 1.143) (xy 5.08 1.651)
					)
					(stroke
						(width 0.254)
						(type default)
					)
					(fill
						(type background)
					)
				)
				(polyline
					(pts
						(xy 5.08 1.143) (xy 5.08 0.635)
					)
					(stroke
						(width 0.254)
						(type default)
					)
					(fill
						(type background)
					)
				)
				(circle
					(center 6.35 2.54)
					(radius 3.302)
					(stroke
						(width 0.254)
						(type default)
					)
					(fill
						(type background)
					)
				)
				(polyline
					(pts
						(xy 7.239 2.54) (xy 6.477 3.048) (xy 6.477 2.032) (xy 7.239 2.54)
					)
					(stroke
						(width 0.254)
						(type default)
					)
					(fill
						(type outline)
					)
				)
				(polyline
					(pts
						(xy 7.493 0.635) (xy 8.636 0.635) (xy 8.636 3.937) (xy 8.636 4.445) (xy 7.493 4.445)
					)
					(stroke
						(width 0.254)
						(type default)
					)
					(fill
						(type background)
					)
				)
				(polyline
					(pts
						(xy 7.62 6.35) (xy 7.62 3.937) (xy 5.08 3.937)
					)
					(stroke
						(width 0.254)
						(type default)
					)
					(fill
						(type none)
					)
				)
				(circle
					(center 7.62 4.445)
					(radius 0.127)
					(stroke
						(width 0.254)
						(type default)
					)
					(fill
						(type background)
					)
				)
				(polyline
					(pts
						(xy 7.62 1.143) (xy 5.08 1.143)
					)
					(stroke
						(width 0.254)
						(type default)
					)
					(fill
						(type background)
					)
				)
				(circle
					(center 7.62 1.143)
					(radius 0.127)
					(stroke
						(width 0.254)
						(type default)
					)
					(fill
						(type background)
					)
				)
				(circle
					(center 7.62 0.635)
					(radius 0.127)
					(stroke
						(width 0.254)
						(type default)
					)
					(fill
						(type background)
					)
				)
				(polyline
					(pts
						(xy 7.62 -1.27) (xy 7.62 2.54) (xy 5.08 2.54)
					)
					(stroke
						(width 0.254)
						(type default)
					)
					(fill
						(type none)
					)
				)
				(polyline
					(pts
						(xy 8.636 2.286) (xy 8.128 3.048) (xy 9.144 3.048) (xy 8.636 2.286)
					)
					(stroke
						(width 0.254)
						(type default)
					)
					(fill
						(type outline)
					)
				)
				(polyline
					(pts
						(xy 9.144 2.2352) (xy 8.128 2.2352)
					)
					(stroke
						(width 0.254)
						(type default)
					)
					(fill
						(type background)
					)
				)
				(pin passive line
					(at 0 0 0)
					(length 2.54)
					(name "G"
						(effects
							(font
								(size 1.27 1.27)
							)
						)
					)
					(number "4"
						(effects
							(font
								(size 1.27 1.27)
							)
						)
					)
				)
				(pin passive line
					(at 7.62 8.89 270)
					(length 2.54)
					(name "D"
						(effects
							(font
								(size 1.27 1.27)
							)
						)
					)
					(number "5"
						(effects
							(font
								(size 1.27 1.27)
							)
						)
					)
				)
				(pin passive line
					(at 7.62 -3.81 90)
					(length 2.54)
					(name "S"
						(effects
							(font
								(size 1.27 1.27)
							)
						)
					)
					(number "1"
						(effects
							(font
								(size 1.27 1.27)
							)
						)
					)
				)
				(pin passive line
					(at 7.62 -3.81 90)
					(length 2.54)
					(hide yes)
					(name "S"
						(effects
							(font
								(size 1.27 1.27)
							)
						)
					)
					(number "2"
						(effects
							(font
								(size 1.27 1.27)
							)
						)
					)
				)
				(pin passive line
					(at 7.62 -3.81 90)
					(length 2.54)
					(hide yes)
					(name "S"
						(effects
							(font
								(size 1.27 1.27)
							)
						)
					)
					(number "3"
						(effects
							(font
								(size 1.27 1.27)
							)
						)
					)
				)
			)
		)
	(symbol "antmicroUSBConnectors:USB-C_GCT_USB4105-GF-A"
			(exclude_from_sim no)
			(in_bom yes)
			(on_board yes)
			(property "Reference" "J"
				(at 38.1 -2.54 0)
				(effects
					(font
						(size 1.27 1.27)
						(thickness 0.15)
					)
					(justify left bottom)
				)
			)
			(property "Value" "USB-C_GCT_USB4105-GF-A"
				(at 38.1 -5.08 0)
				(effects
					(font
						(size 1.27 1.27)
						(thickness 0.15)
					)
					(justify left bottom)
				)
			)
			(property "Footprint" "antmicro-footprints:USB-C_Receptacle_GCT_USB4105-GF-A"
				(at 38.1 -7.62 0)
				(effects
					(font
						(size 1.27 1.27)
						(thickness 0.15)
					)
					(justify left bottom)
					(hide yes)
				)
			)
			(property "Datasheet" "https://gct.co/files/drawings/usb4105.pdf"
				(at 38.1 -10.16 0)
				(effects
					(font
						(size 1.27 1.27)
						(thickness 0.15)
					)
					(justify left bottom)
					(hide yes)
				)
			)
			(property "Description" "USB-C (USB TYPE-C) USB 2.0 Receptacle Connector 24 (16+8 Dummy) Position Surface Mount, Right Angle"
				(at 0 0 0)
				(effects
					(font
						(size 1.27 1.27)
					)
					(hide yes)
				)
			)
			(property "Manufacturer" "GCT"
				(at 38.1 -12.7 0)
				(effects
					(font
						(size 1.27 1.27)
						(thickness 0.15)
					)
					(justify left bottom)
					(hide yes)
				)
			)
			(property "MPN" "USB4105-GF-A"
				(at 38.1 -15.24 0)
				(effects
					(font
						(size 1.27 1.27)
						(thickness 0.15)
					)
					(justify left bottom)
					(hide yes)
				)
			)
			(property "Author" "Antmicro"
				(at 38.1 -17.78 0)
				(effects
					(font
						(size 1.27 1.27)
						(thickness 0.15)
					)
					(justify left bottom)
					(hide yes)
				)
			)
			(property "License" "Apache-2.0"
				(at 38.1 -20.32 0)
				(effects
					(font
						(size 1.27 1.27)
						(thickness 0.15)
					)
					(justify left bottom)
					(hide yes)
				)
			)
			(property "ki_keywords" "USB, CONNECTOR, SMT, HORIZONTAL"
				(at 0 0 0)
				(effects
					(font
						(size 1.27 1.27)
					)
					(hide yes)
				)
			)
			(symbol "USB-C_GCT_USB4105-GF-A_1_1"
				(rectangle
					(start -22.86 2.54)
					(end -3.81 -38.1)
					(stroke
						(width 0.254)
						(type default)
					)
					(fill
						(type background)
					)
				)
				(circle
					(center -20.066 -18.034)
					(radius 0.284)
					(stroke
						(width 0.254)
						(type default)
					)
					(fill
						(type outline)
					)
				)
				(polyline
					(pts
						(xy -19.812 -16.383) (xy -19.177 -15.24) (xy -18.542 -16.383) (xy -19.812 -16.383)
					)
					(stroke
						(width 0.254)
						(type default)
					)
					(fill
						(type outline)
					)
				)
				(polyline
					(pts
						(xy -19.177 -19.558) (xy -18.288 -18.669) (xy -18.288 -18.034)
					)
					(stroke
						(width 0.254)
						(type default)
					)
					(fill
						(type background)
					)
				)
				(polyline
					(pts
						(xy -19.177 -19.939) (xy -20.066 -19.05) (xy -20.066 -18.415)
					)
					(stroke
						(width 0.254)
						(type default)
					)
					(fill
						(type background)
					)
				)
				(polyline
					(pts
						(xy -19.177 -20.701) (xy -19.177 -16.383)
					)
					(stroke
						(width 0.254)
						(type default)
					)
					(fill
						(type background)
					)
				)
				(circle
					(center -19.177 -20.828)
					(radius 0.5236)
					(stroke
						(width 0.254)
						(type default)
					)
					(fill
						(type outline)
					)
				)
				(rectangle
					(start -18.669 -18.034)
					(end -17.907 -17.272)
					(stroke
						(width 0.254)
						(type default)
					)
					(fill
						(type outline)
					)
				)
				(polyline
					(pts
						(xy -16.51 -21.59) (xy -16.51 -13.97)
					)
					(stroke
						(width 0.254)
						(type default)
					)
					(fill
						(type background)
					)
				)
				(rectangle
					(start -15.24 -21.59)
					(end -13.97 -13.97)
					(stroke
						(width 0.254)
						(type default)
					)
					(fill
						(type outline)
					)
				)
				(arc
					(start -15.24 -13.97)
					(mid -14.605 -13.3377)
					(end -13.97 -13.97)
					(stroke
						(width 0.254)
						(type default)
					)
					(fill
						(type outline)
					)
				)
				(arc
					(start -15.24 -13.97)
					(mid -14.605 -13.3377)
					(end -13.97 -13.97)
					(stroke
						(width 0.254)
						(type default)
					)
					(fill
						(type background)
					)
				)
				(arc
					(start -16.51 -13.97)
					(mid -14.605 -12.0733)
					(end -12.7 -13.97)
					(stroke
						(width 0.254)
						(type default)
					)
					(fill
						(type background)
					)
				)
				(arc
					(start -12.7 -21.59)
					(mid -14.605 -23.4867)
					(end -16.51 -21.59)
					(stroke
						(width 0.254)
						(type default)
					)
					(fill
						(type background)
					)
				)
				(arc
					(start -13.97 -21.59)
					(mid -14.605 -22.2223)
					(end -15.24 -21.59)
					(stroke
						(width 0.254)
						(type default)
					)
					(fill
						(type outline)
					)
				)
				(arc
					(start -13.97 -21.59)
					(mid -14.605 -22.2223)
					(end -15.24 -21.59)
					(stroke
						(width 0.254)
						(type default)
					)
					(fill
						(type background)
					)
				)
				(polyline
					(pts
						(xy -12.7 -13.97) (xy -12.7 -21.59)
					)
					(stroke
						(width 0.254)
						(type default)
					)
					(fill
						(type background)
					)
				)
				(pin passive line
					(at 0 0 180)
					(length 3.81)
					(name "VBUS"
						(effects
							(font
								(size 1.27 1.27)
							)
						)
					)
					(number "A4"
						(effects
							(font
								(size 1.27 1.27)
							)
						)
					)
				)
				(pin passive line
					(at 0 0 180)
					(length 3.81)
					(hide yes)
					(name "VBUS"
						(effects
							(font
								(size 1.27 1.27)
							)
						)
					)
					(number "A9"
						(effects
							(font
								(size 1.27 1.27)
							)
						)
					)
				)
				(pin passive line
					(at 0 0 180)
					(length 3.81)
					(hide yes)
					(name "VBUS"
						(effects
							(font
								(size 1.27 1.27)
							)
						)
					)
					(number "B4"
						(effects
							(font
								(size 1.27 1.27)
							)
						)
					)
				)
				(pin passive line
					(at 0 0 180)
					(length 3.81)
					(hide yes)
					(name "VBUS"
						(effects
							(font
								(size 1.27 1.27)
							)
						)
					)
					(number "B9"
						(effects
							(font
								(size 1.27 1.27)
							)
						)
					)
				)
				(pin bidirectional line
					(at 0 -5.08 180)
					(length 3.81)
					(name "CC_{1}"
						(effects
							(font
								(size 1.27 1.27)
							)
						)
					)
					(number "A5"
						(effects
							(font
								(size 1.27 1.27)
							)
						)
					)
				)
				(pin bidirectional line
					(at 0 -7.62 180)
					(length 3.81)
					(name "CC_{2}"
						(effects
							(font
								(size 1.27 1.27)
							)
						)
					)
					(number "B5"
						(effects
							(font
								(size 1.27 1.27)
							)
						)
					)
				)
				(pin bidirectional line
					(at 0 -12.7 180)
					(length 3.81)
					(name "D_{A}+"
						(effects
							(font
								(size 1.27 1.27)
							)
						)
					)
					(number "A6"
						(effects
							(font
								(size 1.27 1.27)
							)
						)
					)
				)
				(pin bidirectional line
					(at 0 -15.24 180)
					(length 3.81)
					(name "D_{A}-"
						(effects
							(font
								(size 1.27 1.27)
							)
						)
					)
					(number "A7"
						(effects
							(font
								(size 1.27 1.27)
							)
						)
					)
				)
				(pin bidirectional line
					(at 0 -17.78 180)
					(length 3.81)
					(name "D_{B}+"
						(effects
							(font
								(size 1.27 1.27)
							)
						)
					)
					(number "B6"
						(effects
							(font
								(size 1.27 1.27)
							)
						)
					)
				)
				(pin bidirectional line
					(at 0 -20.32 180)
					(length 3.81)
					(name "D_{B}-"
						(effects
							(font
								(size 1.27 1.27)
							)
						)
					)
					(number "B7"
						(effects
							(font
								(size 1.27 1.27)
							)
						)
					)
				)
				(pin bidirectional line
					(at 0 -25.4 180)
					(length 3.81)
					(name "SBU_{1}"
						(effects
							(font
								(size 1.27 1.27)
							)
						)
					)
					(number "A8"
						(effects
							(font
								(size 1.27 1.27)
							)
						)
					)
				)
				(pin bidirectional line
					(at 0 -27.94 180)
					(length 3.81)
					(name "SBU_{2}"
						(effects
							(font
								(size 1.27 1.27)
							)
						)
					)
					(number "B8"
						(effects
							(font
								(size 1.27 1.27)
							)
						)
					)
				)
				(pin power_in line
					(at 0 -33.02 180)
					(length 3.81)
					(name "GND"
						(effects
							(font
								(size 1.27 1.27)
							)
						)
					)
					(number "A1"
						(effects
							(font
								(size 1.27 1.27)
							)
						)
					)
				)
				(pin passive line
					(at 0 -33.02 180)
					(length 3.81)
					(hide yes)
					(name "GND"
						(effects
							(font
								(size 1.27 1.27)
							)
						)
					)
					(number "A12"
						(effects
							(font
								(size 1.27 1.27)
							)
						)
					)
				)
				(pin passive line
					(at 0 -33.02 180)
					(length 3.81)
					(hide yes)
					(name "GND"
						(effects
							(font
								(size 1.27 1.27)
							)
						)
					)
					(number "B1"
						(effects
							(font
								(size 1.27 1.27)
							)
						)
					)
				)
				(pin passive line
					(at 0 -33.02 180)
					(length 3.81)
					(hide yes)
					(name "GND"
						(effects
							(font
								(size 1.27 1.27)
							)
						)
					)
					(number "B12"
						(effects
							(font
								(size 1.27 1.27)
							)
						)
					)
				)
				(pin passive line
					(at 0 -35.56 180)
					(length 3.81)
					(name "SH"
						(effects
							(font
								(size 1.27 1.27)
							)
						)
					)
					(number "SH"
						(effects
							(font
								(size 1.27 1.27)
							)
						)
					)
				)
			)
		)
	(symbol "antmicroVideoConnectors:HDMI-A_WE_685119134923"
			(exclude_from_sim no)
			(in_bom yes)
			(on_board yes)
			(property "Reference" "J"
				(at 35.56 -2.54 0)
				(effects
					(font
						(size 1.27 1.27)
						(thickness 0.15)
					)
					(justify left bottom)
				)
			)
			(property "Value" "HDMI-A_WE_685119134923"
				(at 35.56 -5.08 0)
				(effects
					(font
						(size 1.27 1.27)
						(thickness 0.15)
					)
					(justify left bottom)
				)
			)
			(property "Footprint" "antmicro-footprints:HDMI-A_Receptacle_WE_685119134923"
				(at 35.56 -7.62 0)
				(effects
					(font
						(size 1.27 1.27)
						(thickness 0.15)
					)
					(justify left bottom)
					(hide yes)
				)
			)
			(property "Datasheet" "https://www.we-online.com/components/products/datasheet/685119134923.pdf"
				(at 35.56 -10.16 0)
				(effects
					(font
						(size 1.27 1.27)
						(thickness 0.15)
					)
					(justify left bottom)
					(hide yes)
				)
			)
			(property "Description" "HDMI Receptacle Connector 19 Position Surface Mount, Right Angle; Through Hole"
				(at 0 0 0)
				(effects
					(font
						(size 1.27 1.27)
					)
					(hide yes)
				)
			)
			(property "MPN" "685119134923"
				(at 35.56 -12.7 0)
				(effects
					(font
						(size 1.27 1.27)
						(thickness 0.15)
					)
					(justify left bottom)
					(hide yes)
				)
			)
			(property "Manufacturer" "Würth Elektronik"
				(at 35.56 -15.24 0)
				(effects
					(font
						(size 1.27 1.27)
						(thickness 0.15)
					)
					(justify left bottom)
					(hide yes)
				)
			)
			(property "Author" "Antmicro"
				(at 35.56 -17.78 0)
				(effects
					(font
						(size 1.27 1.27)
						(thickness 0.15)
					)
					(justify left bottom)
					(hide yes)
				)
			)
			(property "License" "Apache-2.0"
				(at 35.56 -20.32 0)
				(effects
					(font
						(size 1.27 1.27)
						(thickness 0.15)
					)
					(justify left bottom)
					(hide yes)
				)
			)
			(property "ki_keywords" "HDMI, CONNECTOR, THT"
				(at 0 0 0)
				(effects
					(font
						(size 1.27 1.27)
					)
					(hide yes)
				)
			)
			(property "ki_fp_filters" "685119134923"
				(at 0 0 0)
				(effects
					(font
						(size 1.27 1.27)
					)
					(hide yes)
				)
			)
			(symbol "HDMI-A_WE_685119134923_0_0"
				(polyline
					(pts
						(xy 13.97 0) (xy 13.97 1.524) (xy 13.97 0.762) (xy 15.875 0.762) (xy 15.875 1.524) (xy 15.875 0)
					)
					(stroke
						(width 0.635)
						(type default)
					)
					(fill
						(type none)
					)
				)
				(polyline
					(pts
						(xy 16.637 1.524) (xy 18.288 1.524) (xy 18.542 1.27) (xy 18.542 0.254) (xy 18.288 0) (xy 16.637 0)
						(xy 16.637 0.762)
					)
					(stroke
						(width 0.635)
						(type default)
					)
					(fill
						(type none)
					)
				)
				(polyline
					(pts
						(xy 22.098 0) (xy 22.098 1.524)
					)
					(stroke
						(width 0.635)
						(type default)
					)
					(fill
						(type none)
					)
				)
			)
			(symbol "HDMI-A_WE_685119134923_0_1"
				(polyline
					(pts
						(xy 10.16 -15.24) (xy 13.97 -15.24) (xy 15.875 -17.145) (xy 15.875 -28.575) (xy 13.97 -30.48)
						(xy 10.16 -30.48) (xy 10.16 -15.24)
					)
					(stroke
						(width 0.635)
						(type default)
					)
					(fill
						(type none)
					)
				)
				(polyline
					(pts
						(xy 12.065 -16.51) (xy 13.335 -16.51) (xy 13.97 -17.145) (xy 13.97 -28.575) (xy 13.335 -29.21)
						(xy 12.065 -29.21) (xy 12.065 -16.51)
					)
					(stroke
						(width 0.254)
						(type default)
					)
					(fill
						(type outline)
					)
				)
				(polyline
					(pts
						(xy 19.304 0) (xy 19.304 1.524) (xy 20.32 1.524) (xy 20.32 0) (xy 20.32 1.524) (xy 21.082 1.524)
						(xy 21.336 1.27) (xy 21.336 0)
					)
					(stroke
						(width 0.635)
						(type default)
					)
					(fill
						(type none)
					)
				)
			)
			(symbol "HDMI-A_WE_685119134923_1_1"
				(rectangle
					(start 2.54 2.54)
					(end 22.86 -53.34)
					(stroke
						(width 0.254)
						(type default)
					)
					(fill
						(type background)
					)
				)
				(pin bidirectional line
					(at 0 0 0)
					(length 2.54)
					(name "D2+"
						(effects
							(font
								(size 1.27 1.27)
							)
						)
					)
					(number "1"
						(effects
							(font
								(size 1.27 1.27)
							)
						)
					)
				)
				(pin bidirectional line
					(at 0 -2.54 0)
					(length 2.54)
					(name "D2-"
						(effects
							(font
								(size 1.27 1.27)
							)
						)
					)
					(number "3"
						(effects
							(font
								(size 1.27 1.27)
							)
						)
					)
				)
				(pin bidirectional line
					(at 0 -7.62 0)
					(length 2.54)
					(name "D1+"
						(effects
							(font
								(size 1.27 1.27)
							)
						)
					)
					(number "4"
						(effects
							(font
								(size 1.27 1.27)
							)
						)
					)
				)
				(pin bidirectional line
					(at 0 -10.16 0)
					(length 2.54)
					(name "D1-"
						(effects
							(font
								(size 1.27 1.27)
							)
						)
					)
					(number "6"
						(effects
							(font
								(size 1.27 1.27)
							)
						)
					)
				)
				(pin bidirectional line
					(at 0 -15.24 0)
					(length 2.54)
					(name "D0+"
						(effects
							(font
								(size 1.27 1.27)
							)
						)
					)
					(number "7"
						(effects
							(font
								(size 1.27 1.27)
							)
						)
					)
				)
				(pin bidirectional line
					(at 0 -17.78 0)
					(length 2.54)
					(name "D0-"
						(effects
							(font
								(size 1.27 1.27)
							)
						)
					)
					(number "9"
						(effects
							(font
								(size 1.27 1.27)
							)
						)
					)
				)
				(pin bidirectional line
					(at 0 -22.86 0)
					(length 2.54)
					(name "CK+"
						(effects
							(font
								(size 1.27 1.27)
							)
						)
					)
					(number "10"
						(effects
							(font
								(size 1.27 1.27)
							)
						)
					)
				)
				(pin bidirectional line
					(at 0 -25.4 0)
					(length 2.54)
					(name "CK-"
						(effects
							(font
								(size 1.27 1.27)
							)
						)
					)
					(number "12"
						(effects
							(font
								(size 1.27 1.27)
							)
						)
					)
				)
				(pin bidirectional line
					(at 0 -30.48 0)
					(length 2.54)
					(name "SCL"
						(effects
							(font
								(size 1.27 1.27)
							)
						)
					)
					(number "15"
						(effects
							(font
								(size 1.27 1.27)
							)
						)
					)
				)
				(pin bidirectional line
					(at 0 -33.02 0)
					(length 2.54)
					(name "SDA"
						(effects
							(font
								(size 1.27 1.27)
							)
						)
					)
					(number "16"
						(effects
							(font
								(size 1.27 1.27)
							)
						)
					)
				)
				(pin bidirectional line
					(at 0 -38.1 0)
					(length 2.54)
					(name "CEC"
						(effects
							(font
								(size 1.27 1.27)
							)
						)
					)
					(number "13"
						(effects
							(font
								(size 1.27 1.27)
							)
						)
					)
				)
				(pin bidirectional line
					(at 0 -43.18 0)
					(length 2.54)
					(name "HPD/HEAC-"
						(effects
							(font
								(size 1.27 1.27)
							)
						)
					)
					(number "19"
						(effects
							(font
								(size 1.27 1.27)
							)
						)
					)
					(alternate "HEAC-" passive line)
					(alternate "HPD" passive line)
				)
				(pin bidirectional line
					(at 0 -45.72 0)
					(length 2.54)
					(name "UTILITY/HEAC+"
						(effects
							(font
								(size 1.27 1.27)
							)
						)
					)
					(number "14"
						(effects
							(font
								(size 1.27 1.27)
							)
						)
					)
					(alternate "HEAC+" passive line)
					(alternate "UTILITY" passive line)
				)
				(pin power_in line
					(at 0 -50.8 0)
					(length 2.54)
					(name "+5V"
						(effects
							(font
								(size 1.27 1.27)
							)
						)
					)
					(number "18"
						(effects
							(font
								(size 1.27 1.27)
							)
						)
					)
				)
				(pin passive line
					(at 25.4 -38.1 180)
					(length 2.54)
					(name "D2S"
						(effects
							(font
								(size 1.27 1.27)
							)
						)
					)
					(number "2"
						(effects
							(font
								(size 1.27 1.27)
							)
						)
					)
				)
				(pin passive line
					(at 25.4 -40.64 180)
					(length 2.54)
					(name "D1S"
						(effects
							(font
								(size 1.27 1.27)
							)
						)
					)
					(number "5"
						(effects
							(font
								(size 1.27 1.27)
							)
						)
					)
				)
				(pin passive line
					(at 25.4 -43.18 180)
					(length 2.54)
					(name "D0S"
						(effects
							(font
								(size 1.27 1.27)
							)
						)
					)
					(number "8"
						(effects
							(font
								(size 1.27 1.27)
							)
						)
					)
				)
				(pin passive line
					(at 25.4 -45.72 180)
					(length 2.54)
					(name "CKS"
						(effects
							(font
								(size 1.27 1.27)
							)
						)
					)
					(number "11"
						(effects
							(font
								(size 1.27 1.27)
							)
						)
					)
				)
				(pin power_in line
					(at 25.4 -48.26 180)
					(length 2.54)
					(name "GND"
						(effects
							(font
								(size 1.27 1.27)
							)
						)
					)
					(number "17"
						(effects
							(font
								(size 1.27 1.27)
							)
						)
					)
				)
				(pin passive line
					(at 25.4 -50.8 180)
					(length 2.54)
					(name "SH"
						(effects
							(font
								(size 1.27 1.27)
							)
						)
					)
					(number "SH"
						(effects
							(font
								(size 1.27 1.27)
							)
						)
					)
				)
			)
		)
	(symbol "antmicroWire2BoardConnectors:I-PEX_CABLINE-VS_1x20_20455-A20E-76"
			(exclude_from_sim no)
			(in_bom yes)
			(on_board yes)
			(property "Reference" "J"
				(at 22.86 -2.54 0)
				(effects
					(font
						(size 1.27 1.27)
						(thickness 0.15)
					)
					(justify left bottom)
				)
			)
			(property "Value" "I-PEX_CABLINE-VS_1x20_20455-A20E-76"
				(at 22.86 -7.62 0)
				(effects
					(font
						(size 1.27 1.27)
						(thickness 0.15)
					)
					(justify left bottom)
					(hide yes)
				)
			)
			(property "Footprint" "antmicro-footprints:I-PEX_CABLINE-VS_1x20_20455-A20E-76"
				(at 22.86 -10.16 0)
				(effects
					(font
						(size 1.27 1.27)
						(thickness 0.15)
					)
					(justify left bottom)
					(hide yes)
				)
			)
			(property "Datasheet" "https://www.i-pex.com/sites/default/files/downloads/pdf/MANUAL_CABLINE-VS_HIM-08004-07EN.pdf"
				(at 22.86 -12.7 0)
				(effects
					(font
						(size 1.27 1.27)
						(thickness 0.15)
					)
					(justify left bottom)
					(hide yes)
				)
			)
			(property "Description" "0.5 mm pitch, Horizontal mating type Micro-coaxial and FPC connector with mechanical lock (VESA standard connector)"
				(at 0 0 0)
				(effects
					(font
						(size 1.27 1.27)
					)
					(hide yes)
				)
			)
			(property "MPN" "20455-A20E-76"
				(at 22.86 -5.08 0)
				(effects
					(font
						(size 1.27 1.27)
						(thickness 0.15)
					)
					(justify left bottom)
				)
			)
			(property "Manufacturer" "I-PEX"
				(at 22.86 -15.24 0)
				(effects
					(font
						(size 1.27 1.27)
						(thickness 0.15)
					)
					(justify left bottom)
					(hide yes)
				)
			)
			(property "Author" "Antmicro"
				(at 22.86 -17.78 0)
				(effects
					(font
						(size 1.27 1.27)
						(thickness 0.15)
					)
					(justify left bottom)
					(hide yes)
				)
			)
			(property "License" "Apache-2.0"
				(at 22.86 -20.32 0)
				(effects
					(font
						(size 1.27 1.27)
						(thickness 0.15)
					)
					(justify left bottom)
					(hide yes)
				)
			)
			(property "ki_keywords" "CONNECTOR, SMT, WIRE-BOARD"
				(at 0 0 0)
				(effects
					(font
						(size 1.27 1.27)
					)
					(hide yes)
				)
			)
			(symbol "I-PEX_CABLINE-VS_1x20_20455-A20E-76_1_1"
				(rectangle
					(start 2.54 2.54)
					(end 7.62 -53.34)
					(stroke
						(width 0.254)
						(type default)
					)
					(fill
						(type background)
					)
				)
				(pin passive line
					(at 0 0 0)
					(length 2.54)
					(name "1"
						(effects
							(font
								(size 1.27 1.27)
							)
						)
					)
					(number "1"
						(effects
							(font
								(size 1.27 1.27)
							)
						)
					)
				)
				(pin passive line
					(at 0 -2.54 0)
					(length 2.54)
					(name "2"
						(effects
							(font
								(size 1.27 1.27)
							)
						)
					)
					(number "2"
						(effects
							(font
								(size 1.27 1.27)
							)
						)
					)
				)
				(pin passive line
					(at 0 -5.08 0)
					(length 2.54)
					(name "3"
						(effects
							(font
								(size 1.27 1.27)
							)
						)
					)
					(number "3"
						(effects
							(font
								(size 1.27 1.27)
							)
						)
					)
				)
				(pin passive line
					(at 0 -7.62 0)
					(length 2.54)
					(name "4"
						(effects
							(font
								(size 1.27 1.27)
							)
						)
					)
					(number "4"
						(effects
							(font
								(size 1.27 1.27)
							)
						)
					)
				)
				(pin passive line
					(at 0 -10.16 0)
					(length 2.54)
					(name "5"
						(effects
							(font
								(size 1.27 1.27)
							)
						)
					)
					(number "5"
						(effects
							(font
								(size 1.27 1.27)
							)
						)
					)
				)
				(pin passive line
					(at 0 -12.7 0)
					(length 2.54)
					(name "6"
						(effects
							(font
								(size 1.27 1.27)
							)
						)
					)
					(number "6"
						(effects
							(font
								(size 1.27 1.27)
							)
						)
					)
				)
				(pin passive line
					(at 0 -15.24 0)
					(length 2.54)
					(name "7"
						(effects
							(font
								(size 1.27 1.27)
							)
						)
					)
					(number "7"
						(effects
							(font
								(size 1.27 1.27)
							)
						)
					)
				)
				(pin passive line
					(at 0 -17.78 0)
					(length 2.54)
					(name "8"
						(effects
							(font
								(size 1.27 1.27)
							)
						)
					)
					(number "8"
						(effects
							(font
								(size 1.27 1.27)
							)
						)
					)
				)
				(pin passive line
					(at 0 -20.32 0)
					(length 2.54)
					(name "9"
						(effects
							(font
								(size 1.27 1.27)
							)
						)
					)
					(number "9"
						(effects
							(font
								(size 1.27 1.27)
							)
						)
					)
				)
				(pin passive line
					(at 0 -22.86 0)
					(length 2.54)
					(name "10"
						(effects
							(font
								(size 1.27 1.27)
							)
						)
					)
					(number "10"
						(effects
							(font
								(size 1.27 1.27)
							)
						)
					)
				)
				(pin passive line
					(at 0 -25.4 0)
					(length 2.54)
					(name "11"
						(effects
							(font
								(size 1.27 1.27)
							)
						)
					)
					(number "11"
						(effects
							(font
								(size 1.27 1.27)
							)
						)
					)
				)
				(pin passive line
					(at 0 -27.94 0)
					(length 2.54)
					(name "12"
						(effects
							(font
								(size 1.27 1.27)
							)
						)
					)
					(number "12"
						(effects
							(font
								(size 1.27 1.27)
							)
						)
					)
				)
				(pin passive line
					(at 0 -30.48 0)
					(length 2.54)
					(name "13"
						(effects
							(font
								(size 1.27 1.27)
							)
						)
					)
					(number "13"
						(effects
							(font
								(size 1.27 1.27)
							)
						)
					)
				)
				(pin passive line
					(at 0 -33.02 0)
					(length 2.54)
					(name "14"
						(effects
							(font
								(size 1.27 1.27)
							)
						)
					)
					(number "14"
						(effects
							(font
								(size 1.27 1.27)
							)
						)
					)
				)
				(pin passive line
					(at 0 -35.56 0)
					(length 2.54)
					(name "15"
						(effects
							(font
								(size 1.27 1.27)
							)
						)
					)
					(number "15"
						(effects
							(font
								(size 1.27 1.27)
							)
						)
					)
				)
				(pin passive line
					(at 0 -38.1 0)
					(length 2.54)
					(name "16"
						(effects
							(font
								(size 1.27 1.27)
							)
						)
					)
					(number "16"
						(effects
							(font
								(size 1.27 1.27)
							)
						)
					)
				)
				(pin passive line
					(at 0 -40.64 0)
					(length 2.54)
					(name "17"
						(effects
							(font
								(size 1.27 1.27)
							)
						)
					)
					(number "17"
						(effects
							(font
								(size 1.27 1.27)
							)
						)
					)
				)
				(pin passive line
					(at 0 -43.18 0)
					(length 2.54)
					(name "18"
						(effects
							(font
								(size 1.27 1.27)
							)
						)
					)
					(number "18"
						(effects
							(font
								(size 1.27 1.27)
							)
						)
					)
				)
				(pin passive line
					(at 0 -45.72 0)
					(length 2.54)
					(name "19"
						(effects
							(font
								(size 1.27 1.27)
							)
						)
					)
					(number "19"
						(effects
							(font
								(size 1.27 1.27)
							)
						)
					)
				)
				(pin passive line
					(at 0 -48.26 0)
					(length 2.54)
					(name "20"
						(effects
							(font
								(size 1.27 1.27)
							)
						)
					)
					(number "20"
						(effects
							(font
								(size 1.27 1.27)
							)
						)
					)
				)
				(pin passive line
					(at 0 -50.8 0)
					(length 2.54)
					(name "SH"
						(effects
							(font
								(size 1.27 1.27)
							)
						)
					)
					(number "SH"
						(effects
							(font
								(size 1.27 1.27)
							)
						)
					)
				)
			)
		)
	(symbol "antmicroWire2BoardConnectors:JST_SH_1x2_BM02B-SRSS-TB-LF-SN"
			(exclude_from_sim no)
			(in_bom yes)
			(on_board yes)
			(property "Reference" "J"
				(at 19.05 -2.54 0)
				(effects
					(font
						(size 1.27 1.27)
						(thickness 0.15)
					)
					(justify left bottom)
				)
			)
			(property "Value" "JST_SH_1x2_BM02B-SRSS-TB-LF-SN"
				(at 19.05 -7.62 0)
				(effects
					(font
						(size 1.27 1.27)
						(thickness 0.15)
					)
					(justify left bottom)
					(hide yes)
				)
			)
			(property "Footprint" "antmicro-footprints:Conn_JST_SH_1x2_BM02B-SRSS-TB-LF-SN"
				(at 19.05 -10.16 0)
				(effects
					(font
						(size 1.27 1.27)
						(thickness 0.15)
					)
					(justify left bottom)
					(hide yes)
				)
			)
			(property "Datasheet" "https://www.jst-mfg.com/product/pdf/eng/eSH.pdf"
				(at 19.05 -12.7 0)
				(effects
					(font
						(size 1.27 1.27)
						(thickness 0.15)
					)
					(justify left bottom)
					(hide yes)
				)
			)
			(property "Description" "Pin Header, Top Entry, Wire-to-Board, 1 mm, 1 Rows, 2 Contacts, Surface Mount, SR"
				(at 0 0 0)
				(effects
					(font
						(size 1.27 1.27)
					)
					(hide yes)
				)
			)
			(property "MPN" "BM02B-SRSS-TB(LF)(SN)"
				(at 19.05 -5.08 0)
				(effects
					(font
						(size 1.27 1.27)
						(thickness 0.15)
					)
					(justify left bottom)
				)
			)
			(property "Manufacturer" "JST Automotive Connectors"
				(at 19.05 -15.24 0)
				(effects
					(font
						(size 1.27 1.27)
						(thickness 0.15)
					)
					(justify left bottom)
					(hide yes)
				)
			)
			(property "Author" "Antmicro"
				(at 19.05 -17.78 0)
				(effects
					(font
						(size 1.27 1.27)
						(thickness 0.15)
					)
					(justify left bottom)
					(hide yes)
				)
			)
			(property "License" "Apache-2.0"
				(at 19.05 -20.32 0)
				(effects
					(font
						(size 1.27 1.27)
						(thickness 0.15)
					)
					(justify left bottom)
					(hide yes)
				)
			)
			(property "ki_keywords" "VERTICAL, SMT, WIRE-BOARD, CONNECTOR"
				(at 0 0 0)
				(effects
					(font
						(size 1.27 1.27)
					)
					(hide yes)
				)
			)
			(symbol "JST_SH_1x2_BM02B-SRSS-TB-LF-SN_1_1"
				(rectangle
					(start 2.54 2.54)
					(end 5.08 -7.62)
					(stroke
						(width 0.254)
						(type default)
					)
					(fill
						(type background)
					)
				)
				(rectangle
					(start 2.54 0.127)
					(end 3.81 -0.127)
					(stroke
						(width 0.254)
						(type default)
					)
					(fill
						(type background)
					)
				)
				(rectangle
					(start 2.54 -2.413)
					(end 3.81 -2.667)
					(stroke
						(width 0.254)
						(type default)
					)
					(fill
						(type background)
					)
				)
				(rectangle
					(start 2.54 -4.953)
					(end 3.81 -5.207)
					(stroke
						(width 0.254)
						(type default)
					)
					(fill
						(type background)
					)
				)
				(pin passive line
					(at 0 0 0)
					(length 2.54)
					(name "~"
						(effects
							(font
								(size 1.27 1.27)
							)
						)
					)
					(number "1"
						(effects
							(font
								(size 1.27 1.27)
							)
						)
					)
				)
				(pin passive line
					(at 0 -2.54 0)
					(length 2.54)
					(name "~"
						(effects
							(font
								(size 1.27 1.27)
							)
						)
					)
					(number "2"
						(effects
							(font
								(size 1.27 1.27)
							)
						)
					)
				)
				(pin passive line
					(at 0 -5.08 0)
					(length 2.54)
					(name "~"
						(effects
							(font
								(size 1.27 1.27)
							)
						)
					)
					(number "MP"
						(effects
							(font
								(size 1.27 1.27)
							)
						)
					)
				)
			)
		)
	(symbol "antmicroWire2BoardConnectors:JST_SH_1x4_BM04B-SRSS-TB-LF-SN"
			(exclude_from_sim no)
			(in_bom yes)
			(on_board yes)
			(property "Reference" "J"
				(at 20.32 -5.08 0)
				(effects
					(font
						(size 1.27 1.27)
						(thickness 0.15)
					)
					(justify left bottom)
				)
			)
			(property "Value" "JST_SH_1x4_BM04B-SRSS-TB-LF-SN"
				(at 20.32 -7.62 0)
				(effects
					(font
						(size 1.27 1.27)
						(thickness 0.15)
					)
					(justify left bottom)
					(hide yes)
				)
			)
			(property "Footprint" "antmicro-footprints:Conn_JST_SH_1x4_BM04B-SRSS-TB-LF-SN"
				(at 20.32 -10.16 0)
				(effects
					(font
						(size 1.27 1.27)
						(thickness 0.15)
					)
					(justify left bottom)
					(hide yes)
				)
			)
			(property "Datasheet" "https://www.jst-mfg.com/product/pdf/eng/eSH.pdf"
				(at 20.32 -12.7 0)
				(effects
					(font
						(size 1.27 1.27)
						(thickness 0.15)
					)
					(justify left bottom)
					(hide yes)
				)
			)
			(property "Description" "Pin Header, Top Entry, Wire-to-Board, 1 mm, 1 Rows, 4 Contacts, Surface Mount, SR"
				(at 0 0 0)
				(effects
					(font
						(size 1.27 1.27)
					)
					(hide yes)
				)
			)
			(property "MPN" "BM04B-SRSS-TB(LF)(SN) "
				(at 20.32 -15.24 0)
				(effects
					(font
						(size 1.27 1.27)
						(thickness 0.15)
					)
					(justify left bottom)
				)
			)
			(property "Manufacturer" "JST Automotive Connectors"
				(at 20.32 -17.78 0)
				(effects
					(font
						(size 1.27 1.27)
						(thickness 0.15)
					)
					(justify left bottom)
					(hide yes)
				)
			)
			(property "Author" "Antmicro"
				(at 20.32 -20.32 0)
				(effects
					(font
						(size 1.27 1.27)
						(thickness 0.15)
					)
					(justify left bottom)
					(hide yes)
				)
			)
			(property "License" "Apache-2.0"
				(at 20.32 -22.86 0)
				(effects
					(font
						(size 1.27 1.27)
						(thickness 0.15)
					)
					(justify left bottom)
					(hide yes)
				)
			)
			(property "ki_keywords" "VERTICAL, SMT, WIRE-BOARD, CONNECTOR"
				(at 0 0 0)
				(effects
					(font
						(size 1.27 1.27)
					)
					(hide yes)
				)
			)
			(symbol "JST_SH_1x4_BM04B-SRSS-TB-LF-SN_1_1"
				(rectangle
					(start 2.54 2.54)
					(end 5.08 -12.7)
					(stroke
						(width 0.254)
						(type default)
					)
					(fill
						(type background)
					)
				)
				(rectangle
					(start 2.54 0.127)
					(end 3.81 -0.127)
					(stroke
						(width 0.254)
						(type default)
					)
					(fill
						(type background)
					)
				)
				(rectangle
					(start 2.54 -2.413)
					(end 3.81 -2.667)
					(stroke
						(width 0.254)
						(type default)
					)
					(fill
						(type background)
					)
				)
				(rectangle
					(start 2.54 -4.953)
					(end 3.81 -5.207)
					(stroke
						(width 0.254)
						(type default)
					)
					(fill
						(type background)
					)
				)
				(rectangle
					(start 2.54 -7.493)
					(end 3.81 -7.747)
					(stroke
						(width 0.254)
						(type default)
					)
					(fill
						(type background)
					)
				)
				(rectangle
					(start 2.54 -10.033)
					(end 3.81 -10.287)
					(stroke
						(width 0.254)
						(type default)
					)
					(fill
						(type background)
					)
				)
				(pin passive line
					(at 0 0 0)
					(length 2.54)
					(name "~"
						(effects
							(font
								(size 1.27 1.27)
							)
						)
					)
					(number "1"
						(effects
							(font
								(size 1.27 1.27)
							)
						)
					)
				)
				(pin passive line
					(at 0 -2.54 0)
					(length 2.54)
					(name "~"
						(effects
							(font
								(size 1.27 1.27)
							)
						)
					)
					(number "2"
						(effects
							(font
								(size 1.27 1.27)
							)
						)
					)
				)
				(pin passive line
					(at 0 -5.08 0)
					(length 2.54)
					(name "~"
						(effects
							(font
								(size 1.27 1.27)
							)
						)
					)
					(number "3"
						(effects
							(font
								(size 1.27 1.27)
							)
						)
					)
				)
				(pin passive line
					(at 0 -7.62 0)
					(length 2.54)
					(name "~"
						(effects
							(font
								(size 1.27 1.27)
							)
						)
					)
					(number "4"
						(effects
							(font
								(size 1.27 1.27)
							)
						)
					)
				)
				(pin passive line
					(at 0 -10.16 0)
					(length 2.54)
					(name "~"
						(effects
							(font
								(size 1.27 1.27)
							)
						)
					)
					(number "MP"
						(effects
							(font
								(size 1.27 1.27)
							)
						)
					)
				)
			)
		)
	(symbol "antmicropower:+0V85"
			(power)
			(pin_names
				(offset 0)
			)
			(exclude_from_sim no)
			(in_bom yes)
			(on_board yes)
			(property "Reference" "#PWR"
				(at 0 -3.81 0)
				(effects
					(font
						(size 1.27 1.27)
					)
					(hide yes)
				)
			)
			(property "Value" "+0V85"
				(at 0 3.556 0)
				(effects
					(font
						(size 1.27 1.27)
					)
				)
			)
			(property "Footprint" ""
				(at 0 0 0)
				(effects
					(font
						(size 1.27 1.27)
					)
					(hide yes)
				)
			)
			(property "Datasheet" ""
				(at 0 0 0)
				(effects
					(font
						(size 1.27 1.27)
					)
					(hide yes)
				)
			)
			(property "Description" ""
				(at 0 0 0)
				(effects
					(font
						(size 1.27 1.27)
					)
					(hide yes)
				)
			)
			(symbol "+0V85_0_1"
				(polyline
					(pts
						(xy -0.762 1.27) (xy 0 2.54)
					)
					(stroke
						(width 0)
						(type default)
					)
					(fill
						(type none)
					)
				)
				(polyline
					(pts
						(xy 0 2.54) (xy 0.762 1.27)
					)
					(stroke
						(width 0)
						(type default)
					)
					(fill
						(type none)
					)
				)
				(polyline
					(pts
						(xy 0 0) (xy 0 2.54)
					)
					(stroke
						(width 0)
						(type default)
					)
					(fill
						(type none)
					)
				)
			)
			(symbol "+0V85_1_1"
				(pin power_in line
					(at 0 0 90)
					(length 0)
					(hide yes)
					(name "+0V85"
						(effects
							(font
								(size 1.27 1.27)
							)
						)
					)
					(number "1"
						(effects
							(font
								(size 1.27 1.27)
							)
						)
					)
				)
			)
		)
	(symbol "antmicropower:+0V9_MGTAVCC"
			(power)
			(pin_names
				(offset 0)
			)
			(exclude_from_sim no)
			(in_bom yes)
			(on_board yes)
			(property "Reference" "#PWR?"
				(at 0 -3.81 0)
				(effects
					(font
						(size 1.27 1.27)
					)
					(hide yes)
				)
			)
			(property "Value" "+0V9_MGTAVCC"
				(at 0 3.81 0)
				(effects
					(font
						(size 1.27 1.27)
					)
				)
			)
			(property "Footprint" ""
				(at 0 0 0)
				(effects
					(font
						(size 1.27 1.27)
					)
					(hide yes)
				)
			)
			(property "Datasheet" ""
				(at 0 0 0)
				(effects
					(font
						(size 1.27 1.27)
					)
					(hide yes)
				)
			)
			(property "Description" ""
				(at 0 0 0)
				(effects
					(font
						(size 1.27 1.27)
					)
					(hide yes)
				)
			)
			(symbol "+0V9_MGTAVCC_0_1"
				(polyline
					(pts
						(xy -0.762 1.27) (xy 0 2.54)
					)
					(stroke
						(width 0)
						(type default)
					)
					(fill
						(type none)
					)
				)
				(polyline
					(pts
						(xy 0 2.54) (xy 0.762 1.27)
					)
					(stroke
						(width 0)
						(type default)
					)
					(fill
						(type none)
					)
				)
				(polyline
					(pts
						(xy 0 0) (xy 0 2.54)
					)
					(stroke
						(width 0)
						(type default)
					)
					(fill
						(type none)
					)
				)
			)
			(symbol "+0V9_MGTAVCC_1_1"
				(pin power_in line
					(at 0 0 90)
					(length 0)
					(hide yes)
					(name "+1V0_MGTAVCC"
						(effects
							(font
								(size 1.27 1.27)
							)
						)
					)
					(number "1"
						(effects
							(font
								(size 1.27 1.27)
							)
						)
					)
				)
			)
		)
	(symbol "antmicropower:+12V"
			(power)
			(pin_names
				(offset 0)
			)
			(exclude_from_sim no)
			(in_bom yes)
			(on_board yes)
			(property "Reference" "#PWR"
				(at 0 -3.81 0)
				(effects
					(font
						(size 1.27 1.27)
					)
					(hide yes)
				)
			)
			(property "Value" "+12V"
				(at 0 3.556 0)
				(effects
					(font
						(size 1.27 1.27)
					)
				)
			)
			(property "Footprint" ""
				(at 0 0 0)
				(effects
					(font
						(size 1.27 1.27)
					)
					(hide yes)
				)
			)
			(property "Datasheet" ""
				(at 0 0 0)
				(effects
					(font
						(size 1.27 1.27)
					)
					(hide yes)
				)
			)
			(property "Description" ""
				(at 0 0 0)
				(effects
					(font
						(size 1.27 1.27)
					)
					(hide yes)
				)
			)
			(symbol "+12V_0_1"
				(polyline
					(pts
						(xy -0.762 1.27) (xy 0 2.54)
					)
					(stroke
						(width 0)
						(type default)
					)
					(fill
						(type none)
					)
				)
				(polyline
					(pts
						(xy 0 2.54) (xy 0.762 1.27)
					)
					(stroke
						(width 0)
						(type default)
					)
					(fill
						(type none)
					)
				)
				(polyline
					(pts
						(xy 0 0) (xy 0 2.54)
					)
					(stroke
						(width 0)
						(type default)
					)
					(fill
						(type none)
					)
				)
			)
			(symbol "+12V_1_1"
				(pin power_in line
					(at 0 0 90)
					(length 0)
					(hide yes)
					(name "+12V"
						(effects
							(font
								(size 1.27 1.27)
							)
						)
					)
					(number "1"
						(effects
							(font
								(size 1.27 1.27)
							)
						)
					)
				)
			)
		)
	(symbol "antmicropower:+1V1"
			(power)
			(pin_names
				(offset 0)
			)
			(exclude_from_sim no)
			(in_bom yes)
			(on_board yes)
			(property "Reference" "#PWR"
				(at 0 -3.81 0)
				(effects
					(font
						(size 1.27 1.27)
					)
					(hide yes)
				)
			)
			(property "Value" "+1V1"
				(at 0 3.556 0)
				(effects
					(font
						(size 1.27 1.27)
					)
				)
			)
			(property "Footprint" ""
				(at 0 0 0)
				(effects
					(font
						(size 1.27 1.27)
					)
					(hide yes)
				)
			)
			(property "Datasheet" ""
				(at 0 0 0)
				(effects
					(font
						(size 1.27 1.27)
					)
					(hide yes)
				)
			)
			(property "Description" ""
				(at 0 0 0)
				(effects
					(font
						(size 1.27 1.27)
					)
					(hide yes)
				)
			)
			(symbol "+1V1_0_1"
				(polyline
					(pts
						(xy -0.762 1.27) (xy 0 2.54)
					)
					(stroke
						(width 0)
						(type default)
					)
					(fill
						(type none)
					)
				)
				(polyline
					(pts
						(xy 0 2.54) (xy 0.762 1.27)
					)
					(stroke
						(width 0)
						(type default)
					)
					(fill
						(type none)
					)
				)
				(polyline
					(pts
						(xy 0 0) (xy 0 2.54)
					)
					(stroke
						(width 0)
						(type default)
					)
					(fill
						(type none)
					)
				)
			)
			(symbol "+1V1_1_1"
				(pin power_in line
					(at 0 0 90)
					(length 0)
					(hide yes)
					(name "+1V1"
						(effects
							(font
								(size 1.27 1.27)
							)
						)
					)
					(number "1"
						(effects
							(font
								(size 1.27 1.27)
							)
						)
					)
				)
			)
		)
	(symbol "antmicropower:+1V2"
			(power)
			(pin_names
				(offset 0)
			)
			(exclude_from_sim no)
			(in_bom yes)
			(on_board yes)
			(property "Reference" "#PWR"
				(at 0 -3.81 0)
				(effects
					(font
						(size 1.27 1.27)
					)
					(hide yes)
				)
			)
			(property "Value" "+1V2"
				(at 0 3.556 0)
				(effects
					(font
						(size 1.27 1.27)
					)
				)
			)
			(property "Footprint" ""
				(at 0 0 0)
				(effects
					(font
						(size 1.27 1.27)
					)
					(hide yes)
				)
			)
			(property "Datasheet" ""
				(at 0 0 0)
				(effects
					(font
						(size 1.27 1.27)
					)
					(hide yes)
				)
			)
			(property "Description" ""
				(at 0 0 0)
				(effects
					(font
						(size 1.27 1.27)
					)
					(hide yes)
				)
			)
			(symbol "+1V2_0_1"
				(polyline
					(pts
						(xy -0.762 1.27) (xy 0 2.54)
					)
					(stroke
						(width 0)
						(type default)
					)
					(fill
						(type none)
					)
				)
				(polyline
					(pts
						(xy 0 2.54) (xy 0.762 1.27)
					)
					(stroke
						(width 0)
						(type default)
					)
					(fill
						(type none)
					)
				)
				(polyline
					(pts
						(xy 0 0) (xy 0 2.54)
					)
					(stroke
						(width 0)
						(type default)
					)
					(fill
						(type none)
					)
				)
			)
			(symbol "+1V2_1_1"
				(pin power_in line
					(at 0 0 90)
					(length 0)
					(hide yes)
					(name "+1V2"
						(effects
							(font
								(size 1.27 1.27)
							)
						)
					)
					(number "1"
						(effects
							(font
								(size 1.27 1.27)
							)
						)
					)
				)
			)
		)
	(symbol "antmicropower:+1V2_MGTAVTT"
			(power)
			(pin_names
				(offset 0)
			)
			(exclude_from_sim no)
			(in_bom yes)
			(on_board yes)
			(property "Reference" "#PWR?"
				(at 0 -3.81 0)
				(effects
					(font
						(size 1.27 1.27)
					)
					(hide yes)
				)
			)
			(property "Value" "+1V2_MGTAVTT"
				(at 0 3.81 0)
				(effects
					(font
						(size 1.27 1.27)
					)
				)
			)
			(property "Footprint" ""
				(at 0 0 0)
				(effects
					(font
						(size 1.27 1.27)
					)
					(hide yes)
				)
			)
			(property "Datasheet" ""
				(at 0 0 0)
				(effects
					(font
						(size 1.27 1.27)
					)
					(hide yes)
				)
			)
			(property "Description" ""
				(at 0 0 0)
				(effects
					(font
						(size 1.27 1.27)
					)
					(hide yes)
				)
			)
			(symbol "+1V2_MGTAVTT_0_1"
				(polyline
					(pts
						(xy -0.762 1.27) (xy 0 2.54)
					)
					(stroke
						(width 0)
						(type default)
					)
					(fill
						(type none)
					)
				)
				(polyline
					(pts
						(xy 0 2.54) (xy 0.762 1.27)
					)
					(stroke
						(width 0)
						(type default)
					)
					(fill
						(type none)
					)
				)
				(polyline
					(pts
						(xy 0 0) (xy 0 2.54)
					)
					(stroke
						(width 0)
						(type default)
					)
					(fill
						(type none)
					)
				)
			)
			(symbol "+1V2_MGTAVTT_1_1"
				(pin power_in line
					(at 0 0 90)
					(length 0)
					(hide yes)
					(name "+1V2_MGTAVTT"
						(effects
							(font
								(size 1.27 1.27)
							)
						)
					)
					(number "1"
						(effects
							(font
								(size 1.27 1.27)
							)
						)
					)
				)
			)
		)
	(symbol "antmicropower:+1V8"
			(power)
			(pin_numbers
				(hide yes)
			)
			(pin_names
				(hide yes)
			)
			(exclude_from_sim no)
			(in_bom yes)
			(on_board yes)
			(property "Reference" "#PWR"
				(at 15.24 -2.54 0)
				(effects
					(font
						(size 1.27 1.27)
						(thickness 0.15)
					)
					(justify left bottom)
					(hide yes)
				)
			)
			(property "Value" "+1V8"
				(at -3.175 2.54 0)
				(effects
					(font
						(size 1.27 1.27)
						(thickness 0.15)
					)
					(justify left bottom)
				)
			)
			(property "Footprint" ""
				(at 15.24 -7.62 0)
				(effects
					(font
						(size 1.27 1.27)
						(thickness 0.15)
					)
					(justify left bottom)
					(hide yes)
				)
			)
			(property "Datasheet" ""
				(at 15.24 -10.16 0)
				(effects
					(font
						(size 1.27 1.27)
						(thickness 0.15)
					)
					(justify left bottom)
					(hide yes)
				)
			)
			(property "Description" ""
				(at 0 0 0)
				(effects
					(font
						(size 1.27 1.27)
					)
					(hide yes)
				)
			)
			(property "Author" "Antmicro"
				(at 15.24 -5.08 0)
				(effects
					(font
						(size 1.27 1.27)
						(thickness 0.15)
					)
					(justify left bottom)
					(hide yes)
				)
			)
			(property "License" "Apache-2.0"
				(at 15.24 -7.62 0)
				(effects
					(font
						(size 1.27 1.27)
						(thickness 0.15)
					)
					(justify left bottom)
					(hide yes)
				)
			)
			(symbol "+1V8_1_1"
				(polyline
					(pts
						(xy -0.762 1.27) (xy 0 2.54)
					)
					(stroke
						(width 0)
						(type default)
					)
					(fill
						(type background)
					)
				)
				(polyline
					(pts
						(xy 0 2.54) (xy 0.762 1.27)
					)
					(stroke
						(width 0)
						(type default)
					)
					(fill
						(type background)
					)
				)
				(polyline
					(pts
						(xy 0 0) (xy 0 2.54)
					)
					(stroke
						(width 0)
						(type default)
					)
					(fill
						(type background)
					)
				)
				(pin power_in line
					(at 0 0 90)
					(length 0)
					(hide yes)
					(name "+1V8"
						(effects
							(font
								(size 1.27 1.27)
							)
						)
					)
					(number "1"
						(effects
							(font
								(size 1.27 1.27)
							)
						)
					)
				)
			)
		)
	(symbol "antmicropower:+1V8_MGTVCCAUX"
			(power)
			(pin_names
				(offset 0)
			)
			(exclude_from_sim no)
			(in_bom yes)
			(on_board yes)
			(property "Reference" "#PWR?"
				(at 0 -3.81 0)
				(effects
					(font
						(size 1.27 1.27)
					)
					(hide yes)
				)
			)
			(property "Value" "+1V8_MGTVCCAUX"
				(at 0 3.81 0)
				(effects
					(font
						(size 1.27 1.27)
					)
				)
			)
			(property "Footprint" ""
				(at 0 0 0)
				(effects
					(font
						(size 1.27 1.27)
					)
					(hide yes)
				)
			)
			(property "Datasheet" ""
				(at 0 0 0)
				(effects
					(font
						(size 1.27 1.27)
					)
					(hide yes)
				)
			)
			(property "Description" ""
				(at 0 0 0)
				(effects
					(font
						(size 1.27 1.27)
					)
					(hide yes)
				)
			)
			(symbol "+1V8_MGTVCCAUX_0_1"
				(polyline
					(pts
						(xy -0.762 1.27) (xy 0 2.54)
					)
					(stroke
						(width 0)
						(type default)
					)
					(fill
						(type none)
					)
				)
				(polyline
					(pts
						(xy 0 2.54) (xy 0.762 1.27)
					)
					(stroke
						(width 0)
						(type default)
					)
					(fill
						(type none)
					)
				)
				(polyline
					(pts
						(xy 0 0) (xy 0 2.54)
					)
					(stroke
						(width 0)
						(type default)
					)
					(fill
						(type none)
					)
				)
			)
			(symbol "+1V8_MGTVCCAUX_1_1"
				(pin power_in line
					(at 0 0 90)
					(length 0)
					(hide yes)
					(name "+1V8_MGTVCCAUX"
						(effects
							(font
								(size 1.27 1.27)
							)
						)
					)
					(number "1"
						(effects
							(font
								(size 1.27 1.27)
							)
						)
					)
				)
			)
		)
	(symbol "antmicropower:+3V3"
			(power)
			(pin_numbers
				(hide yes)
			)
			(pin_names
				(hide yes)
			)
			(exclude_from_sim no)
			(in_bom yes)
			(on_board yes)
			(property "Reference" "#PWR"
				(at 15.24 0 0)
				(effects
					(font
						(size 1.27 1.27)
						(thickness 0.15)
					)
					(justify left bottom)
					(hide yes)
				)
			)
			(property "Value" "+3V3"
				(at -3.175 2.54 0)
				(effects
					(font
						(size 1.27 1.27)
						(thickness 0.15)
					)
					(justify left bottom)
				)
			)
			(property "Footprint" ""
				(at 15.24 -7.62 0)
				(effects
					(font
						(size 1.27 1.27)
						(thickness 0.15)
					)
					(justify left bottom)
					(hide yes)
				)
			)
			(property "Datasheet" ""
				(at 15.24 -10.16 0)
				(effects
					(font
						(size 1.27 1.27)
						(thickness 0.15)
					)
					(justify left bottom)
					(hide yes)
				)
			)
			(property "Description" ""
				(at 0 0 0)
				(effects
					(font
						(size 1.27 1.27)
					)
					(hide yes)
				)
			)
			(property "Author" "Antmicro"
				(at 15.24 -2.54 0)
				(effects
					(font
						(size 1.27 1.27)
						(thickness 0.15)
					)
					(justify left bottom)
					(hide yes)
				)
			)
			(property "License" "Apache-2.0"
				(at 15.24 -5.08 0)
				(effects
					(font
						(size 1.27 1.27)
						(thickness 0.15)
					)
					(justify left bottom)
					(hide yes)
				)
			)
			(symbol "+3V3_0_1"
				(polyline
					(pts
						(xy 0 2.54) (xy -0.762 1.27)
					)
					(stroke
						(width 0)
						(type default)
					)
					(fill
						(type none)
					)
				)
				(polyline
					(pts
						(xy 0 2.54) (xy 0.762 1.27)
					)
					(stroke
						(width 0)
						(type default)
					)
					(fill
						(type none)
					)
				)
				(polyline
					(pts
						(xy 0 0) (xy 0 2.54)
					)
					(stroke
						(width 0)
						(type default)
					)
					(fill
						(type none)
					)
				)
			)
			(symbol "+3V3_1_1"
				(pin power_in line
					(at 0 0 90)
					(length 0)
					(hide yes)
					(name "+3V3"
						(effects
							(font
								(size 1.27 1.27)
							)
						)
					)
					(number "1"
						(effects
							(font
								(size 1.27 1.27)
							)
						)
					)
				)
			)
		)
	(symbol "antmicropower:+3V3_AON"
			(power)
			(pin_names
				(offset 0)
			)
			(exclude_from_sim no)
			(in_bom yes)
			(on_board yes)
			(property "Reference" "#PWR"
				(at 0 -3.81 0)
				(effects
					(font
						(size 1.27 1.27)
					)
					(hide yes)
				)
			)
			(property "Value" "+3V3_AON"
				(at 0 3.556 0)
				(effects
					(font
						(size 1.27 1.27)
					)
				)
			)
			(property "Footprint" ""
				(at 0 0 0)
				(effects
					(font
						(size 1.27 1.27)
					)
					(hide yes)
				)
			)
			(property "Datasheet" ""
				(at 0 0 0)
				(effects
					(font
						(size 1.27 1.27)
					)
					(hide yes)
				)
			)
			(property "Description" ""
				(at 0 0 0)
				(effects
					(font
						(size 1.27 1.27)
					)
					(hide yes)
				)
			)
			(symbol "+3V3_AON_0_1"
				(polyline
					(pts
						(xy -0.762 1.27) (xy 0 2.54)
					)
					(stroke
						(width 0)
						(type default)
					)
					(fill
						(type none)
					)
				)
				(polyline
					(pts
						(xy 0 2.54) (xy 0.762 1.27)
					)
					(stroke
						(width 0)
						(type default)
					)
					(fill
						(type none)
					)
				)
				(polyline
					(pts
						(xy 0 0) (xy 0 2.54)
					)
					(stroke
						(width 0)
						(type default)
					)
					(fill
						(type none)
					)
				)
			)
			(symbol "+3V3_AON_1_1"
				(pin power_in line
					(at 0 0 90)
					(length 0)
					(hide yes)
					(name "+3V3_AON"
						(effects
							(font
								(size 1.27 1.27)
							)
						)
					)
					(number "1"
						(effects
							(font
								(size 1.27 1.27)
							)
						)
					)
				)
			)
		)
	(symbol "antmicropower:+5V"
			(power)
			(pin_numbers
				(hide yes)
			)
			(pin_names
				(hide yes)
			)
			(exclude_from_sim no)
			(in_bom yes)
			(on_board yes)
			(property "Reference" "#PWR"
				(at 15.24 -2.54 0)
				(effects
					(font
						(size 1.27 1.27)
						(thickness 0.15)
					)
					(justify left bottom)
					(hide yes)
				)
			)
			(property "Value" "+5V"
				(at 15.24 -5.08 0)
				(effects
					(font
						(size 1.27 1.27)
						(thickness 0.15)
					)
					(justify left bottom)
				)
			)
			(property "Footprint" ""
				(at 15.24 -7.62 0)
				(effects
					(font
						(size 1.27 1.27)
						(thickness 0.15)
					)
					(justify left bottom)
					(hide yes)
				)
			)
			(property "Datasheet" ""
				(at 15.24 -10.16 0)
				(effects
					(font
						(size 1.27 1.27)
						(thickness 0.15)
					)
					(justify left bottom)
					(hide yes)
				)
			)
			(property "Description" ""
				(at 0 0 0)
				(effects
					(font
						(size 1.27 1.27)
					)
					(hide yes)
				)
			)
			(property "Author" "Antmicro"
				(at 15.24 -7.62 0)
				(effects
					(font
						(size 1.27 1.27)
						(thickness 0.15)
					)
					(justify left bottom)
					(hide yes)
				)
			)
			(property "License" "Apache-2.0"
				(at 15.24 -10.16 0)
				(effects
					(font
						(size 1.27 1.27)
						(thickness 0.15)
					)
					(justify left bottom)
					(hide yes)
				)
			)
			(symbol "+5V_1_1"
				(polyline
					(pts
						(xy -0.762 1.27) (xy 0 2.54)
					)
					(stroke
						(width 0)
						(type default)
					)
					(fill
						(type background)
					)
				)
				(polyline
					(pts
						(xy 0 2.54) (xy 0.762 1.27)
					)
					(stroke
						(width 0)
						(type default)
					)
					(fill
						(type background)
					)
				)
				(polyline
					(pts
						(xy 0 0) (xy 0 2.54)
					)
					(stroke
						(width 0)
						(type default)
					)
					(fill
						(type background)
					)
				)
				(pin power_in line
					(at 0 0 90)
					(length 0)
					(name "+5V"
						(effects
							(font
								(size 1.27 1.27)
							)
						)
					)
					(number "1"
						(effects
							(font
								(size 1.27 1.27)
							)
						)
					)
				)
			)
		)
	(symbol "antmicropower:GND"
			(power)
			(pin_numbers
				(hide yes)
			)
			(pin_names
				(hide yes)
			)
			(exclude_from_sim no)
			(in_bom yes)
			(on_board yes)
			(property "Reference" "#PWR"
				(at 8.89 -2.54 0)
				(effects
					(font
						(size 1.27 1.27)
						(thickness 0.15)
					)
					(justify left bottom)
					(hide yes)
				)
			)
			(property "Value" "GND"
				(at 8.89 -5.08 0)
				(effects
					(font
						(size 1.27 1.27)
						(thickness 0.15)
					)
					(justify left bottom)
				)
			)
			(property "Footprint" ""
				(at 8.89 -7.62 0)
				(effects
					(font
						(size 1.27 1.27)
						(thickness 0.15)
					)
					(justify left bottom)
					(hide yes)
				)
			)
			(property "Datasheet" ""
				(at 8.89 -12.7 0)
				(effects
					(font
						(size 1.27 1.27)
						(thickness 0.15)
					)
					(justify left bottom)
					(hide yes)
				)
			)
			(property "Description" ""
				(at 0 0 0)
				(effects
					(font
						(size 1.27 1.27)
					)
					(hide yes)
				)
			)
			(property "Author" "Antmicro"
				(at 8.89 -7.62 0)
				(effects
					(font
						(size 1.27 1.27)
						(thickness 0.15)
					)
					(justify left bottom)
					(hide yes)
				)
			)
			(property "License" "Apache-2.0"
				(at 8.89 -10.16 0)
				(effects
					(font
						(size 1.27 1.27)
						(thickness 0.15)
					)
					(justify left bottom)
					(hide yes)
				)
			)
			(symbol "GND_1_1"
				(polyline
					(pts
						(xy 0 0) (xy 0 -1.27) (xy 1.27 -1.27) (xy 0 -2.54) (xy -1.27 -1.27) (xy 0 -1.27)
					)
					(stroke
						(width 0)
						(type default)
					)
					(fill
						(type none)
					)
				)
				(pin power_in line
					(at 0 0 270)
					(length 0)
					(name "GND"
						(effects
							(font
								(size 1.27 1.27)
							)
						)
					)
					(number "1"
						(effects
							(font
								(size 1.27 1.27)
							)
						)
					)
				)
			)
		)
	(symbol "antmicropower:PWR_FLAG"
			(power)
			(pin_numbers
				(hide yes)
			)
			(pin_names
				(offset 0)
				(hide yes)
			)
			(exclude_from_sim no)
			(in_bom yes)
			(on_board yes)
			(property "Reference" "#FLG"
				(at 0 1.905 0)
				(effects
					(font
						(size 1.27 1.27)
					)
					(hide yes)
				)
			)
			(property "Value" "PWR_FLAG"
				(at 0 3.81 0)
				(effects
					(font
						(size 1.27 1.27)
					)
				)
			)
			(property "Footprint" ""
				(at 0 0 0)
				(effects
					(font
						(size 1.27 1.27)
					)
					(hide yes)
				)
			)
			(property "Datasheet" ""
				(at 0 0 0)
				(effects
					(font
						(size 1.27 1.27)
					)
					(hide yes)
				)
			)
			(property "Description" ""
				(at 0 0 0)
				(effects
					(font
						(size 1.27 1.27)
					)
					(hide yes)
				)
			)
			(symbol "PWR_FLAG_0_0"
				(pin power_out line
					(at 0 0 90)
					(length 0)
					(name "pwr"
						(effects
							(font
								(size 1.27 1.27)
							)
						)
					)
					(number "1"
						(effects
							(font
								(size 1.27 1.27)
							)
						)
					)
				)
			)
			(symbol "PWR_FLAG_0_1"
				(polyline
					(pts
						(xy 0 0) (xy 0 1.27) (xy -1.016 1.905) (xy 0 2.54) (xy 1.016 1.905) (xy 0 1.27)
					)
					(stroke
						(width 0)
						(type default)
					)
					(fill
						(type none)
					)
				)
			)
		)
	(symbol "antmicropower:VDC"
			(power)
			(pin_names
				(offset 0)
			)
			(exclude_from_sim no)
			(in_bom yes)
			(on_board yes)
			(property "Reference" "#PWR"
				(at 0 -2.54 0)
				(effects
					(font
						(size 1.27 1.27)
					)
					(hide yes)
				)
			)
			(property "Value" "VDC"
				(at 0 6.35 0)
				(effects
					(font
						(size 1.27 1.27)
					)
				)
			)
			(property "Footprint" ""
				(at 0 0 0)
				(effects
					(font
						(size 1.27 1.27)
					)
					(hide yes)
				)
			)
			(property "Datasheet" ""
				(at 0 0 0)
				(effects
					(font
						(size 1.27 1.27)
					)
					(hide yes)
				)
			)
			(property "Description" ""
				(at 0 0 0)
				(effects
					(font
						(size 1.27 1.27)
					)
					(hide yes)
				)
			)
			(symbol "VDC_0_1"
				(polyline
					(pts
						(xy -0.762 1.27) (xy 0 2.54)
					)
					(stroke
						(width 0)
						(type default)
					)
					(fill
						(type none)
					)
				)
				(polyline
					(pts
						(xy 0 2.54) (xy 0.762 1.27)
					)
					(stroke
						(width 0)
						(type default)
					)
					(fill
						(type none)
					)
				)
				(polyline
					(pts
						(xy 0 0) (xy 0 2.54)
					)
					(stroke
						(width 0)
						(type default)
					)
					(fill
						(type none)
					)
				)
			)
			(symbol "VDC_1_1"
				(pin power_in line
					(at 0 0 90)
					(length 0)
					(hide yes)
					(name "VDC"
						(effects
							(font
								(size 1.27 1.27)
							)
						)
					)
					(number "1"
						(effects
							(font
								(size 1.27 1.27)
							)
						)
					)
				)
			)
		)
	(symbol "antmicropower:VDD"
			(power)
			(pin_names
				(offset 0)
			)
			(exclude_from_sim no)
			(in_bom yes)
			(on_board yes)
			(property "Reference" "#PWR"
				(at 0 -3.81 0)
				(effects
					(font
						(size 1.27 1.27)
					)
					(hide yes)
				)
			)
			(property "Value" "VDD"
				(at 0 3.81 0)
				(effects
					(font
						(size 1.27 1.27)
					)
				)
			)
			(property "Footprint" ""
				(at 0 0 0)
				(effects
					(font
						(size 1.27 1.27)
					)
					(hide yes)
				)
			)
			(property "Datasheet" ""
				(at 0 0 0)
				(effects
					(font
						(size 1.27 1.27)
					)
					(hide yes)
				)
			)
			(property "Description" ""
				(at 0 0 0)
				(effects
					(font
						(size 1.27 1.27)
					)
					(hide yes)
				)
			)
			(symbol "VDD_0_1"
				(polyline
					(pts
						(xy -0.762 1.27) (xy 0 2.54)
					)
					(stroke
						(width 0)
						(type default)
					)
					(fill
						(type none)
					)
				)
				(polyline
					(pts
						(xy 0 2.54) (xy 0.762 1.27)
					)
					(stroke
						(width 0)
						(type default)
					)
					(fill
						(type none)
					)
				)
				(polyline
					(pts
						(xy 0 0) (xy 0 2.54)
					)
					(stroke
						(width 0)
						(type default)
					)
					(fill
						(type none)
					)
				)
			)
			(symbol "VDD_1_1"
				(pin power_in line
					(at 0 0 90)
					(length 0)
					(hide yes)
					(name "VDD"
						(effects
							(font
								(size 1.27 1.27)
							)
						)
					)
					(number "1"
						(effects
							(font
								(size 1.27 1.27)
							)
						)
					)
				)
			)
		)
	(symbol "data-center-rdimm-ddr5-tester:GND_10"
			(power)
			(pin_names
				(offset 0)
			)
			(exclude_from_sim no)
			(in_bom yes)
			(on_board yes)
			(property "Reference" "#PWR"
				(at 0 -6.35 0)
				(effects
					(font
						(size 1.27 1.27)
					)
					(hide yes)
				)
			)
			(property "Value" "GND_10"
				(at 0 -3.81 0)
				(effects
					(font
						(size 1.27 1.27)
					)
				)
			)
			(property "Footprint" ""
				(at 0 0 0)
				(effects
					(font
						(size 1.27 1.27)
					)
					(hide yes)
				)
			)
			(property "Datasheet" ""
				(at 0 0 0)
				(effects
					(font
						(size 1.27 1.27)
					)
					(hide yes)
				)
			)
			(property "Description" ""
				(at 0 0 0)
				(effects
					(font
						(size 1.27 1.27)
					)
					(hide yes)
				)
			)
			(symbol "GND_10_0_1"
				(polyline
					(pts
						(xy 0 0) (xy 0 -1.27) (xy 1.27 -1.27) (xy 0 -2.54) (xy -1.27 -1.27) (xy 0 -1.27)
					)
					(stroke
						(width 0)
						(type default)
					)
					(fill
						(type none)
					)
				)
			)
			(symbol "GND_10_1_1"
				(pin power_in line
					(at 0 0 270)
					(length 0)
					(hide yes)
					(name "GND"
						(effects
							(font
								(size 1.27 1.27)
							)
						)
					)
					(number "1"
						(effects
							(font
								(size 1.27 1.27)
							)
						)
					)
				)
			)
		)
	(symbol "data-center-rdimm-ddr5-tester:GND_11"
			(power)
			(pin_names
				(offset 0)
			)
			(exclude_from_sim no)
			(in_bom yes)
			(on_board yes)
			(property "Reference" "#PWR"
				(at 0 -6.35 0)
				(effects
					(font
						(size 1.27 1.27)
					)
					(hide yes)
				)
			)
			(property "Value" "GND_11"
				(at 0 -3.81 0)
				(effects
					(font
						(size 1.27 1.27)
					)
				)
			)
			(property "Footprint" ""
				(at 0 0 0)
				(effects
					(font
						(size 1.27 1.27)
					)
					(hide yes)
				)
			)
			(property "Datasheet" ""
				(at 0 0 0)
				(effects
					(font
						(size 1.27 1.27)
					)
					(hide yes)
				)
			)
			(property "Description" ""
				(at 0 0 0)
				(effects
					(font
						(size 1.27 1.27)
					)
					(hide yes)
				)
			)
			(symbol "GND_11_0_1"
				(polyline
					(pts
						(xy 0 0) (xy 0 -1.27) (xy 1.27 -1.27) (xy 0 -2.54) (xy -1.27 -1.27) (xy 0 -1.27)
					)
					(stroke
						(width 0)
						(type default)
					)
					(fill
						(type none)
					)
				)
			)
			(symbol "GND_11_1_1"
				(pin power_in line
					(at 0 0 270)
					(length 0)
					(hide yes)
					(name "GND"
						(effects
							(font
								(size 1.27 1.27)
							)
						)
					)
					(number "1"
						(effects
							(font
								(size 1.27 1.27)
							)
						)
					)
				)
			)
		)
	(symbol "data-center-rdimm-ddr5-tester:GND_12"
			(power)
			(pin_names
				(offset 0)
			)
			(exclude_from_sim no)
			(in_bom yes)
			(on_board yes)
			(property "Reference" "#PWR"
				(at 0 -6.35 0)
				(effects
					(font
						(size 1.27 1.27)
					)
					(hide yes)
				)
			)
			(property "Value" "GND_12"
				(at 0 -3.81 0)
				(effects
					(font
						(size 1.27 1.27)
					)
				)
			)
			(property "Footprint" ""
				(at 0 0 0)
				(effects
					(font
						(size 1.27 1.27)
					)
					(hide yes)
				)
			)
			(property "Datasheet" ""
				(at 0 0 0)
				(effects
					(font
						(size 1.27 1.27)
					)
					(hide yes)
				)
			)
			(property "Description" ""
				(at 0 0 0)
				(effects
					(font
						(size 1.27 1.27)
					)
					(hide yes)
				)
			)
			(symbol "GND_12_0_1"
				(polyline
					(pts
						(xy 0 0) (xy 0 -1.27) (xy 1.27 -1.27) (xy 0 -2.54) (xy -1.27 -1.27) (xy 0 -1.27)
					)
					(stroke
						(width 0)
						(type default)
					)
					(fill
						(type none)
					)
				)
			)
			(symbol "GND_12_1_1"
				(pin power_in line
					(at 0 0 270)
					(length 0)
					(hide yes)
					(name "GND"
						(effects
							(font
								(size 1.27 1.27)
							)
						)
					)
					(number "1"
						(effects
							(font
								(size 1.27 1.27)
							)
						)
					)
				)
			)
		)
	(symbol "data-center-rdimm-ddr5-tester:GND_13"
			(power)
			(pin_names
				(offset 0)
			)
			(exclude_from_sim no)
			(in_bom yes)
			(on_board yes)
			(property "Reference" "#PWR"
				(at 0 -6.35 0)
				(effects
					(font
						(size 1.27 1.27)
					)
					(hide yes)
				)
			)
			(property "Value" "GND_13"
				(at 0 -3.81 0)
				(effects
					(font
						(size 1.27 1.27)
					)
				)
			)
			(property "Footprint" ""
				(at 0 0 0)
				(effects
					(font
						(size 1.27 1.27)
					)
					(hide yes)
				)
			)
			(property "Datasheet" ""
				(at 0 0 0)
				(effects
					(font
						(size 1.27 1.27)
					)
					(hide yes)
				)
			)
			(property "Description" ""
				(at 0 0 0)
				(effects
					(font
						(size 1.27 1.27)
					)
					(hide yes)
				)
			)
			(symbol "GND_13_0_1"
				(polyline
					(pts
						(xy 0 0) (xy 0 -1.27) (xy 1.27 -1.27) (xy 0 -2.54) (xy -1.27 -1.27) (xy 0 -1.27)
					)
					(stroke
						(width 0)
						(type default)
					)
					(fill
						(type none)
					)
				)
			)
			(symbol "GND_13_1_1"
				(pin power_in line
					(at 0 0 270)
					(length 0)
					(hide yes)
					(name "GND"
						(effects
							(font
								(size 1.27 1.27)
							)
						)
					)
					(number "1"
						(effects
							(font
								(size 1.27 1.27)
							)
						)
					)
				)
			)
		)
	(symbol "data-center-rdimm-ddr5-tester:GND_14"
			(power)
			(pin_names
				(offset 0)
			)
			(exclude_from_sim no)
			(in_bom yes)
			(on_board yes)
			(property "Reference" "#PWR"
				(at 0 -6.35 0)
				(effects
					(font
						(size 1.27 1.27)
					)
					(hide yes)
				)
			)
			(property "Value" "GND_14"
				(at 0 -3.81 0)
				(effects
					(font
						(size 1.27 1.27)
					)
				)
			)
			(property "Footprint" ""
				(at 0 0 0)
				(effects
					(font
						(size 1.27 1.27)
					)
					(hide yes)
				)
			)
			(property "Datasheet" ""
				(at 0 0 0)
				(effects
					(font
						(size 1.27 1.27)
					)
					(hide yes)
				)
			)
			(property "Description" ""
				(at 0 0 0)
				(effects
					(font
						(size 1.27 1.27)
					)
					(hide yes)
				)
			)
			(symbol "GND_14_0_1"
				(polyline
					(pts
						(xy 0 0) (xy 0 -1.27) (xy 1.27 -1.27) (xy 0 -2.54) (xy -1.27 -1.27) (xy 0 -1.27)
					)
					(stroke
						(width 0)
						(type default)
					)
					(fill
						(type none)
					)
				)
			)
			(symbol "GND_14_1_1"
				(pin power_in line
					(at 0 0 270)
					(length 0)
					(hide yes)
					(name "GND"
						(effects
							(font
								(size 1.27 1.27)
							)
						)
					)
					(number "1"
						(effects
							(font
								(size 1.27 1.27)
							)
						)
					)
				)
			)
		)
	(symbol "data-center-rdimm-ddr5-tester:GND_15"
			(power)
			(pin_names
				(offset 0)
			)
			(exclude_from_sim no)
			(in_bom yes)
			(on_board yes)
			(property "Reference" "#PWR"
				(at 0 -6.35 0)
				(effects
					(font
						(size 1.27 1.27)
					)
					(hide yes)
				)
			)
			(property "Value" "GND_15"
				(at 0 -3.81 0)
				(effects
					(font
						(size 1.27 1.27)
					)
				)
			)
			(property "Footprint" ""
				(at 0 0 0)
				(effects
					(font
						(size 1.27 1.27)
					)
					(hide yes)
				)
			)
			(property "Datasheet" ""
				(at 0 0 0)
				(effects
					(font
						(size 1.27 1.27)
					)
					(hide yes)
				)
			)
			(property "Description" ""
				(at 0 0 0)
				(effects
					(font
						(size 1.27 1.27)
					)
					(hide yes)
				)
			)
			(symbol "GND_15_0_1"
				(polyline
					(pts
						(xy 0 0) (xy 0 -1.27) (xy 1.27 -1.27) (xy 0 -2.54) (xy -1.27 -1.27) (xy 0 -1.27)
					)
					(stroke
						(width 0)
						(type default)
					)
					(fill
						(type none)
					)
				)
			)
			(symbol "GND_15_1_1"
				(pin power_in line
					(at 0 0 270)
					(length 0)
					(hide yes)
					(name "GND"
						(effects
							(font
								(size 1.27 1.27)
							)
						)
					)
					(number "1"
						(effects
							(font
								(size 1.27 1.27)
							)
						)
					)
				)
			)
		)
	(symbol "data-center-rdimm-ddr5-tester:GND_16"
			(power)
			(pin_names
				(offset 0)
			)
			(exclude_from_sim no)
			(in_bom yes)
			(on_board yes)
			(property "Reference" "#PWR"
				(at 0 -6.35 0)
				(effects
					(font
						(size 1.27 1.27)
					)
					(hide yes)
				)
			)
			(property "Value" "GND_16"
				(at 0 -3.81 0)
				(effects
					(font
						(size 1.27 1.27)
					)
				)
			)
			(property "Footprint" ""
				(at 0 0 0)
				(effects
					(font
						(size 1.27 1.27)
					)
					(hide yes)
				)
			)
			(property "Datasheet" ""
				(at 0 0 0)
				(effects
					(font
						(size 1.27 1.27)
					)
					(hide yes)
				)
			)
			(property "Description" ""
				(at 0 0 0)
				(effects
					(font
						(size 1.27 1.27)
					)
					(hide yes)
				)
			)
			(symbol "GND_16_0_1"
				(polyline
					(pts
						(xy 0 0) (xy 0 -1.27) (xy 1.27 -1.27) (xy 0 -2.54) (xy -1.27 -1.27) (xy 0 -1.27)
					)
					(stroke
						(width 0)
						(type default)
					)
					(fill
						(type none)
					)
				)
			)
			(symbol "GND_16_1_1"
				(pin power_in line
					(at 0 0 270)
					(length 0)
					(hide yes)
					(name "GND"
						(effects
							(font
								(size 1.27 1.27)
							)
						)
					)
					(number "1"
						(effects
							(font
								(size 1.27 1.27)
							)
						)
					)
				)
			)
		)
	(symbol "data-center-rdimm-ddr5-tester:GND_17"
			(power)
			(pin_names
				(offset 0)
			)
			(exclude_from_sim no)
			(in_bom yes)
			(on_board yes)
			(property "Reference" "#PWR"
				(at 0 -6.35 0)
				(effects
					(font
						(size 1.27 1.27)
					)
					(hide yes)
				)
			)
			(property "Value" "GND_17"
				(at 0 -3.81 0)
				(effects
					(font
						(size 1.27 1.27)
					)
				)
			)
			(property "Footprint" ""
				(at 0 0 0)
				(effects
					(font
						(size 1.27 1.27)
					)
					(hide yes)
				)
			)
			(property "Datasheet" ""
				(at 0 0 0)
				(effects
					(font
						(size 1.27 1.27)
					)
					(hide yes)
				)
			)
			(property "Description" ""
				(at 0 0 0)
				(effects
					(font
						(size 1.27 1.27)
					)
					(hide yes)
				)
			)
			(symbol "GND_17_0_1"
				(polyline
					(pts
						(xy 0 0) (xy 0 -1.27) (xy 1.27 -1.27) (xy 0 -2.54) (xy -1.27 -1.27) (xy 0 -1.27)
					)
					(stroke
						(width 0)
						(type default)
					)
					(fill
						(type none)
					)
				)
			)
			(symbol "GND_17_1_1"
				(pin power_in line
					(at 0 0 270)
					(length 0)
					(hide yes)
					(name "GND"
						(effects
							(font
								(size 1.27 1.27)
							)
						)
					)
					(number "1"
						(effects
							(font
								(size 1.27 1.27)
							)
						)
					)
				)
			)
		)
	(symbol "data-center-rdimm-ddr5-tester:GND_18"
			(power)
			(pin_names
				(offset 0)
			)
			(exclude_from_sim no)
			(in_bom yes)
			(on_board yes)
			(property "Reference" "#PWR"
				(at 0 -6.35 0)
				(effects
					(font
						(size 1.27 1.27)
					)
					(hide yes)
				)
			)
			(property "Value" "GND_18"
				(at 0 -3.81 0)
				(effects
					(font
						(size 1.27 1.27)
					)
				)
			)
			(property "Footprint" ""
				(at 0 0 0)
				(effects
					(font
						(size 1.27 1.27)
					)
					(hide yes)
				)
			)
			(property "Datasheet" ""
				(at 0 0 0)
				(effects
					(font
						(size 1.27 1.27)
					)
					(hide yes)
				)
			)
			(property "Description" ""
				(at 0 0 0)
				(effects
					(font
						(size 1.27 1.27)
					)
					(hide yes)
				)
			)
			(symbol "GND_18_0_1"
				(polyline
					(pts
						(xy 0 0) (xy 0 -1.27) (xy 1.27 -1.27) (xy 0 -2.54) (xy -1.27 -1.27) (xy 0 -1.27)
					)
					(stroke
						(width 0)
						(type default)
					)
					(fill
						(type none)
					)
				)
			)
			(symbol "GND_18_1_1"
				(pin power_in line
					(at 0 0 270)
					(length 0)
					(hide yes)
					(name "GND"
						(effects
							(font
								(size 1.27 1.27)
							)
						)
					)
					(number "1"
						(effects
							(font
								(size 1.27 1.27)
							)
						)
					)
				)
			)
		)
	(symbol "data-center-rdimm-ddr5-tester:GND_19"
			(power)
			(pin_names
				(offset 0)
			)
			(exclude_from_sim no)
			(in_bom yes)
			(on_board yes)
			(property "Reference" "#PWR"
				(at 0 -6.35 0)
				(effects
					(font
						(size 1.27 1.27)
					)
					(hide yes)
				)
			)
			(property "Value" "GND_19"
				(at 0 -3.81 0)
				(effects
					(font
						(size 1.27 1.27)
					)
				)
			)
			(property "Footprint" ""
				(at 0 0 0)
				(effects
					(font
						(size 1.27 1.27)
					)
					(hide yes)
				)
			)
			(property "Datasheet" ""
				(at 0 0 0)
				(effects
					(font
						(size 1.27 1.27)
					)
					(hide yes)
				)
			)
			(property "Description" ""
				(at 0 0 0)
				(effects
					(font
						(size 1.27 1.27)
					)
					(hide yes)
				)
			)
			(symbol "GND_19_0_1"
				(polyline
					(pts
						(xy 0 0) (xy 0 -1.27) (xy 1.27 -1.27) (xy 0 -2.54) (xy -1.27 -1.27) (xy 0 -1.27)
					)
					(stroke
						(width 0)
						(type default)
					)
					(fill
						(type none)
					)
				)
			)
			(symbol "GND_19_1_1"
				(pin power_in line
					(at 0 0 270)
					(length 0)
					(hide yes)
					(name "GND"
						(effects
							(font
								(size 1.27 1.27)
							)
						)
					)
					(number "1"
						(effects
							(font
								(size 1.27 1.27)
							)
						)
					)
				)
			)
		)
	(symbol "data-center-rdimm-ddr5-tester:GND_20"
			(power)
			(pin_names
				(offset 0)
			)
			(exclude_from_sim no)
			(in_bom yes)
			(on_board yes)
			(property "Reference" "#PWR"
				(at 0 -6.35 0)
				(effects
					(font
						(size 1.27 1.27)
					)
					(hide yes)
				)
			)
			(property "Value" "GND_20"
				(at 0 -3.81 0)
				(effects
					(font
						(size 1.27 1.27)
					)
				)
			)
			(property "Footprint" ""
				(at 0 0 0)
				(effects
					(font
						(size 1.27 1.27)
					)
					(hide yes)
				)
			)
			(property "Datasheet" ""
				(at 0 0 0)
				(effects
					(font
						(size 1.27 1.27)
					)
					(hide yes)
				)
			)
			(property "Description" ""
				(at 0 0 0)
				(effects
					(font
						(size 1.27 1.27)
					)
					(hide yes)
				)
			)
			(symbol "GND_20_0_1"
				(polyline
					(pts
						(xy 0 0) (xy 0 -1.27) (xy 1.27 -1.27) (xy 0 -2.54) (xy -1.27 -1.27) (xy 0 -1.27)
					)
					(stroke
						(width 0)
						(type default)
					)
					(fill
						(type none)
					)
				)
			)
			(symbol "GND_20_1_1"
				(pin power_in line
					(at 0 0 270)
					(length 0)
					(hide yes)
					(name "GND"
						(effects
							(font
								(size 1.27 1.27)
							)
						)
					)
					(number "1"
						(effects
							(font
								(size 1.27 1.27)
							)
						)
					)
				)
			)
		)
	(symbol "data-center-rdimm-ddr5-tester:GND_21"
			(power)
			(pin_names
				(offset 0)
			)
			(exclude_from_sim no)
			(in_bom yes)
			(on_board yes)
			(property "Reference" "#PWR"
				(at 0 -6.35 0)
				(effects
					(font
						(size 1.27 1.27)
					)
					(hide yes)
				)
			)
			(property "Value" "GND_21"
				(at 0 -3.81 0)
				(effects
					(font
						(size 1.27 1.27)
					)
				)
			)
			(property "Footprint" ""
				(at 0 0 0)
				(effects
					(font
						(size 1.27 1.27)
					)
					(hide yes)
				)
			)
			(property "Datasheet" ""
				(at 0 0 0)
				(effects
					(font
						(size 1.27 1.27)
					)
					(hide yes)
				)
			)
			(property "Description" ""
				(at 0 0 0)
				(effects
					(font
						(size 1.27 1.27)
					)
					(hide yes)
				)
			)
			(symbol "GND_21_0_1"
				(polyline
					(pts
						(xy 0 0) (xy 0 -1.27) (xy 1.27 -1.27) (xy 0 -2.54) (xy -1.27 -1.27) (xy 0 -1.27)
					)
					(stroke
						(width 0)
						(type default)
					)
					(fill
						(type none)
					)
				)
			)
			(symbol "GND_21_1_1"
				(pin power_in line
					(at 0 0 270)
					(length 0)
					(hide yes)
					(name "GND"
						(effects
							(font
								(size 1.27 1.27)
							)
						)
					)
					(number "1"
						(effects
							(font
								(size 1.27 1.27)
							)
						)
					)
				)
			)
		)
	(symbol "data-center-rdimm-ddr5-tester:GND_22"
			(power)
			(pin_names
				(offset 0)
			)
			(exclude_from_sim no)
			(in_bom yes)
			(on_board yes)
			(property "Reference" "#PWR"
				(at 0 -6.35 0)
				(effects
					(font
						(size 1.27 1.27)
					)
					(hide yes)
				)
			)
			(property "Value" "GND_22"
				(at 0 -3.81 0)
				(effects
					(font
						(size 1.27 1.27)
					)
				)
			)
			(property "Footprint" ""
				(at 0 0 0)
				(effects
					(font
						(size 1.27 1.27)
					)
					(hide yes)
				)
			)
			(property "Datasheet" ""
				(at 0 0 0)
				(effects
					(font
						(size 1.27 1.27)
					)
					(hide yes)
				)
			)
			(property "Description" ""
				(at 0 0 0)
				(effects
					(font
						(size 1.27 1.27)
					)
					(hide yes)
				)
			)
			(symbol "GND_22_0_1"
				(polyline
					(pts
						(xy 0 0) (xy 0 -1.27) (xy 1.27 -1.27) (xy 0 -2.54) (xy -1.27 -1.27) (xy 0 -1.27)
					)
					(stroke
						(width 0)
						(type default)
					)
					(fill
						(type none)
					)
				)
			)
			(symbol "GND_22_1_1"
				(pin power_in line
					(at 0 0 270)
					(length 0)
					(hide yes)
					(name "GND"
						(effects
							(font
								(size 1.27 1.27)
							)
						)
					)
					(number "1"
						(effects
							(font
								(size 1.27 1.27)
							)
						)
					)
				)
			)
		)
	(symbol "data-center-rdimm-ddr5-tester:GND_23"
			(power)
			(pin_names
				(offset 0)
			)
			(exclude_from_sim no)
			(in_bom yes)
			(on_board yes)
			(property "Reference" "#PWR"
				(at 0 -6.35 0)
				(effects
					(font
						(size 1.27 1.27)
					)
					(hide yes)
				)
			)
			(property "Value" "GND_23"
				(at 0 -3.81 0)
				(effects
					(font
						(size 1.27 1.27)
					)
				)
			)
			(property "Footprint" ""
				(at 0 0 0)
				(effects
					(font
						(size 1.27 1.27)
					)
					(hide yes)
				)
			)
			(property "Datasheet" ""
				(at 0 0 0)
				(effects
					(font
						(size 1.27 1.27)
					)
					(hide yes)
				)
			)
			(property "Description" ""
				(at 0 0 0)
				(effects
					(font
						(size 1.27 1.27)
					)
					(hide yes)
				)
			)
			(symbol "GND_23_0_1"
				(polyline
					(pts
						(xy 0 0) (xy 0 -1.27) (xy 1.27 -1.27) (xy 0 -2.54) (xy -1.27 -1.27) (xy 0 -1.27)
					)
					(stroke
						(width 0)
						(type default)
					)
					(fill
						(type none)
					)
				)
			)
			(symbol "GND_23_1_1"
				(pin power_in line
					(at 0 0 270)
					(length 0)
					(hide yes)
					(name "GND"
						(effects
							(font
								(size 1.27 1.27)
							)
						)
					)
					(number "1"
						(effects
							(font
								(size 1.27 1.27)
							)
						)
					)
				)
			)
		)
	(symbol "data-center-rdimm-ddr5-tester:GND_24"
			(power)
			(pin_names
				(offset 0)
			)
			(exclude_from_sim no)
			(in_bom yes)
			(on_board yes)
			(property "Reference" "#PWR"
				(at 0 -6.35 0)
				(effects
					(font
						(size 1.27 1.27)
					)
					(hide yes)
				)
			)
			(property "Value" "GND_24"
				(at 0 -3.81 0)
				(effects
					(font
						(size 1.27 1.27)
					)
				)
			)
			(property "Footprint" ""
				(at 0 0 0)
				(effects
					(font
						(size 1.27 1.27)
					)
					(hide yes)
				)
			)
			(property "Datasheet" ""
				(at 0 0 0)
				(effects
					(font
						(size 1.27 1.27)
					)
					(hide yes)
				)
			)
			(property "Description" ""
				(at 0 0 0)
				(effects
					(font
						(size 1.27 1.27)
					)
					(hide yes)
				)
			)
			(symbol "GND_24_0_1"
				(polyline
					(pts
						(xy 0 0) (xy 0 -1.27) (xy 1.27 -1.27) (xy 0 -2.54) (xy -1.27 -1.27) (xy 0 -1.27)
					)
					(stroke
						(width 0)
						(type default)
					)
					(fill
						(type none)
					)
				)
			)
			(symbol "GND_24_1_1"
				(pin power_in line
					(at 0 0 270)
					(length 0)
					(hide yes)
					(name "GND"
						(effects
							(font
								(size 1.27 1.27)
							)
						)
					)
					(number "1"
						(effects
							(font
								(size 1.27 1.27)
							)
						)
					)
				)
			)
		)
	(symbol "data-center-rdimm-ddr5-tester:GND_25"
			(power)
			(pin_names
				(offset 0)
			)
			(exclude_from_sim no)
			(in_bom yes)
			(on_board yes)
			(property "Reference" "#PWR"
				(at 0 -6.35 0)
				(effects
					(font
						(size 1.27 1.27)
					)
					(hide yes)
				)
			)
			(property "Value" "GND_25"
				(at 0 -3.81 0)
				(effects
					(font
						(size 1.27 1.27)
					)
				)
			)
			(property "Footprint" ""
				(at 0 0 0)
				(effects
					(font
						(size 1.27 1.27)
					)
					(hide yes)
				)
			)
			(property "Datasheet" ""
				(at 0 0 0)
				(effects
					(font
						(size 1.27 1.27)
					)
					(hide yes)
				)
			)
			(property "Description" ""
				(at 0 0 0)
				(effects
					(font
						(size 1.27 1.27)
					)
					(hide yes)
				)
			)
			(symbol "GND_25_0_1"
				(polyline
					(pts
						(xy 0 0) (xy 0 -1.27) (xy 1.27 -1.27) (xy 0 -2.54) (xy -1.27 -1.27) (xy 0 -1.27)
					)
					(stroke
						(width 0)
						(type default)
					)
					(fill
						(type none)
					)
				)
			)
			(symbol "GND_25_1_1"
				(pin power_in line
					(at 0 0 270)
					(length 0)
					(hide yes)
					(name "GND"
						(effects
							(font
								(size 1.27 1.27)
							)
						)
					)
					(number "1"
						(effects
							(font
								(size 1.27 1.27)
							)
						)
					)
				)
			)
		)
	(symbol "data-center-rdimm-ddr5-tester:GND_26"
			(power)
			(pin_names
				(offset 0)
			)
			(exclude_from_sim no)
			(in_bom yes)
			(on_board yes)
			(property "Reference" "#PWR"
				(at 0 -6.35 0)
				(effects
					(font
						(size 1.27 1.27)
					)
					(hide yes)
				)
			)
			(property "Value" "GND_26"
				(at 0 -3.81 0)
				(effects
					(font
						(size 1.27 1.27)
					)
				)
			)
			(property "Footprint" ""
				(at 0 0 0)
				(effects
					(font
						(size 1.27 1.27)
					)
					(hide yes)
				)
			)
			(property "Datasheet" ""
				(at 0 0 0)
				(effects
					(font
						(size 1.27 1.27)
					)
					(hide yes)
				)
			)
			(property "Description" ""
				(at 0 0 0)
				(effects
					(font
						(size 1.27 1.27)
					)
					(hide yes)
				)
			)
			(symbol "GND_26_0_1"
				(polyline
					(pts
						(xy 0 0) (xy 0 -1.27) (xy 1.27 -1.27) (xy 0 -2.54) (xy -1.27 -1.27) (xy 0 -1.27)
					)
					(stroke
						(width 0)
						(type default)
					)
					(fill
						(type none)
					)
				)
			)
			(symbol "GND_26_1_1"
				(pin power_in line
					(at 0 0 270)
					(length 0)
					(hide yes)
					(name "GND"
						(effects
							(font
								(size 1.27 1.27)
							)
						)
					)
					(number "1"
						(effects
							(font
								(size 1.27 1.27)
							)
						)
					)
				)
			)
		)
	(symbol "data-center-rdimm-ddr5-tester:GND_27"
			(power)
			(pin_names
				(offset 0)
			)
			(exclude_from_sim no)
			(in_bom yes)
			(on_board yes)
			(property "Reference" "#PWR"
				(at 0 -6.35 0)
				(effects
					(font
						(size 1.27 1.27)
					)
					(hide yes)
				)
			)
			(property "Value" "GND_27"
				(at 0 -3.81 0)
				(effects
					(font
						(size 1.27 1.27)
					)
				)
			)
			(property "Footprint" ""
				(at 0 0 0)
				(effects
					(font
						(size 1.27 1.27)
					)
					(hide yes)
				)
			)
			(property "Datasheet" ""
				(at 0 0 0)
				(effects
					(font
						(size 1.27 1.27)
					)
					(hide yes)
				)
			)
			(property "Description" ""
				(at 0 0 0)
				(effects
					(font
						(size 1.27 1.27)
					)
					(hide yes)
				)
			)
			(symbol "GND_27_0_1"
				(polyline
					(pts
						(xy 0 0) (xy 0 -1.27) (xy 1.27 -1.27) (xy 0 -2.54) (xy -1.27 -1.27) (xy 0 -1.27)
					)
					(stroke
						(width 0)
						(type default)
					)
					(fill
						(type none)
					)
				)
			)
			(symbol "GND_27_1_1"
				(pin power_in line
					(at 0 0 270)
					(length 0)
					(hide yes)
					(name "GND"
						(effects
							(font
								(size 1.27 1.27)
							)
						)
					)
					(number "1"
						(effects
							(font
								(size 1.27 1.27)
							)
						)
					)
				)
			)
		)
	(symbol "data-center-rdimm-ddr5-tester:GND_28"
			(power)
			(pin_names
				(offset 0)
			)
			(exclude_from_sim no)
			(in_bom yes)
			(on_board yes)
			(property "Reference" "#PWR"
				(at 0 -6.35 0)
				(effects
					(font
						(size 1.27 1.27)
					)
					(hide yes)
				)
			)
			(property "Value" "GND_28"
				(at 0 -3.81 0)
				(effects
					(font
						(size 1.27 1.27)
					)
				)
			)
			(property "Footprint" ""
				(at 0 0 0)
				(effects
					(font
						(size 1.27 1.27)
					)
					(hide yes)
				)
			)
			(property "Datasheet" ""
				(at 0 0 0)
				(effects
					(font
						(size 1.27 1.27)
					)
					(hide yes)
				)
			)
			(property "Description" ""
				(at 0 0 0)
				(effects
					(font
						(size 1.27 1.27)
					)
					(hide yes)
				)
			)
			(symbol "GND_28_0_1"
				(polyline
					(pts
						(xy 0 0) (xy 0 -1.27) (xy 1.27 -1.27) (xy 0 -2.54) (xy -1.27 -1.27) (xy 0 -1.27)
					)
					(stroke
						(width 0)
						(type default)
					)
					(fill
						(type none)
					)
				)
			)
			(symbol "GND_28_1_1"
				(pin power_in line
					(at 0 0 270)
					(length 0)
					(hide yes)
					(name "GND"
						(effects
							(font
								(size 1.27 1.27)
							)
						)
					)
					(number "1"
						(effects
							(font
								(size 1.27 1.27)
							)
						)
					)
				)
			)
		)
	(symbol "data-center-rdimm-ddr5-tester:GND_29"
			(power)
			(pin_names
				(offset 0)
			)
			(exclude_from_sim no)
			(in_bom yes)
			(on_board yes)
			(property "Reference" "#PWR"
				(at 0 -6.35 0)
				(effects
					(font
						(size 1.27 1.27)
					)
					(hide yes)
				)
			)
			(property "Value" "GND_29"
				(at 0 -3.81 0)
				(effects
					(font
						(size 1.27 1.27)
					)
				)
			)
			(property "Footprint" ""
				(at 0 0 0)
				(effects
					(font
						(size 1.27 1.27)
					)
					(hide yes)
				)
			)
			(property "Datasheet" ""
				(at 0 0 0)
				(effects
					(font
						(size 1.27 1.27)
					)
					(hide yes)
				)
			)
			(property "Description" ""
				(at 0 0 0)
				(effects
					(font
						(size 1.27 1.27)
					)
					(hide yes)
				)
			)
			(symbol "GND_29_0_1"
				(polyline
					(pts
						(xy 0 0) (xy 0 -1.27) (xy 1.27 -1.27) (xy 0 -2.54) (xy -1.27 -1.27) (xy 0 -1.27)
					)
					(stroke
						(width 0)
						(type default)
					)
					(fill
						(type none)
					)
				)
			)
			(symbol "GND_29_1_1"
				(pin power_in line
					(at 0 0 270)
					(length 0)
					(hide yes)
					(name "GND"
						(effects
							(font
								(size 1.27 1.27)
							)
						)
					)
					(number "1"
						(effects
							(font
								(size 1.27 1.27)
							)
						)
					)
				)
			)
		)
	(symbol "data-center-rdimm-ddr5-tester:GND_30"
			(power)
			(pin_names
				(offset 0)
			)
			(exclude_from_sim no)
			(in_bom yes)
			(on_board yes)
			(property "Reference" "#PWR"
				(at 0 -6.35 0)
				(effects
					(font
						(size 1.27 1.27)
					)
					(hide yes)
				)
			)
			(property "Value" "GND_30"
				(at 0 -3.81 0)
				(effects
					(font
						(size 1.27 1.27)
					)
				)
			)
			(property "Footprint" ""
				(at 0 0 0)
				(effects
					(font
						(size 1.27 1.27)
					)
					(hide yes)
				)
			)
			(property "Datasheet" ""
				(at 0 0 0)
				(effects
					(font
						(size 1.27 1.27)
					)
					(hide yes)
				)
			)
			(property "Description" ""
				(at 0 0 0)
				(effects
					(font
						(size 1.27 1.27)
					)
					(hide yes)
				)
			)
			(symbol "GND_30_0_1"
				(polyline
					(pts
						(xy 0 0) (xy 0 -1.27) (xy 1.27 -1.27) (xy 0 -2.54) (xy -1.27 -1.27) (xy 0 -1.27)
					)
					(stroke
						(width 0)
						(type default)
					)
					(fill
						(type none)
					)
				)
			)
			(symbol "GND_30_1_1"
				(pin power_in line
					(at 0 0 270)
					(length 0)
					(hide yes)
					(name "GND"
						(effects
							(font
								(size 1.27 1.27)
							)
						)
					)
					(number "1"
						(effects
							(font
								(size 1.27 1.27)
							)
						)
					)
				)
			)
		)
	(symbol "data-center-rdimm-ddr5-tester:GND_31"
			(power)
			(pin_names
				(offset 0)
			)
			(exclude_from_sim no)
			(in_bom yes)
			(on_board yes)
			(property "Reference" "#PWR"
				(at 0 -6.35 0)
				(effects
					(font
						(size 1.27 1.27)
					)
					(hide yes)
				)
			)
			(property "Value" "GND_31"
				(at 0 -3.81 0)
				(effects
					(font
						(size 1.27 1.27)
					)
				)
			)
			(property "Footprint" ""
				(at 0 0 0)
				(effects
					(font
						(size 1.27 1.27)
					)
					(hide yes)
				)
			)
			(property "Datasheet" ""
				(at 0 0 0)
				(effects
					(font
						(size 1.27 1.27)
					)
					(hide yes)
				)
			)
			(property "Description" ""
				(at 0 0 0)
				(effects
					(font
						(size 1.27 1.27)
					)
					(hide yes)
				)
			)
			(symbol "GND_31_0_1"
				(polyline
					(pts
						(xy 0 0) (xy 0 -1.27) (xy 1.27 -1.27) (xy 0 -2.54) (xy -1.27 -1.27) (xy 0 -1.27)
					)
					(stroke
						(width 0)
						(type default)
					)
					(fill
						(type none)
					)
				)
			)
			(symbol "GND_31_1_1"
				(pin power_in line
					(at 0 0 270)
					(length 0)
					(hide yes)
					(name "GND"
						(effects
							(font
								(size 1.27 1.27)
							)
						)
					)
					(number "1"
						(effects
							(font
								(size 1.27 1.27)
							)
						)
					)
				)
			)
		)
	(symbol "data-center-rdimm-ddr5-tester:GND_32"
			(power)
			(pin_names
				(offset 0)
			)
			(exclude_from_sim no)
			(in_bom yes)
			(on_board yes)
			(property "Reference" "#PWR"
				(at 0 -6.35 0)
				(effects
					(font
						(size 1.27 1.27)
					)
					(hide yes)
				)
			)
			(property "Value" "GND_32"
				(at 0 -3.81 0)
				(effects
					(font
						(size 1.27 1.27)
					)
				)
			)
			(property "Footprint" ""
				(at 0 0 0)
				(effects
					(font
						(size 1.27 1.27)
					)
					(hide yes)
				)
			)
			(property "Datasheet" ""
				(at 0 0 0)
				(effects
					(font
						(size 1.27 1.27)
					)
					(hide yes)
				)
			)
			(property "Description" ""
				(at 0 0 0)
				(effects
					(font
						(size 1.27 1.27)
					)
					(hide yes)
				)
			)
			(symbol "GND_32_0_1"
				(polyline
					(pts
						(xy 0 0) (xy 0 -1.27) (xy 1.27 -1.27) (xy 0 -2.54) (xy -1.27 -1.27) (xy 0 -1.27)
					)
					(stroke
						(width 0)
						(type default)
					)
					(fill
						(type none)
					)
				)
			)
			(symbol "GND_32_1_1"
				(pin power_in line
					(at 0 0 270)
					(length 0)
					(hide yes)
					(name "GND"
						(effects
							(font
								(size 1.27 1.27)
							)
						)
					)
					(number "1"
						(effects
							(font
								(size 1.27 1.27)
							)
						)
					)
				)
			)
		)
	(symbol "data-center-rdimm-ddr5-tester:GND_33"
			(power)
			(pin_names
				(offset 0)
			)
			(exclude_from_sim no)
			(in_bom yes)
			(on_board yes)
			(property "Reference" "#PWR"
				(at 0 -6.35 0)
				(effects
					(font
						(size 1.27 1.27)
					)
					(hide yes)
				)
			)
			(property "Value" "GND_33"
				(at 0 -3.81 0)
				(effects
					(font
						(size 1.27 1.27)
					)
				)
			)
			(property "Footprint" ""
				(at 0 0 0)
				(effects
					(font
						(size 1.27 1.27)
					)
					(hide yes)
				)
			)
			(property "Datasheet" ""
				(at 0 0 0)
				(effects
					(font
						(size 1.27 1.27)
					)
					(hide yes)
				)
			)
			(property "Description" ""
				(at 0 0 0)
				(effects
					(font
						(size 1.27 1.27)
					)
					(hide yes)
				)
			)
			(symbol "GND_33_0_1"
				(polyline
					(pts
						(xy 0 0) (xy 0 -1.27) (xy 1.27 -1.27) (xy 0 -2.54) (xy -1.27 -1.27) (xy 0 -1.27)
					)
					(stroke
						(width 0)
						(type default)
					)
					(fill
						(type none)
					)
				)
			)
			(symbol "GND_33_1_1"
				(pin power_in line
					(at 0 0 270)
					(length 0)
					(hide yes)
					(name "GND"
						(effects
							(font
								(size 1.27 1.27)
							)
						)
					)
					(number "1"
						(effects
							(font
								(size 1.27 1.27)
							)
						)
					)
				)
			)
		)
	(symbol "data-center-rdimm-ddr5-tester:GND_34"
			(power)
			(pin_names
				(offset 0)
			)
			(exclude_from_sim no)
			(in_bom yes)
			(on_board yes)
			(property "Reference" "#PWR"
				(at 0 -6.35 0)
				(effects
					(font
						(size 1.27 1.27)
					)
					(hide yes)
				)
			)
			(property "Value" "GND_34"
				(at 0 -3.81 0)
				(effects
					(font
						(size 1.27 1.27)
					)
				)
			)
			(property "Footprint" ""
				(at 0 0 0)
				(effects
					(font
						(size 1.27 1.27)
					)
					(hide yes)
				)
			)
			(property "Datasheet" ""
				(at 0 0 0)
				(effects
					(font
						(size 1.27 1.27)
					)
					(hide yes)
				)
			)
			(property "Description" ""
				(at 0 0 0)
				(effects
					(font
						(size 1.27 1.27)
					)
					(hide yes)
				)
			)
			(symbol "GND_34_0_1"
				(polyline
					(pts
						(xy 0 0) (xy 0 -1.27) (xy 1.27 -1.27) (xy 0 -2.54) (xy -1.27 -1.27) (xy 0 -1.27)
					)
					(stroke
						(width 0)
						(type default)
					)
					(fill
						(type none)
					)
				)
			)
			(symbol "GND_34_1_1"
				(pin power_in line
					(at 0 0 270)
					(length 0)
					(hide yes)
					(name "GND"
						(effects
							(font
								(size 1.27 1.27)
							)
						)
					)
					(number "1"
						(effects
							(font
								(size 1.27 1.27)
							)
						)
					)
				)
			)
		)
	(symbol "data-center-rdimm-ddr5-tester:GND_36"
			(power)
			(pin_names
				(offset 0)
			)
			(exclude_from_sim no)
			(in_bom yes)
			(on_board yes)
			(property "Reference" "#PWR"
				(at 0 -6.35 0)
				(effects
					(font
						(size 1.27 1.27)
					)
					(hide yes)
				)
			)
			(property "Value" "GND_36"
				(at 0 -3.81 0)
				(effects
					(font
						(size 1.27 1.27)
					)
				)
			)
			(property "Footprint" ""
				(at 0 0 0)
				(effects
					(font
						(size 1.27 1.27)
					)
					(hide yes)
				)
			)
			(property "Datasheet" ""
				(at 0 0 0)
				(effects
					(font
						(size 1.27 1.27)
					)
					(hide yes)
				)
			)
			(property "Description" ""
				(at 0 0 0)
				(effects
					(font
						(size 1.27 1.27)
					)
					(hide yes)
				)
			)
			(symbol "GND_36_0_1"
				(polyline
					(pts
						(xy 0 0) (xy 0 -1.27) (xy 1.27 -1.27) (xy 0 -2.54) (xy -1.27 -1.27) (xy 0 -1.27)
					)
					(stroke
						(width 0)
						(type default)
					)
					(fill
						(type none)
					)
				)
			)
			(symbol "GND_36_1_1"
				(pin power_in line
					(at 0 0 270)
					(length 0)
					(hide yes)
					(name "GND"
						(effects
							(font
								(size 1.27 1.27)
							)
						)
					)
					(number "1"
						(effects
							(font
								(size 1.27 1.27)
							)
						)
					)
				)
			)
		)
	(symbol "data-center-rdimm-ddr5-tester:GND_37"
			(power)
			(pin_names
				(offset 0)
			)
			(exclude_from_sim no)
			(in_bom yes)
			(on_board yes)
			(property "Reference" "#PWR"
				(at 0 -6.35 0)
				(effects
					(font
						(size 1.27 1.27)
					)
					(hide yes)
				)
			)
			(property "Value" "GND_37"
				(at 0 -3.81 0)
				(effects
					(font
						(size 1.27 1.27)
					)
				)
			)
			(property "Footprint" ""
				(at 0 0 0)
				(effects
					(font
						(size 1.27 1.27)
					)
					(hide yes)
				)
			)
			(property "Datasheet" ""
				(at 0 0 0)
				(effects
					(font
						(size 1.27 1.27)
					)
					(hide yes)
				)
			)
			(property "Description" ""
				(at 0 0 0)
				(effects
					(font
						(size 1.27 1.27)
					)
					(hide yes)
				)
			)
			(symbol "GND_37_0_1"
				(polyline
					(pts
						(xy 0 0) (xy 0 -1.27) (xy 1.27 -1.27) (xy 0 -2.54) (xy -1.27 -1.27) (xy 0 -1.27)
					)
					(stroke
						(width 0)
						(type default)
					)
					(fill
						(type none)
					)
				)
			)
			(symbol "GND_37_1_1"
				(pin power_in line
					(at 0 0 270)
					(length 0)
					(hide yes)
					(name "GND"
						(effects
							(font
								(size 1.27 1.27)
							)
						)
					)
					(number "1"
						(effects
							(font
								(size 1.27 1.27)
							)
						)
					)
				)
			)
		)
	(symbol "data-center-rdimm-ddr5-tester:GND_38"
			(power)
			(pin_names
				(offset 0)
			)
			(exclude_from_sim no)
			(in_bom yes)
			(on_board yes)
			(property "Reference" "#PWR"
				(at 0 -6.35 0)
				(effects
					(font
						(size 1.27 1.27)
					)
					(hide yes)
				)
			)
			(property "Value" "GND_38"
				(at 0 -3.81 0)
				(effects
					(font
						(size 1.27 1.27)
					)
				)
			)
			(property "Footprint" ""
				(at 0 0 0)
				(effects
					(font
						(size 1.27 1.27)
					)
					(hide yes)
				)
			)
			(property "Datasheet" ""
				(at 0 0 0)
				(effects
					(font
						(size 1.27 1.27)
					)
					(hide yes)
				)
			)
			(property "Description" ""
				(at 0 0 0)
				(effects
					(font
						(size 1.27 1.27)
					)
					(hide yes)
				)
			)
			(symbol "GND_38_0_1"
				(polyline
					(pts
						(xy 0 0) (xy 0 -1.27) (xy 1.27 -1.27) (xy 0 -2.54) (xy -1.27 -1.27) (xy 0 -1.27)
					)
					(stroke
						(width 0)
						(type default)
					)
					(fill
						(type none)
					)
				)
			)
			(symbol "GND_38_1_1"
				(pin power_in line
					(at 0 0 270)
					(length 0)
					(hide yes)
					(name "GND"
						(effects
							(font
								(size 1.27 1.27)
							)
						)
					)
					(number "1"
						(effects
							(font
								(size 1.27 1.27)
							)
						)
					)
				)
			)
		)
	(symbol "data-center-rdimm-ddr5-tester:GND_39"
			(power)
			(pin_names
				(offset 0)
			)
			(exclude_from_sim no)
			(in_bom yes)
			(on_board yes)
			(property "Reference" "#PWR"
				(at 0 -6.35 0)
				(effects
					(font
						(size 1.27 1.27)
					)
					(hide yes)
				)
			)
			(property "Value" "GND_39"
				(at 0 -3.81 0)
				(effects
					(font
						(size 1.27 1.27)
					)
				)
			)
			(property "Footprint" ""
				(at 0 0 0)
				(effects
					(font
						(size 1.27 1.27)
					)
					(hide yes)
				)
			)
			(property "Datasheet" ""
				(at 0 0 0)
				(effects
					(font
						(size 1.27 1.27)
					)
					(hide yes)
				)
			)
			(property "Description" ""
				(at 0 0 0)
				(effects
					(font
						(size 1.27 1.27)
					)
					(hide yes)
				)
			)
			(symbol "GND_39_0_1"
				(polyline
					(pts
						(xy 0 0) (xy 0 -1.27) (xy 1.27 -1.27) (xy 0 -2.54) (xy -1.27 -1.27) (xy 0 -1.27)
					)
					(stroke
						(width 0)
						(type default)
					)
					(fill
						(type none)
					)
				)
			)
			(symbol "GND_39_1_1"
				(pin power_in line
					(at 0 0 270)
					(length 0)
					(hide yes)
					(name "GND"
						(effects
							(font
								(size 1.27 1.27)
							)
						)
					)
					(number "1"
						(effects
							(font
								(size 1.27 1.27)
							)
						)
					)
				)
			)
		)
	(symbol "data-center-rdimm-ddr5-tester:GND_40"
			(power)
			(pin_names
				(offset 0)
			)
			(exclude_from_sim no)
			(in_bom yes)
			(on_board yes)
			(property "Reference" "#PWR"
				(at 0 -6.35 0)
				(effects
					(font
						(size 1.27 1.27)
					)
					(hide yes)
				)
			)
			(property "Value" "GND_40"
				(at 0 -3.81 0)
				(effects
					(font
						(size 1.27 1.27)
					)
				)
			)
			(property "Footprint" ""
				(at 0 0 0)
				(effects
					(font
						(size 1.27 1.27)
					)
					(hide yes)
				)
			)
			(property "Datasheet" ""
				(at 0 0 0)
				(effects
					(font
						(size 1.27 1.27)
					)
					(hide yes)
				)
			)
			(property "Description" ""
				(at 0 0 0)
				(effects
					(font
						(size 1.27 1.27)
					)
					(hide yes)
				)
			)
			(symbol "GND_40_0_1"
				(polyline
					(pts
						(xy 0 0) (xy 0 -1.27) (xy 1.27 -1.27) (xy 0 -2.54) (xy -1.27 -1.27) (xy 0 -1.27)
					)
					(stroke
						(width 0)
						(type default)
					)
					(fill
						(type none)
					)
				)
			)
			(symbol "GND_40_1_1"
				(pin power_in line
					(at 0 0 270)
					(length 0)
					(hide yes)
					(name "GND"
						(effects
							(font
								(size 1.27 1.27)
							)
						)
					)
					(number "1"
						(effects
							(font
								(size 1.27 1.27)
							)
						)
					)
				)
			)
		)
	(symbol "data-center-rdimm-ddr5-tester:GND_41"
			(power)
			(pin_names
				(offset 0)
			)
			(exclude_from_sim no)
			(in_bom yes)
			(on_board yes)
			(property "Reference" "#PWR"
				(at 0 -6.35 0)
				(effects
					(font
						(size 1.27 1.27)
					)
					(hide yes)
				)
			)
			(property "Value" "GND_41"
				(at 0 -3.81 0)
				(effects
					(font
						(size 1.27 1.27)
					)
				)
			)
			(property "Footprint" ""
				(at 0 0 0)
				(effects
					(font
						(size 1.27 1.27)
					)
					(hide yes)
				)
			)
			(property "Datasheet" ""
				(at 0 0 0)
				(effects
					(font
						(size 1.27 1.27)
					)
					(hide yes)
				)
			)
			(property "Description" ""
				(at 0 0 0)
				(effects
					(font
						(size 1.27 1.27)
					)
					(hide yes)
				)
			)
			(symbol "GND_41_0_1"
				(polyline
					(pts
						(xy 0 0) (xy 0 -1.27) (xy 1.27 -1.27) (xy 0 -2.54) (xy -1.27 -1.27) (xy 0 -1.27)
					)
					(stroke
						(width 0)
						(type default)
					)
					(fill
						(type none)
					)
				)
			)
			(symbol "GND_41_1_1"
				(pin power_in line
					(at 0 0 270)
					(length 0)
					(hide yes)
					(name "GND"
						(effects
							(font
								(size 1.27 1.27)
							)
						)
					)
					(number "1"
						(effects
							(font
								(size 1.27 1.27)
							)
						)
					)
				)
			)
		)
	(symbol "data-center-rdimm-ddr5-tester:GND_42"
			(power)
			(pin_names
				(offset 0)
			)
			(exclude_from_sim no)
			(in_bom yes)
			(on_board yes)
			(property "Reference" "#PWR"
				(at 0 -6.35 0)
				(effects
					(font
						(size 1.27 1.27)
					)
					(hide yes)
				)
			)
			(property "Value" "GND_42"
				(at 0 -3.81 0)
				(effects
					(font
						(size 1.27 1.27)
					)
				)
			)
			(property "Footprint" ""
				(at 0 0 0)
				(effects
					(font
						(size 1.27 1.27)
					)
					(hide yes)
				)
			)
			(property "Datasheet" ""
				(at 0 0 0)
				(effects
					(font
						(size 1.27 1.27)
					)
					(hide yes)
				)
			)
			(property "Description" ""
				(at 0 0 0)
				(effects
					(font
						(size 1.27 1.27)
					)
					(hide yes)
				)
			)
			(symbol "GND_42_0_1"
				(polyline
					(pts
						(xy 0 0) (xy 0 -1.27) (xy 1.27 -1.27) (xy 0 -2.54) (xy -1.27 -1.27) (xy 0 -1.27)
					)
					(stroke
						(width 0)
						(type default)
					)
					(fill
						(type none)
					)
				)
			)
			(symbol "GND_42_1_1"
				(pin power_in line
					(at 0 0 270)
					(length 0)
					(hide yes)
					(name "GND"
						(effects
							(font
								(size 1.27 1.27)
							)
						)
					)
					(number "1"
						(effects
							(font
								(size 1.27 1.27)
							)
						)
					)
				)
			)
		)
	(symbol "data-center-rdimm-ddr5-tester:GND_43"
			(power)
			(pin_names
				(offset 0)
			)
			(exclude_from_sim no)
			(in_bom yes)
			(on_board yes)
			(property "Reference" "#PWR"
				(at 0 -6.35 0)
				(effects
					(font
						(size 1.27 1.27)
					)
					(hide yes)
				)
			)
			(property "Value" "GND_43"
				(at 0 -3.81 0)
				(effects
					(font
						(size 1.27 1.27)
					)
				)
			)
			(property "Footprint" ""
				(at 0 0 0)
				(effects
					(font
						(size 1.27 1.27)
					)
					(hide yes)
				)
			)
			(property "Datasheet" ""
				(at 0 0 0)
				(effects
					(font
						(size 1.27 1.27)
					)
					(hide yes)
				)
			)
			(property "Description" ""
				(at 0 0 0)
				(effects
					(font
						(size 1.27 1.27)
					)
					(hide yes)
				)
			)
			(symbol "GND_43_0_1"
				(polyline
					(pts
						(xy 0 0) (xy 0 -1.27) (xy 1.27 -1.27) (xy 0 -2.54) (xy -1.27 -1.27) (xy 0 -1.27)
					)
					(stroke
						(width 0)
						(type default)
					)
					(fill
						(type none)
					)
				)
			)
			(symbol "GND_43_1_1"
				(pin power_in line
					(at 0 0 270)
					(length 0)
					(hide yes)
					(name "GND"
						(effects
							(font
								(size 1.27 1.27)
							)
						)
					)
					(number "1"
						(effects
							(font
								(size 1.27 1.27)
							)
						)
					)
				)
			)
		)
	(symbol "data-center-rdimm-ddr5-tester:GND_44"
			(power)
			(pin_names
				(offset 0)
			)
			(exclude_from_sim no)
			(in_bom yes)
			(on_board yes)
			(property "Reference" "#PWR"
				(at 0 -6.35 0)
				(effects
					(font
						(size 1.27 1.27)
					)
					(hide yes)
				)
			)
			(property "Value" "GND_44"
				(at 0 -3.81 0)
				(effects
					(font
						(size 1.27 1.27)
					)
				)
			)
			(property "Footprint" ""
				(at 0 0 0)
				(effects
					(font
						(size 1.27 1.27)
					)
					(hide yes)
				)
			)
			(property "Datasheet" ""
				(at 0 0 0)
				(effects
					(font
						(size 1.27 1.27)
					)
					(hide yes)
				)
			)
			(property "Description" ""
				(at 0 0 0)
				(effects
					(font
						(size 1.27 1.27)
					)
					(hide yes)
				)
			)
			(symbol "GND_44_0_1"
				(polyline
					(pts
						(xy 0 0) (xy 0 -1.27) (xy 1.27 -1.27) (xy 0 -2.54) (xy -1.27 -1.27) (xy 0 -1.27)
					)
					(stroke
						(width 0)
						(type default)
					)
					(fill
						(type none)
					)
				)
			)
			(symbol "GND_44_1_1"
				(pin power_in line
					(at 0 0 270)
					(length 0)
					(hide yes)
					(name "GND"
						(effects
							(font
								(size 1.27 1.27)
							)
						)
					)
					(number "1"
						(effects
							(font
								(size 1.27 1.27)
							)
						)
					)
				)
			)
		)
	(symbol "data-center-rdimm-ddr5-tester:GND_46"
			(power)
			(pin_names
				(offset 0)
			)
			(exclude_from_sim no)
			(in_bom yes)
			(on_board yes)
			(property "Reference" "#PWR"
				(at 0 -6.35 0)
				(effects
					(font
						(size 1.27 1.27)
					)
					(hide yes)
				)
			)
			(property "Value" "GND_46"
				(at 0 -3.81 0)
				(effects
					(font
						(size 1.27 1.27)
					)
				)
			)
			(property "Footprint" ""
				(at 0 0 0)
				(effects
					(font
						(size 1.27 1.27)
					)
					(hide yes)
				)
			)
			(property "Datasheet" ""
				(at 0 0 0)
				(effects
					(font
						(size 1.27 1.27)
					)
					(hide yes)
				)
			)
			(property "Description" ""
				(at 0 0 0)
				(effects
					(font
						(size 1.27 1.27)
					)
					(hide yes)
				)
			)
			(symbol "GND_46_0_1"
				(polyline
					(pts
						(xy 0 0) (xy 0 -1.27) (xy 1.27 -1.27) (xy 0 -2.54) (xy -1.27 -1.27) (xy 0 -1.27)
					)
					(stroke
						(width 0)
						(type default)
					)
					(fill
						(type none)
					)
				)
			)
			(symbol "GND_46_1_1"
				(pin power_in line
					(at 0 0 270)
					(length 0)
					(hide yes)
					(name "GND"
						(effects
							(font
								(size 1.27 1.27)
							)
						)
					)
					(number "1"
						(effects
							(font
								(size 1.27 1.27)
							)
						)
					)
				)
			)
		)
	(symbol "data-center-rdimm-ddr5-tester:GND_47"
			(power)
			(pin_names
				(offset 0)
			)
			(exclude_from_sim no)
			(in_bom yes)
			(on_board yes)
			(property "Reference" "#PWR"
				(at 0 -6.35 0)
				(effects
					(font
						(size 1.27 1.27)
					)
					(hide yes)
				)
			)
			(property "Value" "GND_47"
				(at 0 -3.81 0)
				(effects
					(font
						(size 1.27 1.27)
					)
				)
			)
			(property "Footprint" ""
				(at 0 0 0)
				(effects
					(font
						(size 1.27 1.27)
					)
					(hide yes)
				)
			)
			(property "Datasheet" ""
				(at 0 0 0)
				(effects
					(font
						(size 1.27 1.27)
					)
					(hide yes)
				)
			)
			(property "Description" ""
				(at 0 0 0)
				(effects
					(font
						(size 1.27 1.27)
					)
					(hide yes)
				)
			)
			(symbol "GND_47_0_1"
				(polyline
					(pts
						(xy 0 0) (xy 0 -1.27) (xy 1.27 -1.27) (xy 0 -2.54) (xy -1.27 -1.27) (xy 0 -1.27)
					)
					(stroke
						(width 0)
						(type default)
					)
					(fill
						(type none)
					)
				)
			)
			(symbol "GND_47_1_1"
				(pin power_in line
					(at 0 0 270)
					(length 0)
					(hide yes)
					(name "GND"
						(effects
							(font
								(size 1.27 1.27)
							)
						)
					)
					(number "1"
						(effects
							(font
								(size 1.27 1.27)
							)
						)
					)
				)
			)
		)
	(symbol "data-center-rdimm-ddr5-tester:GND_48"
			(power)
			(pin_names
				(offset 0)
			)
			(exclude_from_sim no)
			(in_bom yes)
			(on_board yes)
			(property "Reference" "#PWR"
				(at 0 -6.35 0)
				(effects
					(font
						(size 1.27 1.27)
					)
					(hide yes)
				)
			)
			(property "Value" "GND_48"
				(at 0 -3.81 0)
				(effects
					(font
						(size 1.27 1.27)
					)
				)
			)
			(property "Footprint" ""
				(at 0 0 0)
				(effects
					(font
						(size 1.27 1.27)
					)
					(hide yes)
				)
			)
			(property "Datasheet" ""
				(at 0 0 0)
				(effects
					(font
						(size 1.27 1.27)
					)
					(hide yes)
				)
			)
			(property "Description" ""
				(at 0 0 0)
				(effects
					(font
						(size 1.27 1.27)
					)
					(hide yes)
				)
			)
			(symbol "GND_48_0_1"
				(polyline
					(pts
						(xy 0 0) (xy 0 -1.27) (xy 1.27 -1.27) (xy 0 -2.54) (xy -1.27 -1.27) (xy 0 -1.27)
					)
					(stroke
						(width 0)
						(type default)
					)
					(fill
						(type none)
					)
				)
			)
			(symbol "GND_48_1_1"
				(pin power_in line
					(at 0 0 270)
					(length 0)
					(hide yes)
					(name "GND"
						(effects
							(font
								(size 1.27 1.27)
							)
						)
					)
					(number "1"
						(effects
							(font
								(size 1.27 1.27)
							)
						)
					)
				)
			)
		)
	(symbol "data-center-rdimm-ddr5-tester:GND_49"
			(power)
			(pin_names
				(offset 0)
			)
			(exclude_from_sim no)
			(in_bom yes)
			(on_board yes)
			(property "Reference" "#PWR"
				(at 0 -6.35 0)
				(effects
					(font
						(size 1.27 1.27)
					)
					(hide yes)
				)
			)
			(property "Value" "GND_49"
				(at 0 -3.81 0)
				(effects
					(font
						(size 1.27 1.27)
					)
				)
			)
			(property "Footprint" ""
				(at 0 0 0)
				(effects
					(font
						(size 1.27 1.27)
					)
					(hide yes)
				)
			)
			(property "Datasheet" ""
				(at 0 0 0)
				(effects
					(font
						(size 1.27 1.27)
					)
					(hide yes)
				)
			)
			(property "Description" ""
				(at 0 0 0)
				(effects
					(font
						(size 1.27 1.27)
					)
					(hide yes)
				)
			)
			(symbol "GND_49_0_1"
				(polyline
					(pts
						(xy 0 0) (xy 0 -1.27) (xy 1.27 -1.27) (xy 0 -2.54) (xy -1.27 -1.27) (xy 0 -1.27)
					)
					(stroke
						(width 0)
						(type default)
					)
					(fill
						(type none)
					)
				)
			)
			(symbol "GND_49_1_1"
				(pin power_in line
					(at 0 0 270)
					(length 0)
					(hide yes)
					(name "GND"
						(effects
							(font
								(size 1.27 1.27)
							)
						)
					)
					(number "1"
						(effects
							(font
								(size 1.27 1.27)
							)
						)
					)
				)
			)
		)
	(symbol "data-center-rdimm-ddr5-tester:GND_50"
			(power)
			(pin_names
				(offset 0)
			)
			(exclude_from_sim no)
			(in_bom yes)
			(on_board yes)
			(property "Reference" "#PWR"
				(at 0 -6.35 0)
				(effects
					(font
						(size 1.27 1.27)
					)
					(hide yes)
				)
			)
			(property "Value" "GND_50"
				(at 0 -3.81 0)
				(effects
					(font
						(size 1.27 1.27)
					)
				)
			)
			(property "Footprint" ""
				(at 0 0 0)
				(effects
					(font
						(size 1.27 1.27)
					)
					(hide yes)
				)
			)
			(property "Datasheet" ""
				(at 0 0 0)
				(effects
					(font
						(size 1.27 1.27)
					)
					(hide yes)
				)
			)
			(property "Description" ""
				(at 0 0 0)
				(effects
					(font
						(size 1.27 1.27)
					)
					(hide yes)
				)
			)
			(symbol "GND_50_0_1"
				(polyline
					(pts
						(xy 0 0) (xy 0 -1.27) (xy 1.27 -1.27) (xy 0 -2.54) (xy -1.27 -1.27) (xy 0 -1.27)
					)
					(stroke
						(width 0)
						(type default)
					)
					(fill
						(type none)
					)
				)
			)
			(symbol "GND_50_1_1"
				(pin power_in line
					(at 0 0 270)
					(length 0)
					(hide yes)
					(name "GND"
						(effects
							(font
								(size 1.27 1.27)
							)
						)
					)
					(number "1"
						(effects
							(font
								(size 1.27 1.27)
							)
						)
					)
				)
			)
		)
	(symbol "data-center-rdimm-ddr5-tester:GND_51"
			(power)
			(pin_names
				(offset 0)
			)
			(exclude_from_sim no)
			(in_bom yes)
			(on_board yes)
			(property "Reference" "#PWR"
				(at 0 -6.35 0)
				(effects
					(font
						(size 1.27 1.27)
					)
					(hide yes)
				)
			)
			(property "Value" "GND_51"
				(at 0 -3.81 0)
				(effects
					(font
						(size 1.27 1.27)
					)
				)
			)
			(property "Footprint" ""
				(at 0 0 0)
				(effects
					(font
						(size 1.27 1.27)
					)
					(hide yes)
				)
			)
			(property "Datasheet" ""
				(at 0 0 0)
				(effects
					(font
						(size 1.27 1.27)
					)
					(hide yes)
				)
			)
			(property "Description" ""
				(at 0 0 0)
				(effects
					(font
						(size 1.27 1.27)
					)
					(hide yes)
				)
			)
			(symbol "GND_51_0_1"
				(polyline
					(pts
						(xy 0 0) (xy 0 -1.27) (xy 1.27 -1.27) (xy 0 -2.54) (xy -1.27 -1.27) (xy 0 -1.27)
					)
					(stroke
						(width 0)
						(type default)
					)
					(fill
						(type none)
					)
				)
			)
			(symbol "GND_51_1_1"
				(pin power_in line
					(at 0 0 270)
					(length 0)
					(hide yes)
					(name "GND"
						(effects
							(font
								(size 1.27 1.27)
							)
						)
					)
					(number "1"
						(effects
							(font
								(size 1.27 1.27)
							)
						)
					)
				)
			)
		)
	(symbol "data-center-rdimm-ddr5-tester:GND_52"
			(power)
			(pin_names
				(offset 0)
			)
			(exclude_from_sim no)
			(in_bom yes)
			(on_board yes)
			(property "Reference" "#PWR"
				(at 0 -6.35 0)
				(effects
					(font
						(size 1.27 1.27)
					)
					(hide yes)
				)
			)
			(property "Value" "GND_52"
				(at 0 -3.81 0)
				(effects
					(font
						(size 1.27 1.27)
					)
				)
			)
			(property "Footprint" ""
				(at 0 0 0)
				(effects
					(font
						(size 1.27 1.27)
					)
					(hide yes)
				)
			)
			(property "Datasheet" ""
				(at 0 0 0)
				(effects
					(font
						(size 1.27 1.27)
					)
					(hide yes)
				)
			)
			(property "Description" ""
				(at 0 0 0)
				(effects
					(font
						(size 1.27 1.27)
					)
					(hide yes)
				)
			)
			(symbol "GND_52_0_1"
				(polyline
					(pts
						(xy 0 0) (xy 0 -1.27) (xy 1.27 -1.27) (xy 0 -2.54) (xy -1.27 -1.27) (xy 0 -1.27)
					)
					(stroke
						(width 0)
						(type default)
					)
					(fill
						(type none)
					)
				)
			)
			(symbol "GND_52_1_1"
				(pin power_in line
					(at 0 0 270)
					(length 0)
					(hide yes)
					(name "GND"
						(effects
							(font
								(size 1.27 1.27)
							)
						)
					)
					(number "1"
						(effects
							(font
								(size 1.27 1.27)
							)
						)
					)
				)
			)
		)
	(symbol "data-center-rdimm-ddr5-tester:GND_53"
			(power)
			(pin_names
				(offset 0)
			)
			(exclude_from_sim no)
			(in_bom yes)
			(on_board yes)
			(property "Reference" "#PWR"
				(at 0 -6.35 0)
				(effects
					(font
						(size 1.27 1.27)
					)
					(hide yes)
				)
			)
			(property "Value" "GND_53"
				(at 0 -3.81 0)
				(effects
					(font
						(size 1.27 1.27)
					)
				)
			)
			(property "Footprint" ""
				(at 0 0 0)
				(effects
					(font
						(size 1.27 1.27)
					)
					(hide yes)
				)
			)
			(property "Datasheet" ""
				(at 0 0 0)
				(effects
					(font
						(size 1.27 1.27)
					)
					(hide yes)
				)
			)
			(property "Description" ""
				(at 0 0 0)
				(effects
					(font
						(size 1.27 1.27)
					)
					(hide yes)
				)
			)
			(symbol "GND_53_0_1"
				(polyline
					(pts
						(xy 0 0) (xy 0 -1.27) (xy 1.27 -1.27) (xy 0 -2.54) (xy -1.27 -1.27) (xy 0 -1.27)
					)
					(stroke
						(width 0)
						(type default)
					)
					(fill
						(type none)
					)
				)
			)
			(symbol "GND_53_1_1"
				(pin power_in line
					(at 0 0 270)
					(length 0)
					(hide yes)
					(name "GND"
						(effects
							(font
								(size 1.27 1.27)
							)
						)
					)
					(number "1"
						(effects
							(font
								(size 1.27 1.27)
							)
						)
					)
				)
			)
		)
	(symbol "data-center-rdimm-ddr5-tester:GND_54"
			(power)
			(pin_names
				(offset 0)
			)
			(exclude_from_sim no)
			(in_bom yes)
			(on_board yes)
			(property "Reference" "#PWR"
				(at 0 -6.35 0)
				(effects
					(font
						(size 1.27 1.27)
					)
					(hide yes)
				)
			)
			(property "Value" "GND_54"
				(at 0 -3.81 0)
				(effects
					(font
						(size 1.27 1.27)
					)
				)
			)
			(property "Footprint" ""
				(at 0 0 0)
				(effects
					(font
						(size 1.27 1.27)
					)
					(hide yes)
				)
			)
			(property "Datasheet" ""
				(at 0 0 0)
				(effects
					(font
						(size 1.27 1.27)
					)
					(hide yes)
				)
			)
			(property "Description" ""
				(at 0 0 0)
				(effects
					(font
						(size 1.27 1.27)
					)
					(hide yes)
				)
			)
			(symbol "GND_54_0_1"
				(polyline
					(pts
						(xy 0 0) (xy 0 -1.27) (xy 1.27 -1.27) (xy 0 -2.54) (xy -1.27 -1.27) (xy 0 -1.27)
					)
					(stroke
						(width 0)
						(type default)
					)
					(fill
						(type none)
					)
				)
			)
			(symbol "GND_54_1_1"
				(pin power_in line
					(at 0 0 270)
					(length 0)
					(hide yes)
					(name "GND"
						(effects
							(font
								(size 1.27 1.27)
							)
						)
					)
					(number "1"
						(effects
							(font
								(size 1.27 1.27)
							)
						)
					)
				)
			)
		)
	(symbol "data-center-rdimm-ddr5-tester:GND_55"
			(power)
			(pin_names
				(offset 0)
			)
			(exclude_from_sim no)
			(in_bom yes)
			(on_board yes)
			(property "Reference" "#PWR"
				(at 0 -6.35 0)
				(effects
					(font
						(size 1.27 1.27)
					)
					(hide yes)
				)
			)
			(property "Value" "GND_55"
				(at 0 -3.81 0)
				(effects
					(font
						(size 1.27 1.27)
					)
				)
			)
			(property "Footprint" ""
				(at 0 0 0)
				(effects
					(font
						(size 1.27 1.27)
					)
					(hide yes)
				)
			)
			(property "Datasheet" ""
				(at 0 0 0)
				(effects
					(font
						(size 1.27 1.27)
					)
					(hide yes)
				)
			)
			(property "Description" ""
				(at 0 0 0)
				(effects
					(font
						(size 1.27 1.27)
					)
					(hide yes)
				)
			)
			(symbol "GND_55_0_1"
				(polyline
					(pts
						(xy 0 0) (xy 0 -1.27) (xy 1.27 -1.27) (xy 0 -2.54) (xy -1.27 -1.27) (xy 0 -1.27)
					)
					(stroke
						(width 0)
						(type default)
					)
					(fill
						(type none)
					)
				)
			)
			(symbol "GND_55_1_1"
				(pin power_in line
					(at 0 0 270)
					(length 0)
					(hide yes)
					(name "GND"
						(effects
							(font
								(size 1.27 1.27)
							)
						)
					)
					(number "1"
						(effects
							(font
								(size 1.27 1.27)
							)
						)
					)
				)
			)
		)
	(symbol "data-center-rdimm-ddr5-tester:GND_56"
			(power)
			(pin_names
				(offset 0)
			)
			(exclude_from_sim no)
			(in_bom yes)
			(on_board yes)
			(property "Reference" "#PWR"
				(at 0 -6.35 0)
				(effects
					(font
						(size 1.27 1.27)
					)
					(hide yes)
				)
			)
			(property "Value" "GND_56"
				(at 0 -3.81 0)
				(effects
					(font
						(size 1.27 1.27)
					)
				)
			)
			(property "Footprint" ""
				(at 0 0 0)
				(effects
					(font
						(size 1.27 1.27)
					)
					(hide yes)
				)
			)
			(property "Datasheet" ""
				(at 0 0 0)
				(effects
					(font
						(size 1.27 1.27)
					)
					(hide yes)
				)
			)
			(property "Description" ""
				(at 0 0 0)
				(effects
					(font
						(size 1.27 1.27)
					)
					(hide yes)
				)
			)
			(symbol "GND_56_0_1"
				(polyline
					(pts
						(xy 0 0) (xy 0 -1.27) (xy 1.27 -1.27) (xy 0 -2.54) (xy -1.27 -1.27) (xy 0 -1.27)
					)
					(stroke
						(width 0)
						(type default)
					)
					(fill
						(type none)
					)
				)
			)
			(symbol "GND_56_1_1"
				(pin power_in line
					(at 0 0 270)
					(length 0)
					(hide yes)
					(name "GND"
						(effects
							(font
								(size 1.27 1.27)
							)
						)
					)
					(number "1"
						(effects
							(font
								(size 1.27 1.27)
							)
						)
					)
				)
			)
		)
	(symbol "data-center-rdimm-ddr5-tester:GND_57"
			(power)
			(pin_names
				(offset 0)
			)
			(exclude_from_sim no)
			(in_bom yes)
			(on_board yes)
			(property "Reference" "#PWR"
				(at 0 -6.35 0)
				(effects
					(font
						(size 1.27 1.27)
					)
					(hide yes)
				)
			)
			(property "Value" "GND_57"
				(at 0 -3.81 0)
				(effects
					(font
						(size 1.27 1.27)
					)
				)
			)
			(property "Footprint" ""
				(at 0 0 0)
				(effects
					(font
						(size 1.27 1.27)
					)
					(hide yes)
				)
			)
			(property "Datasheet" ""
				(at 0 0 0)
				(effects
					(font
						(size 1.27 1.27)
					)
					(hide yes)
				)
			)
			(property "Description" ""
				(at 0 0 0)
				(effects
					(font
						(size 1.27 1.27)
					)
					(hide yes)
				)
			)
			(symbol "GND_57_0_1"
				(polyline
					(pts
						(xy 0 0) (xy 0 -1.27) (xy 1.27 -1.27) (xy 0 -2.54) (xy -1.27 -1.27) (xy 0 -1.27)
					)
					(stroke
						(width 0)
						(type default)
					)
					(fill
						(type none)
					)
				)
			)
			(symbol "GND_57_1_1"
				(pin power_in line
					(at 0 0 270)
					(length 0)
					(hide yes)
					(name "GND"
						(effects
							(font
								(size 1.27 1.27)
							)
						)
					)
					(number "1"
						(effects
							(font
								(size 1.27 1.27)
							)
						)
					)
				)
			)
		)
	(symbol "data-center-rdimm-ddr5-tester:GND_58"
			(power)
			(pin_names
				(offset 0)
			)
			(exclude_from_sim no)
			(in_bom yes)
			(on_board yes)
			(property "Reference" "#PWR"
				(at 0 -6.35 0)
				(effects
					(font
						(size 1.27 1.27)
					)
					(hide yes)
				)
			)
			(property "Value" "GND_58"
				(at 0 -3.81 0)
				(effects
					(font
						(size 1.27 1.27)
					)
				)
			)
			(property "Footprint" ""
				(at 0 0 0)
				(effects
					(font
						(size 1.27 1.27)
					)
					(hide yes)
				)
			)
			(property "Datasheet" ""
				(at 0 0 0)
				(effects
					(font
						(size 1.27 1.27)
					)
					(hide yes)
				)
			)
			(property "Description" ""
				(at 0 0 0)
				(effects
					(font
						(size 1.27 1.27)
					)
					(hide yes)
				)
			)
			(symbol "GND_58_0_1"
				(polyline
					(pts
						(xy 0 0) (xy 0 -1.27) (xy 1.27 -1.27) (xy 0 -2.54) (xy -1.27 -1.27) (xy 0 -1.27)
					)
					(stroke
						(width 0)
						(type default)
					)
					(fill
						(type none)
					)
				)
			)
			(symbol "GND_58_1_1"
				(pin power_in line
					(at 0 0 270)
					(length 0)
					(hide yes)
					(name "GND"
						(effects
							(font
								(size 1.27 1.27)
							)
						)
					)
					(number "1"
						(effects
							(font
								(size 1.27 1.27)
							)
						)
					)
				)
			)
		)
	(symbol "data-center-rdimm-ddr5-tester:GND_59"
			(power)
			(pin_names
				(offset 0)
			)
			(exclude_from_sim no)
			(in_bom yes)
			(on_board yes)
			(property "Reference" "#PWR"
				(at 0 -6.35 0)
				(effects
					(font
						(size 1.27 1.27)
					)
					(hide yes)
				)
			)
			(property "Value" "GND_59"
				(at 0 -3.81 0)
				(effects
					(font
						(size 1.27 1.27)
					)
				)
			)
			(property "Footprint" ""
				(at 0 0 0)
				(effects
					(font
						(size 1.27 1.27)
					)
					(hide yes)
				)
			)
			(property "Datasheet" ""
				(at 0 0 0)
				(effects
					(font
						(size 1.27 1.27)
					)
					(hide yes)
				)
			)
			(property "Description" ""
				(at 0 0 0)
				(effects
					(font
						(size 1.27 1.27)
					)
					(hide yes)
				)
			)
			(symbol "GND_59_0_1"
				(polyline
					(pts
						(xy 0 0) (xy 0 -1.27) (xy 1.27 -1.27) (xy 0 -2.54) (xy -1.27 -1.27) (xy 0 -1.27)
					)
					(stroke
						(width 0)
						(type default)
					)
					(fill
						(type none)
					)
				)
			)
			(symbol "GND_59_1_1"
				(pin power_in line
					(at 0 0 270)
					(length 0)
					(hide yes)
					(name "GND"
						(effects
							(font
								(size 1.27 1.27)
							)
						)
					)
					(number "1"
						(effects
							(font
								(size 1.27 1.27)
							)
						)
					)
				)
			)
		)
	(symbol "data-center-rdimm-ddr5-tester:GND_60"
			(power)
			(pin_names
				(offset 0)
			)
			(exclude_from_sim no)
			(in_bom yes)
			(on_board yes)
			(property "Reference" "#PWR"
				(at 0 -6.35 0)
				(effects
					(font
						(size 1.27 1.27)
					)
					(hide yes)
				)
			)
			(property "Value" "GND_60"
				(at 0 -3.81 0)
				(effects
					(font
						(size 1.27 1.27)
					)
				)
			)
			(property "Footprint" ""
				(at 0 0 0)
				(effects
					(font
						(size 1.27 1.27)
					)
					(hide yes)
				)
			)
			(property "Datasheet" ""
				(at 0 0 0)
				(effects
					(font
						(size 1.27 1.27)
					)
					(hide yes)
				)
			)
			(property "Description" ""
				(at 0 0 0)
				(effects
					(font
						(size 1.27 1.27)
					)
					(hide yes)
				)
			)
			(symbol "GND_60_0_1"
				(polyline
					(pts
						(xy 0 0) (xy 0 -1.27) (xy 1.27 -1.27) (xy 0 -2.54) (xy -1.27 -1.27) (xy 0 -1.27)
					)
					(stroke
						(width 0)
						(type default)
					)
					(fill
						(type none)
					)
				)
			)
			(symbol "GND_60_1_1"
				(pin power_in line
					(at 0 0 270)
					(length 0)
					(hide yes)
					(name "GND"
						(effects
							(font
								(size 1.27 1.27)
							)
						)
					)
					(number "1"
						(effects
							(font
								(size 1.27 1.27)
							)
						)
					)
				)
			)
		)
	(symbol "data-center-rdimm-ddr5-tester:GND_61"
			(power)
			(pin_names
				(offset 0)
			)
			(exclude_from_sim no)
			(in_bom yes)
			(on_board yes)
			(property "Reference" "#PWR"
				(at 0 -6.35 0)
				(effects
					(font
						(size 1.27 1.27)
					)
					(hide yes)
				)
			)
			(property "Value" "GND_61"
				(at 0 -3.81 0)
				(effects
					(font
						(size 1.27 1.27)
					)
				)
			)
			(property "Footprint" ""
				(at 0 0 0)
				(effects
					(font
						(size 1.27 1.27)
					)
					(hide yes)
				)
			)
			(property "Datasheet" ""
				(at 0 0 0)
				(effects
					(font
						(size 1.27 1.27)
					)
					(hide yes)
				)
			)
			(property "Description" ""
				(at 0 0 0)
				(effects
					(font
						(size 1.27 1.27)
					)
					(hide yes)
				)
			)
			(symbol "GND_61_0_1"
				(polyline
					(pts
						(xy 0 0) (xy 0 -1.27) (xy 1.27 -1.27) (xy 0 -2.54) (xy -1.27 -1.27) (xy 0 -1.27)
					)
					(stroke
						(width 0)
						(type default)
					)
					(fill
						(type none)
					)
				)
			)
			(symbol "GND_61_1_1"
				(pin power_in line
					(at 0 0 270)
					(length 0)
					(hide yes)
					(name "GND"
						(effects
							(font
								(size 1.27 1.27)
							)
						)
					)
					(number "1"
						(effects
							(font
								(size 1.27 1.27)
							)
						)
					)
				)
			)
		)
	(symbol "data-center-rdimm-ddr5-tester:GND_62"
			(power)
			(pin_names
				(offset 0)
			)
			(exclude_from_sim no)
			(in_bom yes)
			(on_board yes)
			(property "Reference" "#PWR"
				(at 0 -6.35 0)
				(effects
					(font
						(size 1.27 1.27)
					)
					(hide yes)
				)
			)
			(property "Value" "GND_62"
				(at 0 -3.81 0)
				(effects
					(font
						(size 1.27 1.27)
					)
				)
			)
			(property "Footprint" ""
				(at 0 0 0)
				(effects
					(font
						(size 1.27 1.27)
					)
					(hide yes)
				)
			)
			(property "Datasheet" ""
				(at 0 0 0)
				(effects
					(font
						(size 1.27 1.27)
					)
					(hide yes)
				)
			)
			(property "Description" ""
				(at 0 0 0)
				(effects
					(font
						(size 1.27 1.27)
					)
					(hide yes)
				)
			)
			(symbol "GND_62_0_1"
				(polyline
					(pts
						(xy 0 0) (xy 0 -1.27) (xy 1.27 -1.27) (xy 0 -2.54) (xy -1.27 -1.27) (xy 0 -1.27)
					)
					(stroke
						(width 0)
						(type default)
					)
					(fill
						(type none)
					)
				)
			)
			(symbol "GND_62_1_1"
				(pin power_in line
					(at 0 0 270)
					(length 0)
					(hide yes)
					(name "GND"
						(effects
							(font
								(size 1.27 1.27)
							)
						)
					)
					(number "1"
						(effects
							(font
								(size 1.27 1.27)
							)
						)
					)
				)
			)
		)
	(symbol "data-center-rdimm-ddr5-tester:GND_63"
			(power)
			(pin_names
				(offset 0)
			)
			(exclude_from_sim no)
			(in_bom yes)
			(on_board yes)
			(property "Reference" "#PWR"
				(at 0 -6.35 0)
				(effects
					(font
						(size 1.27 1.27)
					)
					(hide yes)
				)
			)
			(property "Value" "GND_63"
				(at 0 -3.81 0)
				(effects
					(font
						(size 1.27 1.27)
					)
				)
			)
			(property "Footprint" ""
				(at 0 0 0)
				(effects
					(font
						(size 1.27 1.27)
					)
					(hide yes)
				)
			)
			(property "Datasheet" ""
				(at 0 0 0)
				(effects
					(font
						(size 1.27 1.27)
					)
					(hide yes)
				)
			)
			(property "Description" ""
				(at 0 0 0)
				(effects
					(font
						(size 1.27 1.27)
					)
					(hide yes)
				)
			)
			(symbol "GND_63_0_1"
				(polyline
					(pts
						(xy 0 0) (xy 0 -1.27) (xy 1.27 -1.27) (xy 0 -2.54) (xy -1.27 -1.27) (xy 0 -1.27)
					)
					(stroke
						(width 0)
						(type default)
					)
					(fill
						(type none)
					)
				)
			)
			(symbol "GND_63_1_1"
				(pin power_in line
					(at 0 0 270)
					(length 0)
					(hide yes)
					(name "GND"
						(effects
							(font
								(size 1.27 1.27)
							)
						)
					)
					(number "1"
						(effects
							(font
								(size 1.27 1.27)
							)
						)
					)
				)
			)
		)
	(symbol "data-center-rdimm-ddr5-tester:GND_64"
			(power)
			(pin_names
				(offset 0)
			)
			(exclude_from_sim no)
			(in_bom yes)
			(on_board yes)
			(property "Reference" "#PWR"
				(at 0 -6.35 0)
				(effects
					(font
						(size 1.27 1.27)
					)
					(hide yes)
				)
			)
			(property "Value" "GND_64"
				(at 0 -3.81 0)
				(effects
					(font
						(size 1.27 1.27)
					)
				)
			)
			(property "Footprint" ""
				(at 0 0 0)
				(effects
					(font
						(size 1.27 1.27)
					)
					(hide yes)
				)
			)
			(property "Datasheet" ""
				(at 0 0 0)
				(effects
					(font
						(size 1.27 1.27)
					)
					(hide yes)
				)
			)
			(property "Description" ""
				(at 0 0 0)
				(effects
					(font
						(size 1.27 1.27)
					)
					(hide yes)
				)
			)
			(symbol "GND_64_0_1"
				(polyline
					(pts
						(xy 0 0) (xy 0 -1.27) (xy 1.27 -1.27) (xy 0 -2.54) (xy -1.27 -1.27) (xy 0 -1.27)
					)
					(stroke
						(width 0)
						(type default)
					)
					(fill
						(type none)
					)
				)
			)
			(symbol "GND_64_1_1"
				(pin power_in line
					(at 0 0 270)
					(length 0)
					(hide yes)
					(name "GND"
						(effects
							(font
								(size 1.27 1.27)
							)
						)
					)
					(number "1"
						(effects
							(font
								(size 1.27 1.27)
							)
						)
					)
				)
			)
		)
	(symbol "data-center-rdimm-ddr5-tester:GND_65"
			(power)
			(pin_names
				(offset 0)
			)
			(exclude_from_sim no)
			(in_bom yes)
			(on_board yes)
			(property "Reference" "#PWR"
				(at 0 -6.35 0)
				(effects
					(font
						(size 1.27 1.27)
					)
					(hide yes)
				)
			)
			(property "Value" "GND_65"
				(at 0 -3.81 0)
				(effects
					(font
						(size 1.27 1.27)
					)
				)
			)
			(property "Footprint" ""
				(at 0 0 0)
				(effects
					(font
						(size 1.27 1.27)
					)
					(hide yes)
				)
			)
			(property "Datasheet" ""
				(at 0 0 0)
				(effects
					(font
						(size 1.27 1.27)
					)
					(hide yes)
				)
			)
			(property "Description" ""
				(at 0 0 0)
				(effects
					(font
						(size 1.27 1.27)
					)
					(hide yes)
				)
			)
			(symbol "GND_65_0_1"
				(polyline
					(pts
						(xy 0 0) (xy 0 -1.27) (xy 1.27 -1.27) (xy 0 -2.54) (xy -1.27 -1.27) (xy 0 -1.27)
					)
					(stroke
						(width 0)
						(type default)
					)
					(fill
						(type none)
					)
				)
			)
			(symbol "GND_65_1_1"
				(pin power_in line
					(at 0 0 270)
					(length 0)
					(hide yes)
					(name "GND"
						(effects
							(font
								(size 1.27 1.27)
							)
						)
					)
					(number "1"
						(effects
							(font
								(size 1.27 1.27)
							)
						)
					)
				)
			)
		)
	(symbol "data-center-rdimm-ddr5-tester:GND_66"
			(power)
			(pin_names
				(offset 0)
			)
			(exclude_from_sim no)
			(in_bom yes)
			(on_board yes)
			(property "Reference" "#PWR"
				(at 0 -6.35 0)
				(effects
					(font
						(size 1.27 1.27)
					)
					(hide yes)
				)
			)
			(property "Value" "GND_66"
				(at 0 -3.81 0)
				(effects
					(font
						(size 1.27 1.27)
					)
				)
			)
			(property "Footprint" ""
				(at 0 0 0)
				(effects
					(font
						(size 1.27 1.27)
					)
					(hide yes)
				)
			)
			(property "Datasheet" ""
				(at 0 0 0)
				(effects
					(font
						(size 1.27 1.27)
					)
					(hide yes)
				)
			)
			(property "Description" ""
				(at 0 0 0)
				(effects
					(font
						(size 1.27 1.27)
					)
					(hide yes)
				)
			)
			(symbol "GND_66_0_1"
				(polyline
					(pts
						(xy 0 0) (xy 0 -1.27) (xy 1.27 -1.27) (xy 0 -2.54) (xy -1.27 -1.27) (xy 0 -1.27)
					)
					(stroke
						(width 0)
						(type default)
					)
					(fill
						(type none)
					)
				)
			)
			(symbol "GND_66_1_1"
				(pin power_in line
					(at 0 0 270)
					(length 0)
					(hide yes)
					(name "GND"
						(effects
							(font
								(size 1.27 1.27)
							)
						)
					)
					(number "1"
						(effects
							(font
								(size 1.27 1.27)
							)
						)
					)
				)
			)
		)
	(symbol "data-center-rdimm-ddr5-tester:GND_67"
			(power)
			(pin_names
				(offset 0)
			)
			(exclude_from_sim no)
			(in_bom yes)
			(on_board yes)
			(property "Reference" "#PWR"
				(at 0 -6.35 0)
				(effects
					(font
						(size 1.27 1.27)
					)
					(hide yes)
				)
			)
			(property "Value" "GND_67"
				(at 0 -3.81 0)
				(effects
					(font
						(size 1.27 1.27)
					)
				)
			)
			(property "Footprint" ""
				(at 0 0 0)
				(effects
					(font
						(size 1.27 1.27)
					)
					(hide yes)
				)
			)
			(property "Datasheet" ""
				(at 0 0 0)
				(effects
					(font
						(size 1.27 1.27)
					)
					(hide yes)
				)
			)
			(property "Description" ""
				(at 0 0 0)
				(effects
					(font
						(size 1.27 1.27)
					)
					(hide yes)
				)
			)
			(symbol "GND_67_0_1"
				(polyline
					(pts
						(xy 0 0) (xy 0 -1.27) (xy 1.27 -1.27) (xy 0 -2.54) (xy -1.27 -1.27) (xy 0 -1.27)
					)
					(stroke
						(width 0)
						(type default)
					)
					(fill
						(type none)
					)
				)
			)
			(symbol "GND_67_1_1"
				(pin power_in line
					(at 0 0 270)
					(length 0)
					(hide yes)
					(name "GND"
						(effects
							(font
								(size 1.27 1.27)
							)
						)
					)
					(number "1"
						(effects
							(font
								(size 1.27 1.27)
							)
						)
					)
				)
			)
		)
	(symbol "data-center-rdimm-ddr5-tester:GND_68"
			(power)
			(pin_names
				(offset 0)
			)
			(exclude_from_sim no)
			(in_bom yes)
			(on_board yes)
			(property "Reference" "#PWR"
				(at 0 -6.35 0)
				(effects
					(font
						(size 1.27 1.27)
					)
					(hide yes)
				)
			)
			(property "Value" "GND_68"
				(at 0 -3.81 0)
				(effects
					(font
						(size 1.27 1.27)
					)
				)
			)
			(property "Footprint" ""
				(at 0 0 0)
				(effects
					(font
						(size 1.27 1.27)
					)
					(hide yes)
				)
			)
			(property "Datasheet" ""
				(at 0 0 0)
				(effects
					(font
						(size 1.27 1.27)
					)
					(hide yes)
				)
			)
			(property "Description" ""
				(at 0 0 0)
				(effects
					(font
						(size 1.27 1.27)
					)
					(hide yes)
				)
			)
			(symbol "GND_68_0_1"
				(polyline
					(pts
						(xy 0 0) (xy 0 -1.27) (xy 1.27 -1.27) (xy 0 -2.54) (xy -1.27 -1.27) (xy 0 -1.27)
					)
					(stroke
						(width 0)
						(type default)
					)
					(fill
						(type none)
					)
				)
			)
			(symbol "GND_68_1_1"
				(pin power_in line
					(at 0 0 270)
					(length 0)
					(hide yes)
					(name "GND"
						(effects
							(font
								(size 1.27 1.27)
							)
						)
					)
					(number "1"
						(effects
							(font
								(size 1.27 1.27)
							)
						)
					)
				)
			)
		)
	(symbol "data-center-rdimm-ddr5-tester:GND_69"
			(power)
			(pin_names
				(offset 0)
			)
			(exclude_from_sim no)
			(in_bom yes)
			(on_board yes)
			(property "Reference" "#PWR"
				(at 0 -6.35 0)
				(effects
					(font
						(size 1.27 1.27)
					)
					(hide yes)
				)
			)
			(property "Value" "GND_69"
				(at 0 -3.81 0)
				(effects
					(font
						(size 1.27 1.27)
					)
				)
			)
			(property "Footprint" ""
				(at 0 0 0)
				(effects
					(font
						(size 1.27 1.27)
					)
					(hide yes)
				)
			)
			(property "Datasheet" ""
				(at 0 0 0)
				(effects
					(font
						(size 1.27 1.27)
					)
					(hide yes)
				)
			)
			(property "Description" ""
				(at 0 0 0)
				(effects
					(font
						(size 1.27 1.27)
					)
					(hide yes)
				)
			)
			(symbol "GND_69_0_1"
				(polyline
					(pts
						(xy 0 0) (xy 0 -1.27) (xy 1.27 -1.27) (xy 0 -2.54) (xy -1.27 -1.27) (xy 0 -1.27)
					)
					(stroke
						(width 0)
						(type default)
					)
					(fill
						(type none)
					)
				)
			)
			(symbol "GND_69_1_1"
				(pin power_in line
					(at 0 0 270)
					(length 0)
					(hide yes)
					(name "GND"
						(effects
							(font
								(size 1.27 1.27)
							)
						)
					)
					(number "1"
						(effects
							(font
								(size 1.27 1.27)
							)
						)
					)
				)
			)
		)
	(symbol "data-center-rdimm-ddr5-tester:GND_70"
			(power)
			(pin_names
				(offset 0)
			)
			(exclude_from_sim no)
			(in_bom yes)
			(on_board yes)
			(property "Reference" "#PWR"
				(at 0 -6.35 0)
				(effects
					(font
						(size 1.27 1.27)
					)
					(hide yes)
				)
			)
			(property "Value" "GND_70"
				(at 0 -3.81 0)
				(effects
					(font
						(size 1.27 1.27)
					)
				)
			)
			(property "Footprint" ""
				(at 0 0 0)
				(effects
					(font
						(size 1.27 1.27)
					)
					(hide yes)
				)
			)
			(property "Datasheet" ""
				(at 0 0 0)
				(effects
					(font
						(size 1.27 1.27)
					)
					(hide yes)
				)
			)
			(property "Description" ""
				(at 0 0 0)
				(effects
					(font
						(size 1.27 1.27)
					)
					(hide yes)
				)
			)
			(symbol "GND_70_0_1"
				(polyline
					(pts
						(xy 0 0) (xy 0 -1.27) (xy 1.27 -1.27) (xy 0 -2.54) (xy -1.27 -1.27) (xy 0 -1.27)
					)
					(stroke
						(width 0)
						(type default)
					)
					(fill
						(type none)
					)
				)
			)
			(symbol "GND_70_1_1"
				(pin power_in line
					(at 0 0 270)
					(length 0)
					(hide yes)
					(name "GND"
						(effects
							(font
								(size 1.27 1.27)
							)
						)
					)
					(number "1"
						(effects
							(font
								(size 1.27 1.27)
							)
						)
					)
				)
			)
		)
	(symbol "data-center-rdimm-ddr5-tester:GND_71"
			(power)
			(pin_names
				(offset 0)
			)
			(exclude_from_sim no)
			(in_bom yes)
			(on_board yes)
			(property "Reference" "#PWR"
				(at 0 -6.35 0)
				(effects
					(font
						(size 1.27 1.27)
					)
					(hide yes)
				)
			)
			(property "Value" "GND_71"
				(at 0 -3.81 0)
				(effects
					(font
						(size 1.27 1.27)
					)
				)
			)
			(property "Footprint" ""
				(at 0 0 0)
				(effects
					(font
						(size 1.27 1.27)
					)
					(hide yes)
				)
			)
			(property "Datasheet" ""
				(at 0 0 0)
				(effects
					(font
						(size 1.27 1.27)
					)
					(hide yes)
				)
			)
			(property "Description" ""
				(at 0 0 0)
				(effects
					(font
						(size 1.27 1.27)
					)
					(hide yes)
				)
			)
			(symbol "GND_71_0_1"
				(polyline
					(pts
						(xy 0 0) (xy 0 -1.27) (xy 1.27 -1.27) (xy 0 -2.54) (xy -1.27 -1.27) (xy 0 -1.27)
					)
					(stroke
						(width 0)
						(type default)
					)
					(fill
						(type none)
					)
				)
			)
			(symbol "GND_71_1_1"
				(pin power_in line
					(at 0 0 270)
					(length 0)
					(hide yes)
					(name "GND"
						(effects
							(font
								(size 1.27 1.27)
							)
						)
					)
					(number "1"
						(effects
							(font
								(size 1.27 1.27)
							)
						)
					)
				)
			)
		)
	(symbol "data-center-rdimm-ddr5-tester:GND_72"
			(power)
			(pin_names
				(offset 0)
			)
			(exclude_from_sim no)
			(in_bom yes)
			(on_board yes)
			(property "Reference" "#PWR"
				(at 0 -6.35 0)
				(effects
					(font
						(size 1.27 1.27)
					)
					(hide yes)
				)
			)
			(property "Value" "GND_72"
				(at 0 -3.81 0)
				(effects
					(font
						(size 1.27 1.27)
					)
				)
			)
			(property "Footprint" ""
				(at 0 0 0)
				(effects
					(font
						(size 1.27 1.27)
					)
					(hide yes)
				)
			)
			(property "Datasheet" ""
				(at 0 0 0)
				(effects
					(font
						(size 1.27 1.27)
					)
					(hide yes)
				)
			)
			(property "Description" ""
				(at 0 0 0)
				(effects
					(font
						(size 1.27 1.27)
					)
					(hide yes)
				)
			)
			(symbol "GND_72_0_1"
				(polyline
					(pts
						(xy 0 0) (xy 0 -1.27) (xy 1.27 -1.27) (xy 0 -2.54) (xy -1.27 -1.27) (xy 0 -1.27)
					)
					(stroke
						(width 0)
						(type default)
					)
					(fill
						(type none)
					)
				)
			)
			(symbol "GND_72_1_1"
				(pin power_in line
					(at 0 0 270)
					(length 0)
					(hide yes)
					(name "GND"
						(effects
							(font
								(size 1.27 1.27)
							)
						)
					)
					(number "1"
						(effects
							(font
								(size 1.27 1.27)
							)
						)
					)
				)
			)
		)
	(symbol "data-center-rdimm-ddr5-tester:GND_73"
			(power)
			(pin_names
				(offset 0)
			)
			(exclude_from_sim no)
			(in_bom yes)
			(on_board yes)
			(property "Reference" "#PWR"
				(at 0 -6.35 0)
				(effects
					(font
						(size 1.27 1.27)
					)
					(hide yes)
				)
			)
			(property "Value" "GND_73"
				(at 0 -3.81 0)
				(effects
					(font
						(size 1.27 1.27)
					)
				)
			)
			(property "Footprint" ""
				(at 0 0 0)
				(effects
					(font
						(size 1.27 1.27)
					)
					(hide yes)
				)
			)
			(property "Datasheet" ""
				(at 0 0 0)
				(effects
					(font
						(size 1.27 1.27)
					)
					(hide yes)
				)
			)
			(property "Description" ""
				(at 0 0 0)
				(effects
					(font
						(size 1.27 1.27)
					)
					(hide yes)
				)
			)
			(symbol "GND_73_0_1"
				(polyline
					(pts
						(xy 0 0) (xy 0 -1.27) (xy 1.27 -1.27) (xy 0 -2.54) (xy -1.27 -1.27) (xy 0 -1.27)
					)
					(stroke
						(width 0)
						(type default)
					)
					(fill
						(type none)
					)
				)
			)
			(symbol "GND_73_1_1"
				(pin power_in line
					(at 0 0 270)
					(length 0)
					(hide yes)
					(name "GND"
						(effects
							(font
								(size 1.27 1.27)
							)
						)
					)
					(number "1"
						(effects
							(font
								(size 1.27 1.27)
							)
						)
					)
				)
			)
		)
	(symbol "data-center-rdimm-ddr5-tester:GND_74"
			(power)
			(pin_names
				(offset 0)
			)
			(exclude_from_sim no)
			(in_bom yes)
			(on_board yes)
			(property "Reference" "#PWR"
				(at 0 -6.35 0)
				(effects
					(font
						(size 1.27 1.27)
					)
					(hide yes)
				)
			)
			(property "Value" "GND_74"
				(at 0 -3.81 0)
				(effects
					(font
						(size 1.27 1.27)
					)
				)
			)
			(property "Footprint" ""
				(at 0 0 0)
				(effects
					(font
						(size 1.27 1.27)
					)
					(hide yes)
				)
			)
			(property "Datasheet" ""
				(at 0 0 0)
				(effects
					(font
						(size 1.27 1.27)
					)
					(hide yes)
				)
			)
			(property "Description" ""
				(at 0 0 0)
				(effects
					(font
						(size 1.27 1.27)
					)
					(hide yes)
				)
			)
			(symbol "GND_74_0_1"
				(polyline
					(pts
						(xy 0 0) (xy 0 -1.27) (xy 1.27 -1.27) (xy 0 -2.54) (xy -1.27 -1.27) (xy 0 -1.27)
					)
					(stroke
						(width 0)
						(type default)
					)
					(fill
						(type none)
					)
				)
			)
			(symbol "GND_74_1_1"
				(pin power_in line
					(at 0 0 270)
					(length 0)
					(hide yes)
					(name "GND"
						(effects
							(font
								(size 1.27 1.27)
							)
						)
					)
					(number "1"
						(effects
							(font
								(size 1.27 1.27)
							)
						)
					)
				)
			)
		)
	(symbol "data-center-rdimm-ddr5-tester:GND_75"
			(power)
			(pin_names
				(offset 0)
			)
			(exclude_from_sim no)
			(in_bom yes)
			(on_board yes)
			(property "Reference" "#PWR"
				(at 0 -6.35 0)
				(effects
					(font
						(size 1.27 1.27)
					)
					(hide yes)
				)
			)
			(property "Value" "GND_75"
				(at 0 -3.81 0)
				(effects
					(font
						(size 1.27 1.27)
					)
				)
			)
			(property "Footprint" ""
				(at 0 0 0)
				(effects
					(font
						(size 1.27 1.27)
					)
					(hide yes)
				)
			)
			(property "Datasheet" ""
				(at 0 0 0)
				(effects
					(font
						(size 1.27 1.27)
					)
					(hide yes)
				)
			)
			(property "Description" ""
				(at 0 0 0)
				(effects
					(font
						(size 1.27 1.27)
					)
					(hide yes)
				)
			)
			(symbol "GND_75_0_1"
				(polyline
					(pts
						(xy 0 0) (xy 0 -1.27) (xy 1.27 -1.27) (xy 0 -2.54) (xy -1.27 -1.27) (xy 0 -1.27)
					)
					(stroke
						(width 0)
						(type default)
					)
					(fill
						(type none)
					)
				)
			)
			(symbol "GND_75_1_1"
				(pin power_in line
					(at 0 0 270)
					(length 0)
					(hide yes)
					(name "GND"
						(effects
							(font
								(size 1.27 1.27)
							)
						)
					)
					(number "1"
						(effects
							(font
								(size 1.27 1.27)
							)
						)
					)
				)
			)
		)
	(symbol "data-center-rdimm-ddr5-tester:GND_76"
			(power)
			(pin_names
				(offset 0)
			)
			(exclude_from_sim no)
			(in_bom yes)
			(on_board yes)
			(property "Reference" "#PWR"
				(at 0 -6.35 0)
				(effects
					(font
						(size 1.27 1.27)
					)
					(hide yes)
				)
			)
			(property "Value" "GND_76"
				(at 0 -3.81 0)
				(effects
					(font
						(size 1.27 1.27)
					)
				)
			)
			(property "Footprint" ""
				(at 0 0 0)
				(effects
					(font
						(size 1.27 1.27)
					)
					(hide yes)
				)
			)
			(property "Datasheet" ""
				(at 0 0 0)
				(effects
					(font
						(size 1.27 1.27)
					)
					(hide yes)
				)
			)
			(property "Description" ""
				(at 0 0 0)
				(effects
					(font
						(size 1.27 1.27)
					)
					(hide yes)
				)
			)
			(symbol "GND_76_0_1"
				(polyline
					(pts
						(xy 0 0) (xy 0 -1.27) (xy 1.27 -1.27) (xy 0 -2.54) (xy -1.27 -1.27) (xy 0 -1.27)
					)
					(stroke
						(width 0)
						(type default)
					)
					(fill
						(type none)
					)
				)
			)
			(symbol "GND_76_1_1"
				(pin power_in line
					(at 0 0 270)
					(length 0)
					(hide yes)
					(name "GND"
						(effects
							(font
								(size 1.27 1.27)
							)
						)
					)
					(number "1"
						(effects
							(font
								(size 1.27 1.27)
							)
						)
					)
				)
			)
		)
	(symbol "data-center-rdimm-ddr5-tester:GND_77"
			(power)
			(pin_names
				(offset 0)
			)
			(exclude_from_sim no)
			(in_bom yes)
			(on_board yes)
			(property "Reference" "#PWR"
				(at 0 -6.35 0)
				(effects
					(font
						(size 1.27 1.27)
					)
					(hide yes)
				)
			)
			(property "Value" "GND_77"
				(at 0 -3.81 0)
				(effects
					(font
						(size 1.27 1.27)
					)
				)
			)
			(property "Footprint" ""
				(at 0 0 0)
				(effects
					(font
						(size 1.27 1.27)
					)
					(hide yes)
				)
			)
			(property "Datasheet" ""
				(at 0 0 0)
				(effects
					(font
						(size 1.27 1.27)
					)
					(hide yes)
				)
			)
			(property "Description" ""
				(at 0 0 0)
				(effects
					(font
						(size 1.27 1.27)
					)
					(hide yes)
				)
			)
			(symbol "GND_77_0_1"
				(polyline
					(pts
						(xy 0 0) (xy 0 -1.27) (xy 1.27 -1.27) (xy 0 -2.54) (xy -1.27 -1.27) (xy 0 -1.27)
					)
					(stroke
						(width 0)
						(type default)
					)
					(fill
						(type none)
					)
				)
			)
			(symbol "GND_77_1_1"
				(pin power_in line
					(at 0 0 270)
					(length 0)
					(hide yes)
					(name "GND"
						(effects
							(font
								(size 1.27 1.27)
							)
						)
					)
					(number "1"
						(effects
							(font
								(size 1.27 1.27)
							)
						)
					)
				)
			)
		)
	(symbol "data-center-rdimm-ddr5-tester:GND_78"
			(power)
			(pin_names
				(offset 0)
			)
			(exclude_from_sim no)
			(in_bom yes)
			(on_board yes)
			(property "Reference" "#PWR"
				(at 0 -6.35 0)
				(effects
					(font
						(size 1.27 1.27)
					)
					(hide yes)
				)
			)
			(property "Value" "GND_78"
				(at 0 -3.81 0)
				(effects
					(font
						(size 1.27 1.27)
					)
				)
			)
			(property "Footprint" ""
				(at 0 0 0)
				(effects
					(font
						(size 1.27 1.27)
					)
					(hide yes)
				)
			)
			(property "Datasheet" ""
				(at 0 0 0)
				(effects
					(font
						(size 1.27 1.27)
					)
					(hide yes)
				)
			)
			(property "Description" ""
				(at 0 0 0)
				(effects
					(font
						(size 1.27 1.27)
					)
					(hide yes)
				)
			)
			(symbol "GND_78_0_1"
				(polyline
					(pts
						(xy 0 0) (xy 0 -1.27) (xy 1.27 -1.27) (xy 0 -2.54) (xy -1.27 -1.27) (xy 0 -1.27)
					)
					(stroke
						(width 0)
						(type default)
					)
					(fill
						(type none)
					)
				)
			)
			(symbol "GND_78_1_1"
				(pin power_in line
					(at 0 0 270)
					(length 0)
					(hide yes)
					(name "GND"
						(effects
							(font
								(size 1.27 1.27)
							)
						)
					)
					(number "1"
						(effects
							(font
								(size 1.27 1.27)
							)
						)
					)
				)
			)
		)
	(symbol "data-center-rdimm-ddr5-tester:GND_79"
			(power)
			(pin_names
				(offset 0)
			)
			(exclude_from_sim no)
			(in_bom yes)
			(on_board yes)
			(property "Reference" "#PWR"
				(at 0 -6.35 0)
				(effects
					(font
						(size 1.27 1.27)
					)
					(hide yes)
				)
			)
			(property "Value" "GND_79"
				(at 0 -3.81 0)
				(effects
					(font
						(size 1.27 1.27)
					)
				)
			)
			(property "Footprint" ""
				(at 0 0 0)
				(effects
					(font
						(size 1.27 1.27)
					)
					(hide yes)
				)
			)
			(property "Datasheet" ""
				(at 0 0 0)
				(effects
					(font
						(size 1.27 1.27)
					)
					(hide yes)
				)
			)
			(property "Description" ""
				(at 0 0 0)
				(effects
					(font
						(size 1.27 1.27)
					)
					(hide yes)
				)
			)
			(symbol "GND_79_0_1"
				(polyline
					(pts
						(xy 0 0) (xy 0 -1.27) (xy 1.27 -1.27) (xy 0 -2.54) (xy -1.27 -1.27) (xy 0 -1.27)
					)
					(stroke
						(width 0)
						(type default)
					)
					(fill
						(type none)
					)
				)
			)
			(symbol "GND_79_1_1"
				(pin power_in line
					(at 0 0 270)
					(length 0)
					(hide yes)
					(name "GND"
						(effects
							(font
								(size 1.27 1.27)
							)
						)
					)
					(number "1"
						(effects
							(font
								(size 1.27 1.27)
							)
						)
					)
				)
			)
		)
	(symbol "data-center-rdimm-ddr5-tester:GND_81"
			(power)
			(pin_names
				(offset 0)
			)
			(exclude_from_sim no)
			(in_bom yes)
			(on_board yes)
			(property "Reference" "#PWR"
				(at 0 -6.35 0)
				(effects
					(font
						(size 1.27 1.27)
					)
					(hide yes)
				)
			)
			(property "Value" "GND_81"
				(at 0 -3.81 0)
				(effects
					(font
						(size 1.27 1.27)
					)
				)
			)
			(property "Footprint" ""
				(at 0 0 0)
				(effects
					(font
						(size 1.27 1.27)
					)
					(hide yes)
				)
			)
			(property "Datasheet" ""
				(at 0 0 0)
				(effects
					(font
						(size 1.27 1.27)
					)
					(hide yes)
				)
			)
			(property "Description" ""
				(at 0 0 0)
				(effects
					(font
						(size 1.27 1.27)
					)
					(hide yes)
				)
			)
			(symbol "GND_81_0_1"
				(polyline
					(pts
						(xy 0 0) (xy 0 -1.27) (xy 1.27 -1.27) (xy 0 -2.54) (xy -1.27 -1.27) (xy 0 -1.27)
					)
					(stroke
						(width 0)
						(type default)
					)
					(fill
						(type none)
					)
				)
			)
			(symbol "GND_81_1_1"
				(pin power_in line
					(at 0 0 270)
					(length 0)
					(hide yes)
					(name "GND"
						(effects
							(font
								(size 1.27 1.27)
							)
						)
					)
					(number "1"
						(effects
							(font
								(size 1.27 1.27)
							)
						)
					)
				)
			)
		)
	(symbol "data-center-rdimm-ddr5-tester:GND_82"
			(power)
			(pin_names
				(offset 0)
			)
			(exclude_from_sim no)
			(in_bom yes)
			(on_board yes)
			(property "Reference" "#PWR"
				(at 0 -6.35 0)
				(effects
					(font
						(size 1.27 1.27)
					)
					(hide yes)
				)
			)
			(property "Value" "GND_82"
				(at 0 -3.81 0)
				(effects
					(font
						(size 1.27 1.27)
					)
				)
			)
			(property "Footprint" ""
				(at 0 0 0)
				(effects
					(font
						(size 1.27 1.27)
					)
					(hide yes)
				)
			)
			(property "Datasheet" ""
				(at 0 0 0)
				(effects
					(font
						(size 1.27 1.27)
					)
					(hide yes)
				)
			)
			(property "Description" ""
				(at 0 0 0)
				(effects
					(font
						(size 1.27 1.27)
					)
					(hide yes)
				)
			)
			(symbol "GND_82_0_1"
				(polyline
					(pts
						(xy 0 0) (xy 0 -1.27) (xy 1.27 -1.27) (xy 0 -2.54) (xy -1.27 -1.27) (xy 0 -1.27)
					)
					(stroke
						(width 0)
						(type default)
					)
					(fill
						(type none)
					)
				)
			)
			(symbol "GND_82_1_1"
				(pin power_in line
					(at 0 0 270)
					(length 0)
					(hide yes)
					(name "GND"
						(effects
							(font
								(size 1.27 1.27)
							)
						)
					)
					(number "1"
						(effects
							(font
								(size 1.27 1.27)
							)
						)
					)
				)
			)
		)
	(symbol "data-center-rdimm-ddr5-tester:GND_83"
			(power)
			(pin_names
				(offset 0)
			)
			(exclude_from_sim no)
			(in_bom yes)
			(on_board yes)
			(property "Reference" "#PWR"
				(at 0 -6.35 0)
				(effects
					(font
						(size 1.27 1.27)
					)
					(hide yes)
				)
			)
			(property "Value" "GND_83"
				(at 0 -3.81 0)
				(effects
					(font
						(size 1.27 1.27)
					)
				)
			)
			(property "Footprint" ""
				(at 0 0 0)
				(effects
					(font
						(size 1.27 1.27)
					)
					(hide yes)
				)
			)
			(property "Datasheet" ""
				(at 0 0 0)
				(effects
					(font
						(size 1.27 1.27)
					)
					(hide yes)
				)
			)
			(property "Description" ""
				(at 0 0 0)
				(effects
					(font
						(size 1.27 1.27)
					)
					(hide yes)
				)
			)
			(symbol "GND_83_0_1"
				(polyline
					(pts
						(xy 0 0) (xy 0 -1.27) (xy 1.27 -1.27) (xy 0 -2.54) (xy -1.27 -1.27) (xy 0 -1.27)
					)
					(stroke
						(width 0)
						(type default)
					)
					(fill
						(type none)
					)
				)
			)
			(symbol "GND_83_1_1"
				(pin power_in line
					(at 0 0 270)
					(length 0)
					(hide yes)
					(name "GND"
						(effects
							(font
								(size 1.27 1.27)
							)
						)
					)
					(number "1"
						(effects
							(font
								(size 1.27 1.27)
							)
						)
					)
				)
			)
		)
	(symbol "data-center-rdimm-ddr5-tester:GND_85"
			(power)
			(pin_names
				(offset 0)
			)
			(exclude_from_sim no)
			(in_bom yes)
			(on_board yes)
			(property "Reference" "#PWR"
				(at 0 -6.35 0)
				(effects
					(font
						(size 1.27 1.27)
					)
					(hide yes)
				)
			)
			(property "Value" "GND_85"
				(at 0 -3.81 0)
				(effects
					(font
						(size 1.27 1.27)
					)
				)
			)
			(property "Footprint" ""
				(at 0 0 0)
				(effects
					(font
						(size 1.27 1.27)
					)
					(hide yes)
				)
			)
			(property "Datasheet" ""
				(at 0 0 0)
				(effects
					(font
						(size 1.27 1.27)
					)
					(hide yes)
				)
			)
			(property "Description" ""
				(at 0 0 0)
				(effects
					(font
						(size 1.27 1.27)
					)
					(hide yes)
				)
			)
			(symbol "GND_85_0_1"
				(polyline
					(pts
						(xy 0 0) (xy 0 -1.27) (xy 1.27 -1.27) (xy 0 -2.54) (xy -1.27 -1.27) (xy 0 -1.27)
					)
					(stroke
						(width 0)
						(type default)
					)
					(fill
						(type none)
					)
				)
			)
			(symbol "GND_85_1_1"
				(pin power_in line
					(at 0 0 270)
					(length 0)
					(hide yes)
					(name "GND"
						(effects
							(font
								(size 1.27 1.27)
							)
						)
					)
					(number "1"
						(effects
							(font
								(size 1.27 1.27)
							)
						)
					)
				)
			)
		)
	(symbol "data-center-rdimm-ddr5-tester:GND_86"
			(power)
			(pin_names
				(offset 0)
			)
			(exclude_from_sim no)
			(in_bom yes)
			(on_board yes)
			(property "Reference" "#PWR"
				(at 0 -6.35 0)
				(effects
					(font
						(size 1.27 1.27)
					)
					(hide yes)
				)
			)
			(property "Value" "GND_86"
				(at 0 -3.81 0)
				(effects
					(font
						(size 1.27 1.27)
					)
				)
			)
			(property "Footprint" ""
				(at 0 0 0)
				(effects
					(font
						(size 1.27 1.27)
					)
					(hide yes)
				)
			)
			(property "Datasheet" ""
				(at 0 0 0)
				(effects
					(font
						(size 1.27 1.27)
					)
					(hide yes)
				)
			)
			(property "Description" ""
				(at 0 0 0)
				(effects
					(font
						(size 1.27 1.27)
					)
					(hide yes)
				)
			)
			(symbol "GND_86_0_1"
				(polyline
					(pts
						(xy 0 0) (xy 0 -1.27) (xy 1.27 -1.27) (xy 0 -2.54) (xy -1.27 -1.27) (xy 0 -1.27)
					)
					(stroke
						(width 0)
						(type default)
					)
					(fill
						(type none)
					)
				)
			)
			(symbol "GND_86_1_1"
				(pin power_in line
					(at 0 0 270)
					(length 0)
					(hide yes)
					(name "GND"
						(effects
							(font
								(size 1.27 1.27)
							)
						)
					)
					(number "1"
						(effects
							(font
								(size 1.27 1.27)
							)
						)
					)
				)
			)
		)
	(symbol "data-center-rdimm-ddr5-tester:GND_87"
			(power)
			(pin_names
				(offset 0)
			)
			(exclude_from_sim no)
			(in_bom yes)
			(on_board yes)
			(property "Reference" "#PWR"
				(at 0 -6.35 0)
				(effects
					(font
						(size 1.27 1.27)
					)
					(hide yes)
				)
			)
			(property "Value" "GND_87"
				(at 0 -3.81 0)
				(effects
					(font
						(size 1.27 1.27)
					)
				)
			)
			(property "Footprint" ""
				(at 0 0 0)
				(effects
					(font
						(size 1.27 1.27)
					)
					(hide yes)
				)
			)
			(property "Datasheet" ""
				(at 0 0 0)
				(effects
					(font
						(size 1.27 1.27)
					)
					(hide yes)
				)
			)
			(property "Description" ""
				(at 0 0 0)
				(effects
					(font
						(size 1.27 1.27)
					)
					(hide yes)
				)
			)
			(symbol "GND_87_0_1"
				(polyline
					(pts
						(xy 0 0) (xy 0 -1.27) (xy 1.27 -1.27) (xy 0 -2.54) (xy -1.27 -1.27) (xy 0 -1.27)
					)
					(stroke
						(width 0)
						(type default)
					)
					(fill
						(type none)
					)
				)
			)
			(symbol "GND_87_1_1"
				(pin power_in line
					(at 0 0 270)
					(length 0)
					(hide yes)
					(name "GND"
						(effects
							(font
								(size 1.27 1.27)
							)
						)
					)
					(number "1"
						(effects
							(font
								(size 1.27 1.27)
							)
						)
					)
				)
			)
		)
	(symbol "data-center-rdimm-ddr5-tester:GND_88"
			(power)
			(pin_names
				(offset 0)
			)
			(exclude_from_sim no)
			(in_bom yes)
			(on_board yes)
			(property "Reference" "#PWR"
				(at 0 -6.35 0)
				(effects
					(font
						(size 1.27 1.27)
					)
					(hide yes)
				)
			)
			(property "Value" "GND_88"
				(at 0 -3.81 0)
				(effects
					(font
						(size 1.27 1.27)
					)
				)
			)
			(property "Footprint" ""
				(at 0 0 0)
				(effects
					(font
						(size 1.27 1.27)
					)
					(hide yes)
				)
			)
			(property "Datasheet" ""
				(at 0 0 0)
				(effects
					(font
						(size 1.27 1.27)
					)
					(hide yes)
				)
			)
			(property "Description" ""
				(at 0 0 0)
				(effects
					(font
						(size 1.27 1.27)
					)
					(hide yes)
				)
			)
			(symbol "GND_88_0_1"
				(polyline
					(pts
						(xy 0 0) (xy 0 -1.27) (xy 1.27 -1.27) (xy 0 -2.54) (xy -1.27 -1.27) (xy 0 -1.27)
					)
					(stroke
						(width 0)
						(type default)
					)
					(fill
						(type none)
					)
				)
			)
			(symbol "GND_88_1_1"
				(pin power_in line
					(at 0 0 270)
					(length 0)
					(hide yes)
					(name "GND"
						(effects
							(font
								(size 1.27 1.27)
							)
						)
					)
					(number "1"
						(effects
							(font
								(size 1.27 1.27)
							)
						)
					)
				)
			)
		)
	(symbol "data-center-rdimm-ddr5-tester:GND_89"
			(power)
			(pin_names
				(offset 0)
			)
			(exclude_from_sim no)
			(in_bom yes)
			(on_board yes)
			(property "Reference" "#PWR"
				(at 0 -6.35 0)
				(effects
					(font
						(size 1.27 1.27)
					)
					(hide yes)
				)
			)
			(property "Value" "GND_89"
				(at 0 -3.81 0)
				(effects
					(font
						(size 1.27 1.27)
					)
				)
			)
			(property "Footprint" ""
				(at 0 0 0)
				(effects
					(font
						(size 1.27 1.27)
					)
					(hide yes)
				)
			)
			(property "Datasheet" ""
				(at 0 0 0)
				(effects
					(font
						(size 1.27 1.27)
					)
					(hide yes)
				)
			)
			(property "Description" ""
				(at 0 0 0)
				(effects
					(font
						(size 1.27 1.27)
					)
					(hide yes)
				)
			)
			(symbol "GND_89_0_1"
				(polyline
					(pts
						(xy 0 0) (xy 0 -1.27) (xy 1.27 -1.27) (xy 0 -2.54) (xy -1.27 -1.27) (xy 0 -1.27)
					)
					(stroke
						(width 0)
						(type default)
					)
					(fill
						(type none)
					)
				)
			)
			(symbol "GND_89_1_1"
				(pin power_in line
					(at 0 0 270)
					(length 0)
					(hide yes)
					(name "GND"
						(effects
							(font
								(size 1.27 1.27)
							)
						)
					)
					(number "1"
						(effects
							(font
								(size 1.27 1.27)
							)
						)
					)
				)
			)
		)
	(symbol "data-center-rdimm-ddr5-tester:GND_90"
			(power)
			(pin_names
				(offset 0)
			)
			(exclude_from_sim no)
			(in_bom yes)
			(on_board yes)
			(property "Reference" "#PWR"
				(at 0 -6.35 0)
				(effects
					(font
						(size 1.27 1.27)
					)
					(hide yes)
				)
			)
			(property "Value" "GND_90"
				(at 0 -3.81 0)
				(effects
					(font
						(size 1.27 1.27)
					)
				)
			)
			(property "Footprint" ""
				(at 0 0 0)
				(effects
					(font
						(size 1.27 1.27)
					)
					(hide yes)
				)
			)
			(property "Datasheet" ""
				(at 0 0 0)
				(effects
					(font
						(size 1.27 1.27)
					)
					(hide yes)
				)
			)
			(property "Description" ""
				(at 0 0 0)
				(effects
					(font
						(size 1.27 1.27)
					)
					(hide yes)
				)
			)
			(symbol "GND_90_0_1"
				(polyline
					(pts
						(xy 0 0) (xy 0 -1.27) (xy 1.27 -1.27) (xy 0 -2.54) (xy -1.27 -1.27) (xy 0 -1.27)
					)
					(stroke
						(width 0)
						(type default)
					)
					(fill
						(type none)
					)
				)
			)
			(symbol "GND_90_1_1"
				(pin power_in line
					(at 0 0 270)
					(length 0)
					(hide yes)
					(name "GND"
						(effects
							(font
								(size 1.27 1.27)
							)
						)
					)
					(number "1"
						(effects
							(font
								(size 1.27 1.27)
							)
						)
					)
				)
			)
		)
	(symbol "data-center-rdimm-ddr5-tester:GND_91"
			(power)
			(pin_names
				(offset 0)
			)
			(exclude_from_sim no)
			(in_bom yes)
			(on_board yes)
			(property "Reference" "#PWR"
				(at 0 -6.35 0)
				(effects
					(font
						(size 1.27 1.27)
					)
					(hide yes)
				)
			)
			(property "Value" "GND_91"
				(at 0 -3.81 0)
				(effects
					(font
						(size 1.27 1.27)
					)
				)
			)
			(property "Footprint" ""
				(at 0 0 0)
				(effects
					(font
						(size 1.27 1.27)
					)
					(hide yes)
				)
			)
			(property "Datasheet" ""
				(at 0 0 0)
				(effects
					(font
						(size 1.27 1.27)
					)
					(hide yes)
				)
			)
			(property "Description" ""
				(at 0 0 0)
				(effects
					(font
						(size 1.27 1.27)
					)
					(hide yes)
				)
			)
			(symbol "GND_91_0_1"
				(polyline
					(pts
						(xy 0 0) (xy 0 -1.27) (xy 1.27 -1.27) (xy 0 -2.54) (xy -1.27 -1.27) (xy 0 -1.27)
					)
					(stroke
						(width 0)
						(type default)
					)
					(fill
						(type none)
					)
				)
			)
			(symbol "GND_91_1_1"
				(pin power_in line
					(at 0 0 270)
					(length 0)
					(hide yes)
					(name "GND"
						(effects
							(font
								(size 1.27 1.27)
							)
						)
					)
					(number "1"
						(effects
							(font
								(size 1.27 1.27)
							)
						)
					)
				)
			)
		)
	(symbol "data-center-rdimm-ddr5-tester:GND_92"
			(power)
			(pin_names
				(offset 0)
			)
			(exclude_from_sim no)
			(in_bom yes)
			(on_board yes)
			(property "Reference" "#PWR"
				(at 0 -6.35 0)
				(effects
					(font
						(size 1.27 1.27)
					)
					(hide yes)
				)
			)
			(property "Value" "GND_92"
				(at 0 -3.81 0)
				(effects
					(font
						(size 1.27 1.27)
					)
				)
			)
			(property "Footprint" ""
				(at 0 0 0)
				(effects
					(font
						(size 1.27 1.27)
					)
					(hide yes)
				)
			)
			(property "Datasheet" ""
				(at 0 0 0)
				(effects
					(font
						(size 1.27 1.27)
					)
					(hide yes)
				)
			)
			(property "Description" ""
				(at 0 0 0)
				(effects
					(font
						(size 1.27 1.27)
					)
					(hide yes)
				)
			)
			(symbol "GND_92_0_1"
				(polyline
					(pts
						(xy 0 0) (xy 0 -1.27) (xy 1.27 -1.27) (xy 0 -2.54) (xy -1.27 -1.27) (xy 0 -1.27)
					)
					(stroke
						(width 0)
						(type default)
					)
					(fill
						(type none)
					)
				)
			)
			(symbol "GND_92_1_1"
				(pin power_in line
					(at 0 0 270)
					(length 0)
					(hide yes)
					(name "GND"
						(effects
							(font
								(size 1.27 1.27)
							)
						)
					)
					(number "1"
						(effects
							(font
								(size 1.27 1.27)
							)
						)
					)
				)
			)
		)
	(symbol "data-center-rdimm-ddr5-tester:GND_93"
			(power)
			(pin_names
				(offset 0)
			)
			(exclude_from_sim no)
			(in_bom yes)
			(on_board yes)
			(property "Reference" "#PWR"
				(at 0 -6.35 0)
				(effects
					(font
						(size 1.27 1.27)
					)
					(hide yes)
				)
			)
			(property "Value" "GND_93"
				(at 0 -3.81 0)
				(effects
					(font
						(size 1.27 1.27)
					)
				)
			)
			(property "Footprint" ""
				(at 0 0 0)
				(effects
					(font
						(size 1.27 1.27)
					)
					(hide yes)
				)
			)
			(property "Datasheet" ""
				(at 0 0 0)
				(effects
					(font
						(size 1.27 1.27)
					)
					(hide yes)
				)
			)
			(property "Description" ""
				(at 0 0 0)
				(effects
					(font
						(size 1.27 1.27)
					)
					(hide yes)
				)
			)
			(symbol "GND_93_0_1"
				(polyline
					(pts
						(xy 0 0) (xy 0 -1.27) (xy 1.27 -1.27) (xy 0 -2.54) (xy -1.27 -1.27) (xy 0 -1.27)
					)
					(stroke
						(width 0)
						(type default)
					)
					(fill
						(type none)
					)
				)
			)
			(symbol "GND_93_1_1"
				(pin power_in line
					(at 0 0 270)
					(length 0)
					(hide yes)
					(name "GND"
						(effects
							(font
								(size 1.27 1.27)
							)
						)
					)
					(number "1"
						(effects
							(font
								(size 1.27 1.27)
							)
						)
					)
				)
			)
		)
	(symbol "data-center-rdimm-ddr5-tester:GND_94"
			(power)
			(pin_names
				(offset 0)
			)
			(exclude_from_sim no)
			(in_bom yes)
			(on_board yes)
			(property "Reference" "#PWR"
				(at 0 -6.35 0)
				(effects
					(font
						(size 1.27 1.27)
					)
					(hide yes)
				)
			)
			(property "Value" "GND_94"
				(at 0 -3.81 0)
				(effects
					(font
						(size 1.27 1.27)
					)
				)
			)
			(property "Footprint" ""
				(at 0 0 0)
				(effects
					(font
						(size 1.27 1.27)
					)
					(hide yes)
				)
			)
			(property "Datasheet" ""
				(at 0 0 0)
				(effects
					(font
						(size 1.27 1.27)
					)
					(hide yes)
				)
			)
			(property "Description" ""
				(at 0 0 0)
				(effects
					(font
						(size 1.27 1.27)
					)
					(hide yes)
				)
			)
			(symbol "GND_94_0_1"
				(polyline
					(pts
						(xy 0 0) (xy 0 -1.27) (xy 1.27 -1.27) (xy 0 -2.54) (xy -1.27 -1.27) (xy 0 -1.27)
					)
					(stroke
						(width 0)
						(type default)
					)
					(fill
						(type none)
					)
				)
			)
			(symbol "GND_94_1_1"
				(pin power_in line
					(at 0 0 270)
					(length 0)
					(hide yes)
					(name "GND"
						(effects
							(font
								(size 1.27 1.27)
							)
						)
					)
					(number "1"
						(effects
							(font
								(size 1.27 1.27)
							)
						)
					)
				)
			)
		)
	(symbol "data-center-rdimm-ddr5-tester:GND_95"
			(power)
			(pin_names
				(offset 0)
			)
			(exclude_from_sim no)
			(in_bom yes)
			(on_board yes)
			(property "Reference" "#PWR"
				(at 0 -6.35 0)
				(effects
					(font
						(size 1.27 1.27)
					)
					(hide yes)
				)
			)
			(property "Value" "GND_95"
				(at 0 -3.81 0)
				(effects
					(font
						(size 1.27 1.27)
					)
				)
			)
			(property "Footprint" ""
				(at 0 0 0)
				(effects
					(font
						(size 1.27 1.27)
					)
					(hide yes)
				)
			)
			(property "Datasheet" ""
				(at 0 0 0)
				(effects
					(font
						(size 1.27 1.27)
					)
					(hide yes)
				)
			)
			(property "Description" ""
				(at 0 0 0)
				(effects
					(font
						(size 1.27 1.27)
					)
					(hide yes)
				)
			)
			(symbol "GND_95_0_1"
				(polyline
					(pts
						(xy 0 0) (xy 0 -1.27) (xy 1.27 -1.27) (xy 0 -2.54) (xy -1.27 -1.27) (xy 0 -1.27)
					)
					(stroke
						(width 0)
						(type default)
					)
					(fill
						(type none)
					)
				)
			)
			(symbol "GND_95_1_1"
				(pin power_in line
					(at 0 0 270)
					(length 0)
					(hide yes)
					(name "GND"
						(effects
							(font
								(size 1.27 1.27)
							)
						)
					)
					(number "1"
						(effects
							(font
								(size 1.27 1.27)
							)
						)
					)
				)
			)
		)
	(symbol "data-center-rdimm-ddr5-tester:GND_96"
			(power)
			(pin_names
				(offset 0)
			)
			(exclude_from_sim no)
			(in_bom yes)
			(on_board yes)
			(property "Reference" "#PWR"
				(at 0 -6.35 0)
				(effects
					(font
						(size 1.27 1.27)
					)
					(hide yes)
				)
			)
			(property "Value" "GND_96"
				(at 0 -3.81 0)
				(effects
					(font
						(size 1.27 1.27)
					)
				)
			)
			(property "Footprint" ""
				(at 0 0 0)
				(effects
					(font
						(size 1.27 1.27)
					)
					(hide yes)
				)
			)
			(property "Datasheet" ""
				(at 0 0 0)
				(effects
					(font
						(size 1.27 1.27)
					)
					(hide yes)
				)
			)
			(property "Description" ""
				(at 0 0 0)
				(effects
					(font
						(size 1.27 1.27)
					)
					(hide yes)
				)
			)
			(symbol "GND_96_0_1"
				(polyline
					(pts
						(xy 0 0) (xy 0 -1.27) (xy 1.27 -1.27) (xy 0 -2.54) (xy -1.27 -1.27) (xy 0 -1.27)
					)
					(stroke
						(width 0)
						(type default)
					)
					(fill
						(type none)
					)
				)
			)
			(symbol "GND_96_1_1"
				(pin power_in line
					(at 0 0 270)
					(length 0)
					(hide yes)
					(name "GND"
						(effects
							(font
								(size 1.27 1.27)
							)
						)
					)
					(number "1"
						(effects
							(font
								(size 1.27 1.27)
							)
						)
					)
				)
			)
		)
	(symbol "data-center-rdimm-ddr5-tester:GND_97"
			(power)
			(pin_names
				(offset 0)
			)
			(exclude_from_sim no)
			(in_bom yes)
			(on_board yes)
			(property "Reference" "#PWR"
				(at 0 -6.35 0)
				(effects
					(font
						(size 1.27 1.27)
					)
					(hide yes)
				)
			)
			(property "Value" "GND_97"
				(at 0 -3.81 0)
				(effects
					(font
						(size 1.27 1.27)
					)
				)
			)
			(property "Footprint" ""
				(at 0 0 0)
				(effects
					(font
						(size 1.27 1.27)
					)
					(hide yes)
				)
			)
			(property "Datasheet" ""
				(at 0 0 0)
				(effects
					(font
						(size 1.27 1.27)
					)
					(hide yes)
				)
			)
			(property "Description" ""
				(at 0 0 0)
				(effects
					(font
						(size 1.27 1.27)
					)
					(hide yes)
				)
			)
			(symbol "GND_97_0_1"
				(polyline
					(pts
						(xy 0 0) (xy 0 -1.27) (xy 1.27 -1.27) (xy 0 -2.54) (xy -1.27 -1.27) (xy 0 -1.27)
					)
					(stroke
						(width 0)
						(type default)
					)
					(fill
						(type none)
					)
				)
			)
			(symbol "GND_97_1_1"
				(pin power_in line
					(at 0 0 270)
					(length 0)
					(hide yes)
					(name "GND"
						(effects
							(font
								(size 1.27 1.27)
							)
						)
					)
					(number "1"
						(effects
							(font
								(size 1.27 1.27)
							)
						)
					)
				)
			)
		)
	(symbol "data-center-rdimm-ddr5-tester:GND_98"
			(power)
			(pin_names
				(offset 0)
			)
			(exclude_from_sim no)
			(in_bom yes)
			(on_board yes)
			(property "Reference" "#PWR"
				(at 0 -6.35 0)
				(effects
					(font
						(size 1.27 1.27)
					)
					(hide yes)
				)
			)
			(property "Value" "GND_98"
				(at 0 -3.81 0)
				(effects
					(font
						(size 1.27 1.27)
					)
				)
			)
			(property "Footprint" ""
				(at 0 0 0)
				(effects
					(font
						(size 1.27 1.27)
					)
					(hide yes)
				)
			)
			(property "Datasheet" ""
				(at 0 0 0)
				(effects
					(font
						(size 1.27 1.27)
					)
					(hide yes)
				)
			)
			(property "Description" ""
				(at 0 0 0)
				(effects
					(font
						(size 1.27 1.27)
					)
					(hide yes)
				)
			)
			(symbol "GND_98_0_1"
				(polyline
					(pts
						(xy 0 0) (xy 0 -1.27) (xy 1.27 -1.27) (xy 0 -2.54) (xy -1.27 -1.27) (xy 0 -1.27)
					)
					(stroke
						(width 0)
						(type default)
					)
					(fill
						(type none)
					)
				)
			)
			(symbol "GND_98_1_1"
				(pin power_in line
					(at 0 0 270)
					(length 0)
					(hide yes)
					(name "GND"
						(effects
							(font
								(size 1.27 1.27)
							)
						)
					)
					(number "1"
						(effects
							(font
								(size 1.27 1.27)
							)
						)
					)
				)
			)
		)
	(symbol "data-center-rdimm-ddr5-tester:Net-Tie_2_10"
			(pin_numbers
				(hide yes)
			)
			(pin_names
				(hide yes)
			)
			(exclude_from_sim no)
			(in_bom yes)
			(on_board yes)
			(property "Reference" "TP"
				(at 21.59 0 0)
				(effects
					(font
						(size 1.27 1.27)
						(thickness 0.15)
					)
					(justify left bottom)
				)
			)
			(property "Value" "Net-Tie_2_10"
				(at 21.59 -2.54 0)
				(effects
					(font
						(size 1.27 1.27)
						(thickness 0.15)
					)
					(justify left bottom)
				)
			)
			(property "Footprint" "data-center-rdimm-ddr5-tester-footprints:NetTie-2_SMD_Pad0.127mm"
				(at 21.59 -5.08 0)
				(effects
					(font
						(size 1.27 1.27)
						(thickness 0.15)
					)
					(justify left bottom)
					(hide yes)
				)
			)
			(property "Datasheet" ""
				(at 21.59 -7.62 0)
				(effects
					(font
						(size 1.27 1.27)
						(thickness 0.15)
					)
					(justify left bottom)
					(hide yes)
				)
			)
			(property "Description" "Net tie, 2 pins"
				(at 0 0 0)
				(effects
					(font
						(size 1.27 1.27)
					)
					(hide yes)
				)
			)
			(property "MPN" ""
				(at 21.59 -8.89 0)
				(effects
					(font
						(size 1.27 1.27)
					)
					(justify left)
					(hide yes)
				)
			)
			(property "Manufacturer" ""
				(at 21.59 -11.43 0)
				(effects
					(font
						(size 1.27 1.27)
					)
					(justify left)
					(hide yes)
				)
			)
			(property "Author" "Antmicro"
				(at 21.59 -15.24 0)
				(effects
					(font
						(size 1.27 1.27)
						(thickness 0.15)
					)
					(justify left bottom)
					(hide yes)
				)
			)
			(property "License" "Apache-2.0"
				(at 21.59 -17.78 0)
				(effects
					(font
						(size 1.27 1.27)
						(thickness 0.15)
					)
					(justify left bottom)
					(hide yes)
				)
			)
			(property "ki_keywords" "net tie short"
				(at 0 0 0)
				(effects
					(font
						(size 1.27 1.27)
					)
					(hide yes)
				)
			)
			(property "ki_fp_filters" "Net*Tie*"
				(at 0 0 0)
				(effects
					(font
						(size 1.27 1.27)
					)
					(hide yes)
				)
			)
			(symbol "Net-Tie_2_10_1_1"
				(polyline
					(pts
						(xy 1.27 0) (xy 2.54 0)
					)
					(stroke
						(width 0.254)
						(type default)
					)
					(fill
						(type background)
					)
				)
				(pin passive line
					(at 0 0 0)
					(length 1.27)
					(name "1"
						(effects
							(font
								(size 1.27 1.27)
							)
						)
					)
					(number "1"
						(effects
							(font
								(size 1.27 1.27)
							)
						)
					)
				)
				(pin passive line
					(at 3.81 0 180)
					(length 1.27)
					(name "2"
						(effects
							(font
								(size 1.27 1.27)
							)
						)
					)
					(number "2"
						(effects
							(font
								(size 1.27 1.27)
							)
						)
					)
				)
			)
		)
	(symbol "data-center-rdimm-ddr5-tester:Net-Tie_2_11"
			(pin_numbers
				(hide yes)
			)
			(pin_names
				(hide yes)
			)
			(exclude_from_sim no)
			(in_bom yes)
			(on_board yes)
			(property "Reference" "TP"
				(at 21.59 0 0)
				(effects
					(font
						(size 1.27 1.27)
						(thickness 0.15)
					)
					(justify left bottom)
				)
			)
			(property "Value" "Net-Tie_2_11"
				(at 21.59 -2.54 0)
				(effects
					(font
						(size 1.27 1.27)
						(thickness 0.15)
					)
					(justify left bottom)
				)
			)
			(property "Footprint" "data-center-rdimm-ddr5-tester-footprints:NetTie-2_SMD_Pad0.127mm"
				(at 21.59 -5.08 0)
				(effects
					(font
						(size 1.27 1.27)
						(thickness 0.15)
					)
					(justify left bottom)
					(hide yes)
				)
			)
			(property "Datasheet" ""
				(at 21.59 -7.62 0)
				(effects
					(font
						(size 1.27 1.27)
						(thickness 0.15)
					)
					(justify left bottom)
					(hide yes)
				)
			)
			(property "Description" "Net tie, 2 pins"
				(at 0 0 0)
				(effects
					(font
						(size 1.27 1.27)
					)
					(hide yes)
				)
			)
			(property "MPN" ""
				(at 21.59 -8.89 0)
				(effects
					(font
						(size 1.27 1.27)
					)
					(justify left)
					(hide yes)
				)
			)
			(property "Manufacturer" ""
				(at 21.59 -11.43 0)
				(effects
					(font
						(size 1.27 1.27)
					)
					(justify left)
					(hide yes)
				)
			)
			(property "Author" "Antmicro"
				(at 21.59 -15.24 0)
				(effects
					(font
						(size 1.27 1.27)
						(thickness 0.15)
					)
					(justify left bottom)
					(hide yes)
				)
			)
			(property "License" "Apache-2.0"
				(at 21.59 -17.78 0)
				(effects
					(font
						(size 1.27 1.27)
						(thickness 0.15)
					)
					(justify left bottom)
					(hide yes)
				)
			)
			(property "ki_keywords" "net tie short"
				(at 0 0 0)
				(effects
					(font
						(size 1.27 1.27)
					)
					(hide yes)
				)
			)
			(property "ki_fp_filters" "Net*Tie*"
				(at 0 0 0)
				(effects
					(font
						(size 1.27 1.27)
					)
					(hide yes)
				)
			)
			(symbol "Net-Tie_2_11_1_1"
				(polyline
					(pts
						(xy 1.27 0) (xy 2.54 0)
					)
					(stroke
						(width 0.254)
						(type default)
					)
					(fill
						(type background)
					)
				)
				(pin passive line
					(at 0 0 0)
					(length 1.27)
					(name "1"
						(effects
							(font
								(size 1.27 1.27)
							)
						)
					)
					(number "1"
						(effects
							(font
								(size 1.27 1.27)
							)
						)
					)
				)
				(pin passive line
					(at 3.81 0 180)
					(length 1.27)
					(name "2"
						(effects
							(font
								(size 1.27 1.27)
							)
						)
					)
					(number "2"
						(effects
							(font
								(size 1.27 1.27)
							)
						)
					)
				)
			)
		)
	(symbol "data-center-rdimm-ddr5-tester:Net-Tie_2_12"
			(pin_numbers
				(hide yes)
			)
			(pin_names
				(hide yes)
			)
			(exclude_from_sim no)
			(in_bom yes)
			(on_board yes)
			(property "Reference" "TP"
				(at 21.59 0 0)
				(effects
					(font
						(size 1.27 1.27)
						(thickness 0.15)
					)
					(justify left bottom)
				)
			)
			(property "Value" "Net-Tie_2_12"
				(at 21.59 -2.54 0)
				(effects
					(font
						(size 1.27 1.27)
						(thickness 0.15)
					)
					(justify left bottom)
				)
			)
			(property "Footprint" "data-center-rdimm-ddr5-tester-footprints:NetTie-2_SMD_Pad0.127mm"
				(at 21.59 -5.08 0)
				(effects
					(font
						(size 1.27 1.27)
						(thickness 0.15)
					)
					(justify left bottom)
					(hide yes)
				)
			)
			(property "Datasheet" ""
				(at 21.59 -7.62 0)
				(effects
					(font
						(size 1.27 1.27)
						(thickness 0.15)
					)
					(justify left bottom)
					(hide yes)
				)
			)
			(property "Description" "Net tie, 2 pins"
				(at 0 0 0)
				(effects
					(font
						(size 1.27 1.27)
					)
					(hide yes)
				)
			)
			(property "MPN" ""
				(at 21.59 -8.89 0)
				(effects
					(font
						(size 1.27 1.27)
					)
					(justify left)
					(hide yes)
				)
			)
			(property "Manufacturer" ""
				(at 21.59 -11.43 0)
				(effects
					(font
						(size 1.27 1.27)
					)
					(justify left)
					(hide yes)
				)
			)
			(property "Author" "Antmicro"
				(at 21.59 -15.24 0)
				(effects
					(font
						(size 1.27 1.27)
						(thickness 0.15)
					)
					(justify left bottom)
					(hide yes)
				)
			)
			(property "License" "Apache-2.0"
				(at 21.59 -17.78 0)
				(effects
					(font
						(size 1.27 1.27)
						(thickness 0.15)
					)
					(justify left bottom)
					(hide yes)
				)
			)
			(property "ki_keywords" "net tie short"
				(at 0 0 0)
				(effects
					(font
						(size 1.27 1.27)
					)
					(hide yes)
				)
			)
			(property "ki_fp_filters" "Net*Tie*"
				(at 0 0 0)
				(effects
					(font
						(size 1.27 1.27)
					)
					(hide yes)
				)
			)
			(symbol "Net-Tie_2_12_1_1"
				(polyline
					(pts
						(xy 1.27 0) (xy 2.54 0)
					)
					(stroke
						(width 0.254)
						(type default)
					)
					(fill
						(type background)
					)
				)
				(pin passive line
					(at 0 0 0)
					(length 1.27)
					(name "1"
						(effects
							(font
								(size 1.27 1.27)
							)
						)
					)
					(number "1"
						(effects
							(font
								(size 1.27 1.27)
							)
						)
					)
				)
				(pin passive line
					(at 3.81 0 180)
					(length 1.27)
					(name "2"
						(effects
							(font
								(size 1.27 1.27)
							)
						)
					)
					(number "2"
						(effects
							(font
								(size 1.27 1.27)
							)
						)
					)
				)
			)
		)
	(symbol "data-center-rdimm-ddr5-tester:Net-Tie_2_13"
			(pin_numbers
				(hide yes)
			)
			(pin_names
				(hide yes)
			)
			(exclude_from_sim no)
			(in_bom yes)
			(on_board yes)
			(property "Reference" "TP"
				(at 21.59 0 0)
				(effects
					(font
						(size 1.27 1.27)
						(thickness 0.15)
					)
					(justify left bottom)
				)
			)
			(property "Value" "Net-Tie_2_13"
				(at 21.59 -2.54 0)
				(effects
					(font
						(size 1.27 1.27)
						(thickness 0.15)
					)
					(justify left bottom)
				)
			)
			(property "Footprint" "data-center-rdimm-ddr5-tester-footprints:NetTie-2_SMD_Pad0.127mm"
				(at 21.59 -5.08 0)
				(effects
					(font
						(size 1.27 1.27)
						(thickness 0.15)
					)
					(justify left bottom)
					(hide yes)
				)
			)
			(property "Datasheet" ""
				(at 21.59 -7.62 0)
				(effects
					(font
						(size 1.27 1.27)
						(thickness 0.15)
					)
					(justify left bottom)
					(hide yes)
				)
			)
			(property "Description" "Net tie, 2 pins"
				(at 0 0 0)
				(effects
					(font
						(size 1.27 1.27)
					)
					(hide yes)
				)
			)
			(property "MPN" ""
				(at 21.59 -8.89 0)
				(effects
					(font
						(size 1.27 1.27)
					)
					(justify left)
					(hide yes)
				)
			)
			(property "Manufacturer" ""
				(at 21.59 -11.43 0)
				(effects
					(font
						(size 1.27 1.27)
					)
					(justify left)
					(hide yes)
				)
			)
			(property "Author" "Antmicro"
				(at 21.59 -15.24 0)
				(effects
					(font
						(size 1.27 1.27)
						(thickness 0.15)
					)
					(justify left bottom)
					(hide yes)
				)
			)
			(property "License" "Apache-2.0"
				(at 21.59 -17.78 0)
				(effects
					(font
						(size 1.27 1.27)
						(thickness 0.15)
					)
					(justify left bottom)
					(hide yes)
				)
			)
			(property "ki_keywords" "net tie short"
				(at 0 0 0)
				(effects
					(font
						(size 1.27 1.27)
					)
					(hide yes)
				)
			)
			(property "ki_fp_filters" "Net*Tie*"
				(at 0 0 0)
				(effects
					(font
						(size 1.27 1.27)
					)
					(hide yes)
				)
			)
			(symbol "Net-Tie_2_13_1_1"
				(polyline
					(pts
						(xy 1.27 0) (xy 2.54 0)
					)
					(stroke
						(width 0.254)
						(type default)
					)
					(fill
						(type background)
					)
				)
				(pin passive line
					(at 0 0 0)
					(length 1.27)
					(name "1"
						(effects
							(font
								(size 1.27 1.27)
							)
						)
					)
					(number "1"
						(effects
							(font
								(size 1.27 1.27)
							)
						)
					)
				)
				(pin passive line
					(at 3.81 0 180)
					(length 1.27)
					(name "2"
						(effects
							(font
								(size 1.27 1.27)
							)
						)
					)
					(number "2"
						(effects
							(font
								(size 1.27 1.27)
							)
						)
					)
				)
			)
		)
	(symbol "data-center-rdimm-ddr5-tester:Net-Tie_2_14"
			(pin_numbers
				(hide yes)
			)
			(pin_names
				(hide yes)
			)
			(exclude_from_sim no)
			(in_bom yes)
			(on_board yes)
			(property "Reference" "TP"
				(at 21.59 0 0)
				(effects
					(font
						(size 1.27 1.27)
						(thickness 0.15)
					)
					(justify left bottom)
				)
			)
			(property "Value" "Net-Tie_2_14"
				(at 21.59 -2.54 0)
				(effects
					(font
						(size 1.27 1.27)
						(thickness 0.15)
					)
					(justify left bottom)
				)
			)
			(property "Footprint" "data-center-rdimm-ddr5-tester-footprints:NetTie-2_SMD_Pad0.127mm"
				(at 21.59 -5.08 0)
				(effects
					(font
						(size 1.27 1.27)
						(thickness 0.15)
					)
					(justify left bottom)
					(hide yes)
				)
			)
			(property "Datasheet" ""
				(at 21.59 -7.62 0)
				(effects
					(font
						(size 1.27 1.27)
						(thickness 0.15)
					)
					(justify left bottom)
					(hide yes)
				)
			)
			(property "Description" "Net tie, 2 pins"
				(at 0 0 0)
				(effects
					(font
						(size 1.27 1.27)
					)
					(hide yes)
				)
			)
			(property "MPN" ""
				(at 21.59 -8.89 0)
				(effects
					(font
						(size 1.27 1.27)
					)
					(justify left)
					(hide yes)
				)
			)
			(property "Manufacturer" ""
				(at 21.59 -11.43 0)
				(effects
					(font
						(size 1.27 1.27)
					)
					(justify left)
					(hide yes)
				)
			)
			(property "Author" "Antmicro"
				(at 21.59 -15.24 0)
				(effects
					(font
						(size 1.27 1.27)
						(thickness 0.15)
					)
					(justify left bottom)
					(hide yes)
				)
			)
			(property "License" "Apache-2.0"
				(at 21.59 -17.78 0)
				(effects
					(font
						(size 1.27 1.27)
						(thickness 0.15)
					)
					(justify left bottom)
					(hide yes)
				)
			)
			(property "ki_keywords" "net tie short"
				(at 0 0 0)
				(effects
					(font
						(size 1.27 1.27)
					)
					(hide yes)
				)
			)
			(property "ki_fp_filters" "Net*Tie*"
				(at 0 0 0)
				(effects
					(font
						(size 1.27 1.27)
					)
					(hide yes)
				)
			)
			(symbol "Net-Tie_2_14_1_1"
				(polyline
					(pts
						(xy 1.27 0) (xy 2.54 0)
					)
					(stroke
						(width 0.254)
						(type default)
					)
					(fill
						(type background)
					)
				)
				(pin passive line
					(at 0 0 0)
					(length 1.27)
					(name "1"
						(effects
							(font
								(size 1.27 1.27)
							)
						)
					)
					(number "1"
						(effects
							(font
								(size 1.27 1.27)
							)
						)
					)
				)
				(pin passive line
					(at 3.81 0 180)
					(length 1.27)
					(name "2"
						(effects
							(font
								(size 1.27 1.27)
							)
						)
					)
					(number "2"
						(effects
							(font
								(size 1.27 1.27)
							)
						)
					)
				)
			)
		)
	(symbol "data-center-rdimm-ddr5-tester:Net-Tie_2_15"
			(pin_numbers
				(hide yes)
			)
			(pin_names
				(hide yes)
			)
			(exclude_from_sim no)
			(in_bom yes)
			(on_board yes)
			(property "Reference" "TP"
				(at 21.59 0 0)
				(effects
					(font
						(size 1.27 1.27)
						(thickness 0.15)
					)
					(justify left bottom)
				)
			)
			(property "Value" "Net-Tie_2_15"
				(at 21.59 -2.54 0)
				(effects
					(font
						(size 1.27 1.27)
						(thickness 0.15)
					)
					(justify left bottom)
				)
			)
			(property "Footprint" "data-center-rdimm-ddr5-tester-footprints:NetTie-2_SMD_Pad0.127mm"
				(at 21.59 -5.08 0)
				(effects
					(font
						(size 1.27 1.27)
						(thickness 0.15)
					)
					(justify left bottom)
					(hide yes)
				)
			)
			(property "Datasheet" ""
				(at 21.59 -7.62 0)
				(effects
					(font
						(size 1.27 1.27)
						(thickness 0.15)
					)
					(justify left bottom)
					(hide yes)
				)
			)
			(property "Description" "Net tie, 2 pins"
				(at 0 0 0)
				(effects
					(font
						(size 1.27 1.27)
					)
					(hide yes)
				)
			)
			(property "MPN" ""
				(at 21.59 -8.89 0)
				(effects
					(font
						(size 1.27 1.27)
					)
					(justify left)
					(hide yes)
				)
			)
			(property "Manufacturer" ""
				(at 21.59 -11.43 0)
				(effects
					(font
						(size 1.27 1.27)
					)
					(justify left)
					(hide yes)
				)
			)
			(property "Author" "Antmicro"
				(at 21.59 -15.24 0)
				(effects
					(font
						(size 1.27 1.27)
						(thickness 0.15)
					)
					(justify left bottom)
					(hide yes)
				)
			)
			(property "License" "Apache-2.0"
				(at 21.59 -17.78 0)
				(effects
					(font
						(size 1.27 1.27)
						(thickness 0.15)
					)
					(justify left bottom)
					(hide yes)
				)
			)
			(property "ki_keywords" "net tie short"
				(at 0 0 0)
				(effects
					(font
						(size 1.27 1.27)
					)
					(hide yes)
				)
			)
			(property "ki_fp_filters" "Net*Tie*"
				(at 0 0 0)
				(effects
					(font
						(size 1.27 1.27)
					)
					(hide yes)
				)
			)
			(symbol "Net-Tie_2_15_1_1"
				(polyline
					(pts
						(xy 1.27 0) (xy 2.54 0)
					)
					(stroke
						(width 0.254)
						(type default)
					)
					(fill
						(type background)
					)
				)
				(pin passive line
					(at 0 0 0)
					(length 1.27)
					(name "1"
						(effects
							(font
								(size 1.27 1.27)
							)
						)
					)
					(number "1"
						(effects
							(font
								(size 1.27 1.27)
							)
						)
					)
				)
				(pin passive line
					(at 3.81 0 180)
					(length 1.27)
					(name "2"
						(effects
							(font
								(size 1.27 1.27)
							)
						)
					)
					(number "2"
						(effects
							(font
								(size 1.27 1.27)
							)
						)
					)
				)
			)
		)
	(symbol "data-center-rdimm-ddr5-tester:TP_1mm_SMD_10"
			(pin_numbers
				(hide yes)
			)
			(pin_names
				(hide yes)
			)
			(exclude_from_sim no)
			(in_bom yes)
			(on_board yes)
			(property "Reference" "TP"
				(at 15.24 -5.08 0)
				(effects
					(font
						(size 1.27 1.27)
						(thickness 0.15)
					)
					(justify left bottom)
				)
			)
			(property "Value" "TP_1mm_SMD_10"
				(at 15.24 -7.62 0)
				(effects
					(font
						(size 1.27 1.27)
						(thickness 0.15)
					)
					(justify left bottom)
					(hide yes)
				)
			)
			(property "Footprint" "data-center-rdimm-ddr5-tester-footprints:Testpoint_smd_1mm"
				(at 15.24 -10.16 0)
				(effects
					(font
						(size 1.27 1.27)
						(thickness 0.15)
					)
					(justify left bottom)
					(hide yes)
				)
			)
			(property "Datasheet" ""
				(at 15.24 -12.7 0)
				(effects
					(font
						(size 1.27 1.27)
						(thickness 0.15)
					)
					(justify left bottom)
					(hide yes)
				)
			)
			(property "Description" "Test Point 1mm"
				(at 0 0 0)
				(effects
					(font
						(size 1.27 1.27)
					)
					(hide yes)
				)
			)
			(property "MPN" ""
				(at 0 0 0)
				(effects
					(font
						(size 1.27 1.27)
					)
					(hide yes)
				)
			)
			(property "Manufacturer" ""
				(at 0 0 0)
				(effects
					(font
						(size 1.27 1.27)
					)
					(hide yes)
				)
			)
			(property "Author" "Antmicro"
				(at 15.24 -15.24 0)
				(effects
					(font
						(size 1.27 1.27)
						(thickness 0.15)
					)
					(justify left bottom)
					(hide yes)
				)
			)
			(property "License" "Apache-2.0"
				(at 15.24 -17.78 0)
				(effects
					(font
						(size 1.27 1.27)
						(thickness 0.15)
					)
					(justify left bottom)
					(hide yes)
				)
			)
			(symbol "TP_1mm_SMD_10_1_1"
				(circle
					(center 3.175 0)
					(radius 0.635)
					(stroke
						(width 0.254)
						(type default)
					)
					(fill
						(type none)
					)
				)
				(pin passive line
					(at 0 0 0)
					(length 2.54)
					(name "1"
						(effects
							(font
								(size 1.27 1.27)
							)
						)
					)
					(number "1"
						(effects
							(font
								(size 1.27 1.27)
							)
						)
					)
				)
			)
		)
	(symbol "data-center-rdimm-ddr5-tester:TP_1mm_SMD_11"
			(pin_numbers
				(hide yes)
			)
			(pin_names
				(hide yes)
			)
			(exclude_from_sim no)
			(in_bom yes)
			(on_board yes)
			(property "Reference" "TP"
				(at 15.24 -5.08 0)
				(effects
					(font
						(size 1.27 1.27)
						(thickness 0.15)
					)
					(justify left bottom)
				)
			)
			(property "Value" "TP_1mm_SMD_11"
				(at 15.24 -7.62 0)
				(effects
					(font
						(size 1.27 1.27)
						(thickness 0.15)
					)
					(justify left bottom)
					(hide yes)
				)
			)
			(property "Footprint" "data-center-rdimm-ddr5-tester-footprints:Testpoint_smd_1mm"
				(at 15.24 -10.16 0)
				(effects
					(font
						(size 1.27 1.27)
						(thickness 0.15)
					)
					(justify left bottom)
					(hide yes)
				)
			)
			(property "Datasheet" ""
				(at 15.24 -12.7 0)
				(effects
					(font
						(size 1.27 1.27)
						(thickness 0.15)
					)
					(justify left bottom)
					(hide yes)
				)
			)
			(property "Description" "Test Point 1mm"
				(at 0 0 0)
				(effects
					(font
						(size 1.27 1.27)
					)
					(hide yes)
				)
			)
			(property "MPN" ""
				(at 0 0 0)
				(effects
					(font
						(size 1.27 1.27)
					)
					(hide yes)
				)
			)
			(property "Manufacturer" ""
				(at 0 0 0)
				(effects
					(font
						(size 1.27 1.27)
					)
					(hide yes)
				)
			)
			(property "Author" "Antmicro"
				(at 15.24 -15.24 0)
				(effects
					(font
						(size 1.27 1.27)
						(thickness 0.15)
					)
					(justify left bottom)
					(hide yes)
				)
			)
			(property "License" "Apache-2.0"
				(at 15.24 -17.78 0)
				(effects
					(font
						(size 1.27 1.27)
						(thickness 0.15)
					)
					(justify left bottom)
					(hide yes)
				)
			)
			(symbol "TP_1mm_SMD_11_1_1"
				(circle
					(center 3.175 0)
					(radius 0.635)
					(stroke
						(width 0.254)
						(type default)
					)
					(fill
						(type none)
					)
				)
				(pin passive line
					(at 0 0 0)
					(length 2.54)
					(name "1"
						(effects
							(font
								(size 1.27 1.27)
							)
						)
					)
					(number "1"
						(effects
							(font
								(size 1.27 1.27)
							)
						)
					)
				)
			)
		)
	(symbol "data-center-rdimm-ddr5-tester:TP_1mm_SMD_12"
			(pin_numbers
				(hide yes)
			)
			(pin_names
				(hide yes)
			)
			(exclude_from_sim no)
			(in_bom yes)
			(on_board yes)
			(property "Reference" "TP"
				(at 15.24 -5.08 0)
				(effects
					(font
						(size 1.27 1.27)
						(thickness 0.15)
					)
					(justify left bottom)
				)
			)
			(property "Value" "TP_1mm_SMD_12"
				(at 15.24 -7.62 0)
				(effects
					(font
						(size 1.27 1.27)
						(thickness 0.15)
					)
					(justify left bottom)
					(hide yes)
				)
			)
			(property "Footprint" "data-center-rdimm-ddr5-tester-footprints:Testpoint_smd_1mm"
				(at 15.24 -10.16 0)
				(effects
					(font
						(size 1.27 1.27)
						(thickness 0.15)
					)
					(justify left bottom)
					(hide yes)
				)
			)
			(property "Datasheet" ""
				(at 15.24 -12.7 0)
				(effects
					(font
						(size 1.27 1.27)
						(thickness 0.15)
					)
					(justify left bottom)
					(hide yes)
				)
			)
			(property "Description" "Test Point 1mm"
				(at 0 0 0)
				(effects
					(font
						(size 1.27 1.27)
					)
					(hide yes)
				)
			)
			(property "MPN" ""
				(at 0 0 0)
				(effects
					(font
						(size 1.27 1.27)
					)
					(hide yes)
				)
			)
			(property "Manufacturer" ""
				(at 0 0 0)
				(effects
					(font
						(size 1.27 1.27)
					)
					(hide yes)
				)
			)
			(property "Author" "Antmicro"
				(at 15.24 -15.24 0)
				(effects
					(font
						(size 1.27 1.27)
						(thickness 0.15)
					)
					(justify left bottom)
					(hide yes)
				)
			)
			(property "License" "Apache-2.0"
				(at 15.24 -17.78 0)
				(effects
					(font
						(size 1.27 1.27)
						(thickness 0.15)
					)
					(justify left bottom)
					(hide yes)
				)
			)
			(symbol "TP_1mm_SMD_12_1_1"
				(circle
					(center 3.175 0)
					(radius 0.635)
					(stroke
						(width 0.254)
						(type default)
					)
					(fill
						(type none)
					)
				)
				(pin passive line
					(at 0 0 0)
					(length 2.54)
					(name "1"
						(effects
							(font
								(size 1.27 1.27)
							)
						)
					)
					(number "1"
						(effects
							(font
								(size 1.27 1.27)
							)
						)
					)
				)
			)
		)
	(symbol "data-center-rdimm-ddr5-tester:TP_1mm_SMD_13"
			(pin_numbers
				(hide yes)
			)
			(pin_names
				(hide yes)
			)
			(exclude_from_sim no)
			(in_bom yes)
			(on_board yes)
			(property "Reference" "TP"
				(at 15.24 -5.08 0)
				(effects
					(font
						(size 1.27 1.27)
						(thickness 0.15)
					)
					(justify left bottom)
				)
			)
			(property "Value" "TP_1mm_SMD_13"
				(at 15.24 -7.62 0)
				(effects
					(font
						(size 1.27 1.27)
						(thickness 0.15)
					)
					(justify left bottom)
					(hide yes)
				)
			)
			(property "Footprint" "data-center-rdimm-ddr5-tester-footprints:Testpoint_smd_1mm"
				(at 15.24 -10.16 0)
				(effects
					(font
						(size 1.27 1.27)
						(thickness 0.15)
					)
					(justify left bottom)
					(hide yes)
				)
			)
			(property "Datasheet" ""
				(at 15.24 -12.7 0)
				(effects
					(font
						(size 1.27 1.27)
						(thickness 0.15)
					)
					(justify left bottom)
					(hide yes)
				)
			)
			(property "Description" "Test Point 1mm"
				(at 0 0 0)
				(effects
					(font
						(size 1.27 1.27)
					)
					(hide yes)
				)
			)
			(property "MPN" ""
				(at 0 0 0)
				(effects
					(font
						(size 1.27 1.27)
					)
					(hide yes)
				)
			)
			(property "Manufacturer" ""
				(at 0 0 0)
				(effects
					(font
						(size 1.27 1.27)
					)
					(hide yes)
				)
			)
			(property "Author" "Antmicro"
				(at 15.24 -15.24 0)
				(effects
					(font
						(size 1.27 1.27)
						(thickness 0.15)
					)
					(justify left bottom)
					(hide yes)
				)
			)
			(property "License" "Apache-2.0"
				(at 15.24 -17.78 0)
				(effects
					(font
						(size 1.27 1.27)
						(thickness 0.15)
					)
					(justify left bottom)
					(hide yes)
				)
			)
			(symbol "TP_1mm_SMD_13_1_1"
				(circle
					(center 3.175 0)
					(radius 0.635)
					(stroke
						(width 0.254)
						(type default)
					)
					(fill
						(type none)
					)
				)
				(pin passive line
					(at 0 0 0)
					(length 2.54)
					(name "1"
						(effects
							(font
								(size 1.27 1.27)
							)
						)
					)
					(number "1"
						(effects
							(font
								(size 1.27 1.27)
							)
						)
					)
				)
			)
		)
	(symbol "data-center-rdimm-ddr5-tester:TP_1mm_SMD_14"
			(pin_numbers
				(hide yes)
			)
			(pin_names
				(hide yes)
			)
			(exclude_from_sim no)
			(in_bom yes)
			(on_board yes)
			(property "Reference" "TP"
				(at 15.24 -5.08 0)
				(effects
					(font
						(size 1.27 1.27)
						(thickness 0.15)
					)
					(justify left bottom)
				)
			)
			(property "Value" "TP_1mm_SMD_14"
				(at 15.24 -7.62 0)
				(effects
					(font
						(size 1.27 1.27)
						(thickness 0.15)
					)
					(justify left bottom)
					(hide yes)
				)
			)
			(property "Footprint" "data-center-rdimm-ddr5-tester-footprints:Testpoint_smd_1mm"
				(at 15.24 -10.16 0)
				(effects
					(font
						(size 1.27 1.27)
						(thickness 0.15)
					)
					(justify left bottom)
					(hide yes)
				)
			)
			(property "Datasheet" ""
				(at 15.24 -12.7 0)
				(effects
					(font
						(size 1.27 1.27)
						(thickness 0.15)
					)
					(justify left bottom)
					(hide yes)
				)
			)
			(property "Description" "Test Point 1mm"
				(at 0 0 0)
				(effects
					(font
						(size 1.27 1.27)
					)
					(hide yes)
				)
			)
			(property "MPN" ""
				(at 0 0 0)
				(effects
					(font
						(size 1.27 1.27)
					)
					(hide yes)
				)
			)
			(property "Manufacturer" ""
				(at 0 0 0)
				(effects
					(font
						(size 1.27 1.27)
					)
					(hide yes)
				)
			)
			(property "Author" "Antmicro"
				(at 15.24 -15.24 0)
				(effects
					(font
						(size 1.27 1.27)
						(thickness 0.15)
					)
					(justify left bottom)
					(hide yes)
				)
			)
			(property "License" "Apache-2.0"
				(at 15.24 -17.78 0)
				(effects
					(font
						(size 1.27 1.27)
						(thickness 0.15)
					)
					(justify left bottom)
					(hide yes)
				)
			)
			(symbol "TP_1mm_SMD_14_1_1"
				(circle
					(center 3.175 0)
					(radius 0.635)
					(stroke
						(width 0.254)
						(type default)
					)
					(fill
						(type none)
					)
				)
				(pin passive line
					(at 0 0 0)
					(length 2.54)
					(name "1"
						(effects
							(font
								(size 1.27 1.27)
							)
						)
					)
					(number "1"
						(effects
							(font
								(size 1.27 1.27)
							)
						)
					)
				)
			)
		)
)
